5
5
4
4
3
3
2
2
1
1
D D
C C
B B
A A
Expander BD SWB
COVER_PAGE
PROJECT NAME: Grand TetonPCB SIZE: 467.6*418.59 (mm)PCB REV: FPCB LAYER: 18LAST UPDATE: 2022/12/12
SizeDoc NumberRevDate: SheetofReviewerDesignerDepartmentProject
Page TitleCCBU D1 257Tuesday, August 29, 2023<project_name><Designer> GRANDTETON_SWB_20230829001 COVER_PAGE<Reviewer>SizeDoc NumberRevDate: SheetofReviewerDesignerDepartmentProject
Page TitleCCBU D1 257Tuesday, August 29, 2023<project_name><Designer> GRANDTETON_SWB_20230829001 COVER_PAGE<Reviewer>SizeDoc NumberRevDate: SheetofReviewerDesignerDepartmentProject
Page TitleCCBU D1 257Tuesday, August 29, 2023<project_name><Designer> GRANDTETON_SWB_20230829001 COVER_PAGE<Reviewer>



5
5
4
4
3
3
2
2
1
1
D D
C C
B B
A A
001 COVER_PAGE002 TABLE OF CONTENT(1/2)003 TABLE OF CONTENT(2/2)004 SYSTEM DIAGRAM005 POWER SEQUENCE006 CLOCK DIAGRAM007 I2C Topology008 USB TOPOLOGY009 JTAG Diagram010 PEX_0_STN_01(1/11)011 PEX_0_STN_23(2/11)012 PEX_0_STN_45(3/11)013 PEX_0_STN_67(4/11)014 PEX_0_STN_8(5/11)015 PEX_0_GPIO(6/11)016 PEX_0_FLASH(7/11)017 PEX_0_PWR Cap_1(8/11)018 PEX_0_PWR Cap_2(9/11)019 PEX_0_PWR Cap_3(10/11)020 PEX_0_GND(11/11)021 PEX_0_PWR_FILTER022 BLANK023 PEX_1_STN_01(1/11)024 PEX_1_STN_23(2/11)025 PEX_1_STN_45(3/11)026 PEX_1_STN_67(4/11)027 PEX_1_STN_8(5/11)028 PEX_1_GPIO(6/11)029 PEX_1_FLASH(7/11)030 PEX_1_PWR_Cap_1(8/11)031 PEX_1_PWR_Cap_2(9/11)032 PEX_1_PWR_Cap_3(10/11)033 PEX_1_GND(11/11)034 PEX_1_PWR_FILTER035 BLANK036 PEX_2_STN_01(1/11)037 PEX_2_STN_23(2/11)038 PEX_2_STN_45(3/11)039 PEX_2_STN_67(4/11)040 PEX_2_STN_8(5/11)041 PEX_2_GPIO(6/11)042 PEX_2_FLASH(7/11)043 PEX_2_PWR_Cap_1(8/11)044 PEX_2_PWR_Cap_2(9/11)045 PEX_2_PWR_Cap_3(10/11)046 PEX_2_GND(11/11)047 PEX_2_PWR_FILTER048 BLANK049 PEX_3_STN_01(1/11)050 PEX_3_STN_23(2/11)
051 PEX_3_STN_45(3/11)052 PEX_3_STN_67(4/11)053 PEX_3_STN_8(5/11)054 PEX_3_GPIO(6/11)055 PEX_3_FLASH(7/11)056 PEX_3_PWR_Cap_1(8/11)057 PEX_3_PWR_Cap_2(9/11)058 PEX_3_PWR_Cap_3(10/11)059 PEX_3_GND(11/11)060 PEX_3_PWR_FILTER061 BLANK062 PEX_STRAP063 PEX_FLASH_LEVEL_SHIFTER064 PEX_SDB_DEBUG_UART065 PEX_CLI_DEBUG_UART066 BLANK067 PEX_SDB_UART_LEVEL_SHIFTER068 PEX_CLI_UART_LEVEL_SHIFTER069 BLANK070 PEX_USB_HUB071 BLANK072 PEX0_PCA9555073 PEX1_PCA9555074 PEX2_PCA9555075 PEX3_PCA9555076 USB_HUB_CoLayout_TI077 BLANK078 CLOCK_GEN_CK440079 CLOCK_BUFFER_DB2000QL080 CLOCK_BUFFER_9ZXL0851E(1/2)081 CLOCK_BUFFER_9ZXL0851E(2/2)082 CLOCK_GEN_CK440_PEX083 CLOCK_BUFFER_9ZXL0451E_S0084 CLOCK_BUFFER_9ZXL0451E_S3085 BOARD_TYPE086 BIC_1087 BIC_2088 BIC_3089 BIC_4090 BIC_SSD_LED_EN_IOEXP091 BIC_USB_HUB092 BIC_RST093 BIC_HW_STRAPS094 BIC_NIC_I2C_LEVEL_SHIFTER095 BIC_PEX_I2C_LEVEL_SHIFTER096 BIC_SSD_I2C_MUX097 BIC_MUX_ISO_SSD(1/2)098 BIC_MUX_ISO_SSD(2/2)099 BIC_SENSOR_I2C_MUX100 BIC_ADC
101 SSD_SMB_RST(1/2)102 SSD_SMB_RST(2/2)103 BLANK104 FRU_TEMP_SENSOR(1/2)105 FRU_TEMP_SENSOR(2/2)106 E1.S_SSD_ADC(1/4)107 E1.S_SSD_ADC(2/4)108 E1.S_SSD_ADC(3/4)109 E1.S_SSD_ADC(4/4)110 NIC_ADC(1/2)111 NIC_ADC(2/2)112 PEX_P1V25_ADC113 PEX_P1V8_ADC114 BLANK115 FPGA_1116 FPGA_2117 FPGA_3118 FPGA_4119 FPGA_5120 FPGA_6121 FPGA_BUFFER122 USB_TO_UART_CP2108(1/2)123 USB_TO_UART_CP2108(2/2)124 EXAMAX_10P8C_J3_GPU24(1/5)125 EXAMAX_10P8C_J3_GPU24(2/5)126 EXAMAX_10P8C_J3_GPU24(3/5)127 EXAMAX_10P8C_J3_GPU24(4/5)128 EXAMAX_10P8C_J3_GPU24(5/5)129 EXAMAX_10P8C_J11_CPU1(1/5)130 EXAMAX_10P8C_J11_CPU1(2/5)131 EXAMAX_10P8C_J11_CPU1(3/5)132 EXAMAX_10P8C_J11_CPU1(4/5)133 EXAMAX_10P8C_J11_CPU1(5/5)134 EXAMAX_10P8C_J12_CPU1(1/5)135 EXAMAX_10P8C_J12_CPU1(2/5)136 EXAMAX_10P8C_J12_CPU1(3/5)137 EXAMAX_10P8C_J12_CPU1(4/5)138 EXAMAX_10P8C_J12_CPU1(5/5)139 EXAMAX_10P8C_J5_GPU13(1/5)140 EXAMAX_10P8C_J5_GPU13(2/5)141 EXAMAX_10P8C_J5_GPU13(3/5)142 EXAMAX_10P8C_J5_GPU13(4/5)143 EXAMAX_10P8C_J5_GPU13(5/5)144 EXAMAX_10P8C_J7_GPU68(1/5)145 EXAMAX_10P8C_J7_GPU68(2/5)146 EXAMAX_10P8C_J7_GPU68(3/5)147 EXAMAX_10P8C_J7_GPU68(4/5)148 EXAMAX_10P8C_J7_GPU68(5/5)149 EXAMAX_10P8C_J13_CPU0(1/5)150 EXAMAX_10P8C_J13_CPU0(2/5)
151 EXAMAX_10P8C_J13_CPU0(3/5)152 EXAMAX_10P8C_J13_CPU0(4/5)153 EXAMAX_10P8C_J13_CPU0(5/5)154 EXAMAX_10P8C_J14_CPU0(1/5)155 EXAMAX_10P8C_J14_CPU0(2/5)156 EXAMAX_10P8C_J14_CPU0(3/5)157 EXAMAX_10P8C_J14_CPU0(4/5)158 EXAMAX_10P8C_J14_CPU0(5/5)159 EXAMAX_10P8C_J9_GPU78(1/5)160 EXAMAX_10P8C_J9_GPU78(2/5)161 EXAMAX_10P8C_J9_GPU78(3/5)162 EXAMAX_10P8C_J9_GPU78(4/5)163 EXAMAX_10P8C_J9_GPU78(5/5)164 J11_J3_BYPASS165 J12_J5_BYPASS166 J13_J7_BYPASS167 J14_J9_BYPASS168 NIC_0_J20(1/3)169 NIC_0_J20(2/3)170 NIC_0_J20(3/3)171 NIC_1_J21(1/3)172 NIC_1_J21(2/3)173 NIC_1_J21(3/3)174 NIC_2_J22(1/3)175 NIC_2_J22(2/3)176 NIC_2_J22(3/3)177 NIC_3_J23(1/3)178 NIC_3_J23(2/3)179 NIC_3_J23(3/3)180 NIC_4_J24(1/3)181 NIC_4_J24(2/3)182 NIC_4_J24(3/3)183 NIC_5_J25(1/3)184 NIC_5_J25(2/3)185 NIC_5_J25(3/3)186 NIC_6_J26(1/3)187 NIC_6_J26(2/3)188 NIC_6_J26(3/3)189 NIC_7_J27(1/3)190 NIC_7_J27(2/3)191 NIC_7_J27(3/3)192 NIC_PWRBRK_N193 BLANK
TABLE OF CONTENT(1/2) SizeDoc NumberRevDate: SheetofReviewerDesignerDepartmentProject
Page TitleCCBU D2 257Tuesday, August 29, 2023<project_name><Designer> GRANDTETON_SWB_20230829002 TABLE OF CONTENT(1/2)<Reviewer>SizeDoc NumberRevDate: SheetofReviewerDesignerDepartmentProject
Page TitleCCBU D2 257Tuesday, August 29, 2023<project_name><Designer> GRANDTETON_SWB_20230829002 TABLE OF CONTENT(1/2)<Reviewer>SizeDoc NumberRevDate: SheetofReviewerDesignerDepartmentProject
Page TitleCCBU D2 257Tuesday, August 29, 2023<project_name><Designer> GRANDTETON_SWB_20230829002 TABLE OF CONTENT(1/2)<Reviewer>



5
5
4
4
3
3
2
2
1
1
D D
C C
B B
A A
194 SSD_0/1195 SSD_2/3196 SSD_4/5197 SSD_6/7198 SSD_8/9199 SSD_10/11200 SSD_12/13201 SSD_14/15202 SSD_AUX_PWR_EN(1/2)203 SSD_AUX_PWR_EN(2/2)204 BLANK205 BLANK206 BLANK207 BLANK208 BLANK209 POWER_CONN210 HSC_OC211 SLIMSAS_CONN212 SLIMASA_DBV2213 P12V_AUX_HSC_MOSFET214 P12V_AUX_MP5990_HSC(1/3)215 P12V_AUX_MP5990_HSC(2/3)216 P12V_AUX_MP5990_HSC(3/3)217 P1V8_PEX_PLL_RT9059BGQW_1218 P1V8_PEX_PLL_RT9059BGQW_2219 BLANK
220 P5V_AUX_RT7251B221 P3V3_AUX_RS53319LR222 P1V2_AUX_RT9059223 P0V8_PEX0/1_controller(1/3)224 P0V8_PEX0_Phase(2/3)225 P0V8_PEX1_Phase(3/3)226 P0V8_PEX2/3_controller(1/3)227 P0V8_PEX2_Phase(2/3)228 P0V8_PEX3_Phase(3/3)229 P1V25_PEX0_RS53319LR230 P1V25_PEX1_RS53319LR231 P1V25_PEX2_RS53319LR232 P1V25_PEX3_RS53319LR233 P1V8_PEX_RS53318LR234 P3V3_SQ24801BDCD235 P12V_NIC_SQ24801BDCD236 P12V_SSD_SQ24801BDCD237 P12V_SSD_SQ24801BDCD238 P3V3_NIC_SQ24801BDCD239 P3V3_SSD_SQ24801BDCD240 P3V3_SSD_SQ24801BDCD241 P3V3_MP5016_Colay242 P12V_NICx_RS31312R_Colay_1243 P12V_NICx_RS31312R_Colay_2244 P12V_SSDx_MP5016_Colay_1245 P12V_SSDx_MP5016_Colay_2246 P12V_SSDx_MP5016_Colay_3247 P12V_SSDx_MP5016_Colay_4248 P3V3_NIC_MP5016_Colay_1249 P3V3_NIC_MP5016_Colay_2250 P3V3_SSD_MP5016_Colay_1251 P3V3_SSD_MP5016_Colay_2252 P3V3_SSD_MP5016_Colay_3253 P3V3_SSD_MP5016_Colay_4254 TDR255 DELTA_L256 SCREW_HOLE257 DUMMY_SYMBOL
TABLE OF CONTENT(2/2) SizeDoc NumberRevDate: SheetofReviewerDesignerDepartmentProject
Page TitleCCBU D3 257Tuesday, August 29, 2023<project_name><Designer> GRANDTETON_SWB_20230829003 TABLE OF CONTENT(2/2)<Reviewer>SizeDoc NumberRevDate: SheetofReviewerDesignerDepartmentProject
Page TitleCCBU D3 257Tuesday, August 29, 2023<project_name><Designer> GRANDTETON_SWB_20230829003 TABLE OF CONTENT(2/2)<Reviewer>SizeDoc NumberRevDate: SheetofReviewerDesignerDepartmentProject
Page TitleCCBU D3 257Tuesday, August 29, 2023<project_name><Designer> GRANDTETON_SWB_20230829003 TABLE OF CONTENT(2/2)<Reviewer>



5
5
4
4
3
3
2
2
1
1
D D
C C
B B
A A
SYSTEM DIAGRAM SizeDoc NumberRevDate: SheetofReviewerDesignerDepartmentProject
Page TitleCCBU D4 257Tuesday, August 29, 2023<project_name><Designer> GRANDTETON_SWB_20230829004 SYSTEM DIAGRAM<Reviewer>SizeDoc NumberRevDate: SheetofReviewerDesignerDepartmentProject
Page TitleCCBU D4 257Tuesday, August 29, 2023<project_name><Designer> GRANDTETON_SWB_20230829004 SYSTEM DIAGRAM<Reviewer>SizeDoc NumberRevDate: SheetofReviewerDesignerDepartmentProject
Page TitleCCBU D4 257Tuesday, August 29, 2023<project_name><Designer> GRANDTETON_SWB_20230829004 SYSTEM DIAGRAM<Reviewer>



5
5
4
4
3
3
2
2
1
1
D D
C C
B B
A A
POWER SEQUENCE SizeDoc NumberRevDate: SheetofReviewerDesignerDepartmentProject
Page TitleCCBU D5 257Tuesday, August 29, 2023<project_name><Designer> GRANDTETON_SWB_20230829005 POWER SEQUENCE<Reviewer>SizeDoc NumberRevDate: SheetofReviewerDesignerDepartmentProject
Page TitleCCBU D5 257Tuesday, August 29, 2023<project_name><Designer> GRANDTETON_SWB_20230829005 POWER SEQUENCE<Reviewer>SizeDoc NumberRevDate: SheetofReviewerDesignerDepartmentProject
Page TitleCCBU D5 257Tuesday, August 29, 2023<project_name><Designer> GRANDTETON_SWB_20230829005 POWER SEQUENCE<Reviewer>



5
5
4
4
3
3
2
2
1
1
D D
C C
B B
A A
CLOCK DIAGRAM SizeDoc NumberRevDate: SheetofReviewerDesignerDepartmentProject
Page TitleCCBU D6 257Tuesday, August 29, 2023<project_name><Designer> GRANDTETON_SWB_20230829006 CLOCK DIAGRAM<Reviewer>SizeDoc NumberRevDate: SheetofReviewerDesignerDepartmentProject
Page TitleCCBU D6 257Tuesday, August 29, 2023<project_name><Designer> GRANDTETON_SWB_20230829006 CLOCK DIAGRAM<Reviewer>SizeDoc NumberRevDate: SheetofReviewerDesignerDepartmentProject
Page TitleCCBU D6 257Tuesday, August 29, 2023<project_name><Designer> GRANDTETON_SWB_20230829006 CLOCK DIAGRAM<Reviewer>



5
5
4
4
3
3
2
2
1
1
D D
C C
B B
A A
 I2C Topology SizeDoc NumberRevDate: SheetofReviewerDesignerDepartmentProject
Page TitleCCBU D7 257Tuesday, August 29, 2023<project_name><Designer> GRANDTETON_SWB_20230829007 I2C Topology<Reviewer>SizeDoc NumberRevDate: SheetofReviewerDesignerDepartmentProject
Page TitleCCBU D7 257Tuesday, August 29, 2023<project_name><Designer> GRANDTETON_SWB_20230829007 I2C Topology<Reviewer>SizeDoc NumberRevDate: SheetofReviewerDesignerDepartmentProject
Page TitleCCBU D7 257Tuesday, August 29, 2023<project_name><Designer> GRANDTETON_SWB_20230829007 I2C Topology<Reviewer>



5
5
4
4
3
3
2
2
1
1
D D
C C
B B
A A
USB TOPOLOGY SizeDoc NumberRevDate: SheetofReviewerDesignerDepartmentProject
Page TitleCCBU D8 257Tuesday, August 29, 2023<project_name><Designer> GRANDTETON_SWB_20230829008 USB TOPOLOGY<Reviewer>SizeDoc NumberRevDate: SheetofReviewerDesignerDepartmentProject
Page TitleCCBU D8 257Tuesday, August 29, 2023<project_name><Designer> GRANDTETON_SWB_20230829008 USB TOPOLOGY<Reviewer>SizeDoc NumberRevDate: SheetofReviewerDesignerDepartmentProject
Page TitleCCBU D8 257Tuesday, August 29, 2023<project_name><Designer> GRANDTETON_SWB_20230829008 USB TOPOLOGY<Reviewer>



5
5
4
4
3
3
2
2
1
1
D D
C C
B B
A A
JTAG Diagram SizeDoc NumberRevDate: SheetofReviewerDesignerDepartmentProject
Page TitleCCBU D9 257Tuesday, August 29, 2023<project_name><Designer> GRANDTETON_SWB_20230829009 JTAG Diagram<Reviewer>SizeDoc NumberRevDate: SheetofReviewerDesignerDepartmentProject
Page TitleCCBU D9 257Tuesday, August 29, 2023<project_name><Designer> GRANDTETON_SWB_20230829009 JTAG Diagram<Reviewer>SizeDoc NumberRevDate: SheetofReviewerDesignerDepartmentProject
Page TitleCCBU D9 257Tuesday, August 29, 2023<project_name><Designer> GRANDTETON_SWB_20230829009 JTAG Diagram<Reviewer>



5
5
4
4
3
3
2
2
1
1
D D
C C
B B
A A
PEX_0_STN_01(1/11)
P5E_PEX0_STN0_TX_C_DP<15> [171]P5E_PEX0_STN0_TX_C_DN<15> [171]P5E_PEX0_STN0_TX_C_DN<14> [171]P5E_PEX0_STN0_TX_C_DP<14> [171]P5E_PEX0_STN0_TX_C_DP<13> [171]P5E_PEX0_STN0_TX_C_DN<13> [171]P5E_PEX0_STN0_TX_C_DN<12> [171]P5E_PEX0_STN0_TX_C_DP<12> [171]P5E_PEX0_STN0_TX_C_DP<11> [171]P5E_PEX0_STN0_TX_C_DN<11> [171]P5E_PEX0_STN0_TX_C_DP<10> [171]P5E_PEX0_STN0_TX_C_DN<10> [171]P5E_PEX0_STN0_TX_C_DP<9> [171]P5E_PEX0_STN0_TX_C_DN<9> [171]P5E_PEX0_STN0_TX_C_DP<8> [171]P5E_PEX0_STN0_TX_C_DN<8> [171]P5E_PEX0_STN0_TX_C_DP<7> [171]P5E_PEX0_STN0_TX_C_DN<7> [171]P5E_PEX0_STN0_TX_C_DP<6> [171]P5E_PEX0_STN0_TX_C_DN<6> [171]P5E_PEX0_STN0_TX_C_DP<5> [171]P5E_PEX0_STN0_TX_C_DN<5> [171]P5E_PEX0_STN0_TX_C_DP<4> [171]P5E_PEX0_STN0_TX_C_DN<4> [171]P5E_PEX0_STN0_TX_C_DP<3> [171]P5E_PEX0_STN0_TX_C_DN<3> [171]P5E_PEX0_STN0_TX_C_DP<2> [171]P5E_PEX0_STN0_TX_C_DN<2> [171]P5E_PEX0_STN0_TX_C_DP<1> [171]P5E_PEX0_STN0_TX_C_DN<1> [171]P5E_PEX0_STN0_TX_C_DP<0> [171]P5E_PEX0_STN0_TX_C_DN<0> [171]P5E_PEX0_STN1_TX_C_DP<16> [168]P5E_PEX0_STN1_TX_C_DN<16> [168]P5E_PEX0_STN1_TX_C_DN<17> [168]P5E_PEX0_STN1_TX_C_DP<17> [168]P5E_PEX0_STN1_TX_C_DN<19> [168]P5E_PEX0_STN1_TX_C_DP<19> [168]P5E_PEX0_STN1_TX_C_DP<18> [168]P5E_PEX0_STN1_TX_C_DN<18> [168]P5E_PEX0_STN1_TX_C_DN<23> [168]P5E_PEX0_STN1_TX_C_DP<23> [168]P5E_PEX0_STN1_TX_C_DP<22> [168]P5E_PEX0_STN1_TX_C_DN<22> [168]P5E_PEX0_STN1_TX_C_DN<21> [168]P5E_PEX0_STN1_TX_C_DP<21> [168]P5E_PEX0_STN1_TX_C_DP<20> [168]P5E_PEX0_STN1_TX_C_DN<20> [168]P5E_PEX0_STN1_TX_C_DP<24> [168]P5E_PEX0_STN1_TX_C_DN<24> [168]P5E_PEX0_STN1_TX_C_DN<25> [168]P5E_PEX0_STN1_TX_C_DP<25> [168]P5E_PEX0_STN1_TX_C_DN<27> [168]P5E_PEX0_STN1_TX_C_DP<27> [168]P5E_PEX0_STN1_TX_C_DP<26> [168]P5E_PEX0_STN1_TX_C_DN<26> [168]P5E_PEX0_STN1_TX_C_DN<31> [168]P5E_PEX0_STN1_TX_C_DP<31> [168]P5E_PEX0_STN1_TX_C_DP<30> [168]P5E_PEX0_STN1_TX_C_DN<30> [168]P5E_PEX0_STN1_TX_C_DN<29> [168]P5E_PEX0_STN1_TX_C_DP<29> [168]P5E_PEX0_STN1_TX_C_DP<28> [168]P5E_PEX0_STN1_TX_C_DN<28> [168]
P5E_PEX0_STN0_RX_DP<15>[171]P5E_PEX0_STN0_RX_DN<15>[171]P5E_PEX0_STN0_RX_DP<14>[171]P5E_PEX0_STN0_RX_DN<14>[171]P5E_PEX0_STN0_RX_DP<13>[171]P5E_PEX0_STN0_RX_DN<13>[171]P5E_PEX0_STN0_RX_DP<12>[171]P5E_PEX0_STN0_RX_DN<12>[171]P5E_PEX0_STN0_RX_DP<11>[171]P5E_PEX0_STN0_RX_DN<11>[171]P5E_PEX0_STN0_RX_DP<10>[171]P5E_PEX0_STN0_RX_DN<10>[171]P5E_PEX0_STN0_RX_DP<9>[171]P5E_PEX0_STN0_RX_DN<9>[171]P5E_PEX0_STN0_RX_DP<8>[171]P5E_PEX0_STN0_RX_DN<8>[171]P5E_PEX0_STN0_RX_DP<7>[171]P5E_PEX0_STN0_RX_DN<7>[171]P5E_PEX0_STN0_RX_DP<6>[171]P5E_PEX0_STN0_RX_DN<6>[171]P5E_PEX0_STN0_RX_DP<5>[171]P5E_PEX0_STN0_RX_DN<5>[171]P5E_PEX0_STN0_RX_DP<4>[171]P5E_PEX0_STN0_RX_DN<4>[171]P5E_PEX0_STN0_RX_DP<3>[171]P5E_PEX0_STN0_RX_DN<3>[171]P5E_PEX0_STN0_RX_DP<2>[171]P5E_PEX0_STN0_RX_DN<2>[171]P5E_PEX0_STN0_RX_DP<1>[171]P5E_PEX0_STN0_RX_DN<1>[171]P5E_PEX0_STN0_RX_DP<0>[171]P5E_PEX0_STN0_RX_DN<0>[171]P5E_PEX0_STN1_RX_DP<31>[168]P5E_PEX0_STN1_RX_DN<31>[168]P5E_PEX0_STN1_RX_DP<30>[168]P5E_PEX0_STN1_RX_DN<30>[168]P5E_PEX0_STN1_RX_DP<29>[168]P5E_PEX0_STN1_RX_DN<29>[168]P5E_PEX0_STN1_RX_DP<28>[168]P5E_PEX0_STN1_RX_DN<28>[168]P5E_PEX0_STN1_RX_DP<27>[168]P5E_PEX0_STN1_RX_DN<27>[168]P5E_PEX0_STN1_RX_DP<26>[168]P5E_PEX0_STN1_RX_DN<26>[168]P5E_PEX0_STN1_RX_DP<25>[168]P5E_PEX0_STN1_RX_DN<25>[168]P5E_PEX0_STN1_RX_DP<24>[168]P5E_PEX0_STN1_RX_DN<24>[168]P5E_PEX0_STN1_RX_DP<23>[168]P5E_PEX0_STN1_RX_DN<23>[168]P5E_PEX0_STN1_RX_DP<22>[168]P5E_PEX0_STN1_RX_DN<22>[168]P5E_PEX0_STN1_RX_DP<21>[168]P5E_PEX0_STN1_RX_DN<21>[168]P5E_PEX0_STN1_RX_DP<20>[168]P5E_PEX0_STN1_RX_DN<20>[168]P5E_PEX0_STN1_RX_DP<19>[168]P5E_PEX0_STN1_RX_DN<19>[168]P5E_PEX0_STN1_RX_DP<18>[168]P5E_PEX0_STN1_RX_DN<18>[168]P5E_PEX0_STN1_RX_DP<17>[168]P5E_PEX0_STN1_RX_DN<17>[168]P5E_PEX0_STN1_RX_DP<16>[168]P5E_PEX0_STN1_RX_DN<16>[168]SizeDoc NumberRevDate: SheetofReviewerDesignerDepartmentProject
Page TitleCCBU D10 257Tuesday, August 29, 2023<project_name><Designer> GRANDTETON_SWB_20230829010 PEX_0_STN_01(1/11)<Reviewer>SizeDoc NumberRevDate: SheetofReviewerDesignerDepartmentProject
Page TitleCCBU D10 257Tuesday, August 29, 2023<project_name><Designer> GRANDTETON_SWB_20230829010 PEX_0_STN_01(1/11)<Reviewer>SizeDoc NumberRevDate: SheetofReviewerDesignerDepartmentProject
Page TitleCCBU D10 257Tuesday, August 29, 2023<project_name><Designer> GRANDTETON_SWB_20230829010 PEX_0_STN_01(1/11)<Reviewer>
C34 DIFF BUS_0.22UFC52 DIFF BUS_0.22UFC20 DIFF BUS_0.22UFC36 DIFF BUS_0.22UFC26 DIFF BUS_0.22UFC14 DIFF BUS_0.22UF
C61 DIFF BUS_0.22UF
C2 DIFF BUS_0.22UF
C37 DIFF BUS_0.22UFC30 DIFF BUS_0.22UFC25 DIFF BUS_0.22UFC23 DIFF BUS_0.22UFC38 DIFF BUS_0.22UFC28 DIFF BUS_0.22UFC5 DIFF BUS_0.22UF
C58 DIFF BUS_0.22UFC62 DIFF BUS_0.22UF
C6 DIFF BUS_0.22UFC3 DIFF BUS_0.22UFC12 DIFF BUS_0.22UFC44 DIFF BUS_0.22UFC57 DIFF BUS_0.22UF
C4 DIFF BUS_0.22UFC27 DIFF BUS_0.22UF
C64 DIFF BUS_0.22UFC39 DIFF BUS_0.22UFC10 DIFF BUS_0.22UF
C59 DIFF BUS_0.22UFC46 DIFF BUS_0.22UFC17 DIFF BUS_0.22UFC40 DIFF BUS_0.22UFC33 DIFF BUS_0.22UFC63 DIFF BUS_0.22UFC35 DIFF BUS_0.22UFC21 DIFF BUS_0.22UFC16 DIFF BUS_0.22UFC48 DIFF BUS_0.22UFC15 DIFF BUS_0.22UFC19 DIFF BUS_0.22UFC11 DIFF BUS_0.22UF
C55 DIFF BUS_0.22UFC49 DIFF BUS_0.22UF
C9 DIFF BUS_0.22UFC43 DIFF BUS_0.22UF2/26PEX0BSS26-0A0P-01RXP31BF40RXN31BG40RXP30BH39RXN30BJ39RXP29BF38RXN29BG38RXP28BH37RXN28BJ37RXP27BF36RXN27BG36RXP26BH35RXN26BJ35RXP25BF34RXN25BG34RXP24BH33RXN24BJ33RXP23BF32RXN23BG32RXP22BH31RXN22BJ31RXP21BF30RXN21BG30RXP20BH29RXN20BJ29RXP19BF28RXN19BG28RXP18BH27RXN18BJ27RXP17BF26RXN17BG26RXP16BH25RXN16BJ25TXP31BA40TXN31BB40TXP30BC39TXN30BD39TXP29BA38TXN29BB38TXP28BC37TXN28BD37TXP27BA36TXN27BB36TXP26BC35TXN26BD35TXP25BA34TXN25BB34TXP24BC33TXN24BD33TXP23BA32TXN23BB32TXP22BC31TXN22BD31TXP21BA30TXN21BB30TXP20BC29TXN20BD29TXP19BA28TXN19BB28TXP18BC27TXN18BD27TXP17BA26TXP16BC25TXN16BD25TXN17BB26C51 DIFF BUS_0.22UFC53 DIFF BUS_0.22UFC22 DIFF BUS_0.22UFC13 DIFF BUS_0.22UFC7 DIFF BUS_0.22UFC1 DIFF BUS_0.22UF
C47 DIFF BUS_0.22UF
1/26
PEX0ASS26-0A0P-01RXP15BH41RXN15BJ41RXP14BF42RXN14BG42RXP13BH43RXN13BJ43RXP12BF44RXN12BG44RXP11BH45RXN11BJ45RXP10BF46RXN10BG46RXP9BH47RXN9BJ47RXP8BG48RXN8BG49RXP7AY48RXN7AY49RXP6AW46RXN6AW47RXP5AV48RXN5AV49RXP4AU46RXN4AU47RXP3AT48RXN3AT49RXP2AR46RXN2AR47RXP1AP48RXN1AP49RXP0AN46RXN0AN47TXP15BC41TXN15BD41TXP14BA42TXN14BB42TXP13BC43TXN13BD43TXP12BA44TXN12BB44TXP11BC45TXN11BD45TXP10BA46TXN10BB46TXP9BC47TXN9BD47TXP8BE48TXN8BE49TXP7BB48TXN7BB49TXP6AW43TXN6AW44TXP5AV41TXN5AV42TXP4AU43TXN4AU44TXP3AT41TXN3AT42TXP2AR43TXN2AR44TXP1AP41TXN1AP42TXP0AN43TXN0AN44C54 DIFF BUS_0.22UF
C18 DIFF BUS_0.22UFC8 DIFF BUS_0.22UF
C45 DIFF BUS_0.22UFC32 DIFF BUS_0.22UFC31 DIFF BUS_0.22UFC24 DIFF BUS_0.22UFC42 DIFF BUS_0.22UFC50 DIFF BUS_0.22UFC29 DIFF BUS_0.22UFC41 DIFF BUS_0.22UFC56 DIFF BUS_0.22UFC60 DIFF BUS_0.22UFP5E_PEX0_STN0_TX_DP<0>P5E_PEX0_STN0_TX_DN<0>P5E_PEX0_STN1_TX_DN<31>P5E_PEX0_STN1_TX_DP<31>P5E_PEX0_STN0_TX_DP<1>P5E_PEX0_STN0_TX_DN<1>P5E_PEX0_STN0_TX_DP<3>P5E_PEX0_STN0_TX_DN<3>P5E_PEX0_STN0_TX_DP<2>P5E_PEX0_STN0_TX_DN<2>P5E_PEX0_STN0_TX_DP<7>P5E_PEX0_STN0_TX_DN<7>P5E_PEX0_STN0_TX_DP<6>P5E_PEX0_STN0_TX_DN<6>P5E_PEX0_STN0_TX_DP<5>P5E_PEX0_STN0_TX_DN<5>P5E_PEX0_STN0_TX_DP<4>P5E_PEX0_STN0_TX_DN<4>P5E_PEX0_STN0_TX_DP<15>P5E_PEX0_STN0_TX_DN<15>P5E_PEX0_STN0_TX_DN<14>P5E_PEX0_STN0_TX_DP<14>P5E_PEX0_STN0_TX_DP<13>P5E_PEX0_STN0_TX_DN<13>P5E_PEX0_STN0_TX_DN<12>P5E_PEX0_STN0_TX_DP<12>P5E_PEX0_STN0_TX_DP<11>P5E_PEX0_STN0_TX_DN<11>P5E_PEX0_STN0_TX_DP<10>P5E_PEX0_STN0_TX_DN<10>P5E_PEX0_STN0_TX_DP<9>P5E_PEX0_STN0_TX_DN<9>P5E_PEX0_STN0_TX_DP<8>P5E_PEX0_STN0_TX_DN<8>P5E_PEX0_STN1_TX_DP<30>P5E_PEX0_STN1_TX_DN<30>P5E_PEX0_STN1_TX_DN<29>P5E_PEX0_STN1_TX_DP<29>P5E_PEX0_STN1_TX_DP<28>P5E_PEX0_STN1_TX_DN<28>P5E_PEX0_STN1_TX_DN<27>P5E_PEX0_STN1_TX_DP<27>P5E_PEX0_STN1_TX_DP<26>P5E_PEX0_STN1_TX_DN<26>P5E_PEX0_STN1_TX_DN<25>P5E_PEX0_STN1_TX_DP<25>P5E_PEX0_STN1_TX_DP<24>P5E_PEX0_STN1_TX_DN<24>P5E_PEX0_STN1_TX_DN<23>P5E_PEX0_STN1_TX_DP<23>P5E_PEX0_STN1_TX_DP<22>P5E_PEX0_STN1_TX_DN<22>P5E_PEX0_STN1_TX_DN<21>P5E_PEX0_STN1_TX_DP<21>P5E_PEX0_STN1_TX_DP<20>P5E_PEX0_STN1_TX_DN<20>P5E_PEX0_STN1_TX_DN<19>P5E_PEX0_STN1_TX_DP<19>P5E_PEX0_STN1_TX_DP<18>P5E_PEX0_STN1_TX_DN<18>P5E_PEX0_STN1_TX_DN<17>P5E_PEX0_STN1_TX_DP<17>P5E_PEX0_STN1_TX_DP<16>P5E_PEX0_STN1_TX_DN<16>
P5E_PEX0_STN0_TX_C_DP<15>P5E_PEX0_STN0_TX_C_DN<15>P5E_PEX0_STN0_TX_C_DN<14>P5E_PEX0_STN0_TX_C_DP<14>P5E_PEX0_STN0_TX_C_DP<13>P5E_PEX0_STN0_TX_C_DN<13>P5E_PEX0_STN0_TX_C_DN<12>P5E_PEX0_STN0_TX_C_DP<12>P5E_PEX0_STN0_TX_C_DP<11>P5E_PEX0_STN0_TX_C_DN<11>P5E_PEX0_STN0_TX_C_DP<10>P5E_PEX0_STN0_TX_C_DN<10>P5E_PEX0_STN0_TX_C_DP<9>P5E_PEX0_STN0_TX_C_DN<9>P5E_PEX0_STN0_TX_C_DP<8>P5E_PEX0_STN0_TX_C_DN<8>P5E_PEX0_STN0_TX_C_DP<7>P5E_PEX0_STN0_TX_C_DN<7>P5E_PEX0_STN0_TX_C_DP<6>P5E_PEX0_STN0_TX_C_DN<6>P5E_PEX0_STN0_TX_C_DP<5>P5E_PEX0_STN0_TX_C_DN<5>P5E_PEX0_STN0_TX_C_DP<4>P5E_PEX0_STN0_TX_C_DN<4>P5E_PEX0_STN0_TX_C_DP<3>P5E_PEX0_STN0_TX_C_DN<3>P5E_PEX0_STN0_TX_C_DP<2>P5E_PEX0_STN0_TX_C_DN<2>P5E_PEX0_STN0_TX_C_DP<1>P5E_PEX0_STN0_TX_C_DN<1>P5E_PEX0_STN0_TX_C_DP<0>P5E_PEX0_STN0_TX_C_DN<0>P5E_PEX0_STN1_TX_C_DP<16>P5E_PEX0_STN1_TX_C_DN<16>P5E_PEX0_STN1_TX_C_DN<17>P5E_PEX0_STN1_TX_C_DP<17>P5E_PEX0_STN1_TX_C_DN<19>P5E_PEX0_STN1_TX_C_DP<19>P5E_PEX0_STN1_TX_C_DP<18>P5E_PEX0_STN1_TX_C_DN<18>P5E_PEX0_STN1_TX_C_DN<23>P5E_PEX0_STN1_TX_C_DP<23>P5E_PEX0_STN1_TX_C_DP<22>P5E_PEX0_STN1_TX_C_DN<22>P5E_PEX0_STN1_TX_C_DN<21>P5E_PEX0_STN1_TX_C_DP<21>P5E_PEX0_STN1_TX_C_DP<20>P5E_PEX0_STN1_TX_C_DN<20>P5E_PEX0_STN1_TX_C_DP<24>P5E_PEX0_STN1_TX_C_DN<24>P5E_PEX0_STN1_TX_C_DN<25>P5E_PEX0_STN1_TX_C_DP<25>P5E_PEX0_STN1_TX_C_DN<27>P5E_PEX0_STN1_TX_C_DP<27>P5E_PEX0_STN1_TX_C_DP<26>P5E_PEX0_STN1_TX_C_DN<26>P5E_PEX0_STN1_TX_C_DN<31>P5E_PEX0_STN1_TX_C_DP<31>P5E_PEX0_STN1_TX_C_DP<30>P5E_PEX0_STN1_TX_C_DN<30>P5E_PEX0_STN1_TX_C_DN<29>P5E_PEX0_STN1_TX_C_DP<29>P5E_PEX0_STN1_TX_C_DP<28>P5E_PEX0_STN1_TX_C_DN<28>
P5E_PEX0_STN0_RX_DP<15>P5E_PEX0_STN0_RX_DN<15>P5E_PEX0_STN0_RX_DP<14>P5E_PEX0_STN0_RX_DN<14>P5E_PEX0_STN0_RX_DP<13>P5E_PEX0_STN0_RX_DN<13>P5E_PEX0_STN0_RX_DP<12>P5E_PEX0_STN0_RX_DN<12>P5E_PEX0_STN0_RX_DP<11>P5E_PEX0_STN0_RX_DN<11>P5E_PEX0_STN0_RX_DP<10>P5E_PEX0_STN0_RX_DN<10>P5E_PEX0_STN0_RX_DP<9>P5E_PEX0_STN0_RX_DN<9>P5E_PEX0_STN0_RX_DP<8>P5E_PEX0_STN0_RX_DN<8>P5E_PEX0_STN0_RX_DP<7>P5E_PEX0_STN0_RX_DN<7>P5E_PEX0_STN0_RX_DP<6>P5E_PEX0_STN0_RX_DN<6>P5E_PEX0_STN0_RX_DP<5>P5E_PEX0_STN0_RX_DN<5>P5E_PEX0_STN0_RX_DP<4>P5E_PEX0_STN0_RX_DN<4>P5E_PEX0_STN0_RX_DP<3>P5E_PEX0_STN0_RX_DN<3>P5E_PEX0_STN0_RX_DP<2>P5E_PEX0_STN0_RX_DN<2>P5E_PEX0_STN0_RX_DP<1>P5E_PEX0_STN0_RX_DN<1>P5E_PEX0_STN0_RX_DP<0>P5E_PEX0_STN0_RX_DN<0>P5E_PEX0_STN1_RX_DP<31>P5E_PEX0_STN1_RX_DN<31>P5E_PEX0_STN1_RX_DP<30>P5E_PEX0_STN1_RX_DN<30>P5E_PEX0_STN1_RX_DP<29>P5E_PEX0_STN1_RX_DN<29>P5E_PEX0_STN1_RX_DP<28>P5E_PEX0_STN1_RX_DN<28>P5E_PEX0_STN1_RX_DP<27>P5E_PEX0_STN1_RX_DN<27>P5E_PEX0_STN1_RX_DP<26>P5E_PEX0_STN1_RX_DN<26>P5E_PEX0_STN1_RX_DP<25>P5E_PEX0_STN1_RX_DN<25>P5E_PEX0_STN1_RX_DP<24>P5E_PEX0_STN1_RX_DN<24>P5E_PEX0_STN1_RX_DP<23>P5E_PEX0_STN1_RX_DN<23>P5E_PEX0_STN1_RX_DP<22>P5E_PEX0_STN1_RX_DN<22>P5E_PEX0_STN1_RX_DP<21>P5E_PEX0_STN1_RX_DN<21>P5E_PEX0_STN1_RX_DP<20>P5E_PEX0_STN1_RX_DN<20>P5E_PEX0_STN1_RX_DP<19>P5E_PEX0_STN1_RX_DN<19>P5E_PEX0_STN1_RX_DP<18>P5E_PEX0_STN1_RX_DN<18>P5E_PEX0_STN1_RX_DP<17>P5E_PEX0_STN1_RX_DN<17>P5E_PEX0_STN1_RX_DP<16>P5E_PEX0_STN1_RX_DN<16>



5
5
4
4
3
3
2
2
1
1
D D
C C
B B
A A
PEX_0_STN_23(2/11)
P5E_PEX0_STN2_TX_C_DP<47> [194]P5E_PEX0_STN2_TX_C_DN<47> [194]P5E_PEX0_STN2_TX_C_DP<46> [194]P5E_PEX0_STN2_TX_C_DN<46> [194]P5E_PEX0_STN2_TX_C_DP<45> [194]P5E_PEX0_STN2_TX_C_DN<45> [194]P5E_PEX0_STN2_TX_C_DP<44> [194]P5E_PEX0_STN2_TX_C_DN<44> [194]P5E_PEX0_STN2_TX_C_DP<43> [194]P5E_PEX0_STN2_TX_C_DN<43> [194]P5E_PEX0_STN2_TX_C_DP<42> [194]P5E_PEX0_STN2_TX_C_DN<42> [194]P5E_PEX0_STN2_TX_C_DP<41> [194]P5E_PEX0_STN2_TX_C_DN<41> [194]P5E_PEX0_STN2_TX_C_DP<40> [194]P5E_PEX0_STN2_TX_C_DN<40> [194]P5E_PEX0_STN2_TX_C_DP<39> [195]P5E_PEX0_STN2_TX_C_DN<39> [195]P5E_PEX0_STN2_TX_C_DP<38> [195]P5E_PEX0_STN2_TX_C_DN<38> [195]P5E_PEX0_STN2_TX_C_DP<37> [195]P5E_PEX0_STN2_TX_C_DN<37> [195]P5E_PEX0_STN2_TX_C_DP<36> [195]P5E_PEX0_STN2_TX_C_DN<36> [195]P5E_PEX0_STN2_TX_C_DP<35> [195]P5E_PEX0_STN2_TX_C_DN<35> [195]P5E_PEX0_STN2_TX_C_DP<34> [195]P5E_PEX0_STN2_TX_C_DN<34> [195]P5E_PEX0_STN2_TX_C_DP<33> [195]P5E_PEX0_STN2_TX_C_DN<33> [195]P5E_PEX0_STN2_TX_C_DP<32> [195]P5E_PEX0_STN2_TX_C_DN<32> [195]P5E_PEX0_STN2_RX_DP<47>[194]P5E_PEX0_STN2_RX_DN<47>[194]P5E_PEX0_STN2_RX_DP<46>[194]P5E_PEX0_STN2_RX_DN<46>[194]P5E_PEX0_STN2_RX_DP<45>[194]P5E_PEX0_STN2_RX_DN<45>[194]P5E_PEX0_STN2_RX_DP<44>[194]P5E_PEX0_STN2_RX_DN<44>[194]P5E_PEX0_STN2_RX_DP<43>[194]P5E_PEX0_STN2_RX_DN<43>[194]P5E_PEX0_STN2_RX_DP<42>[194]P5E_PEX0_STN2_RX_DN<42>[194]P5E_PEX0_STN2_RX_DP<41>[194]P5E_PEX0_STN2_RX_DN<41>[194]P5E_PEX0_STN2_RX_DP<40>[194]P5E_PEX0_STN2_RX_DN<40>[194]P5E_PEX0_STN2_RX_DP<39>[195]P5E_PEX0_STN2_RX_DN<39>[195]P5E_PEX0_STN2_RX_DP<38>[195]P5E_PEX0_STN2_RX_DN<38>[195]P5E_PEX0_STN2_RX_DP<37>[195]P5E_PEX0_STN2_RX_DN<37>[195]P5E_PEX0_STN2_RX_DP<36>[195]P5E_PEX0_STN2_RX_DN<36>[195]P5E_PEX0_STN2_RX_DP<35>[195]P5E_PEX0_STN2_RX_DN<35>[195]P5E_PEX0_STN2_RX_DP<34>[195]P5E_PEX0_STN2_RX_DN<34>[195]P5E_PEX0_STN2_RX_DP<33>[195]P5E_PEX0_STN2_RX_DN<33>[195]P5E_PEX0_STN2_RX_DP<32>[195]P5E_PEX0_STN2_RX_DN<32>[195]P4E_PEX0_STN3_RX_DP<49>[128]P4E_PEX0_STN3_RX_DN<49>[128]P4E_PEX0_STN3_TX_C_DP<49> [128]P4E_PEX0_STN3_TX_C_DN<49> [128]P4E_PEX0_STN3_RX_DP<48>[128]P4E_PEX0_STN3_TX_C_DP<48> [128]P4E_PEX0_STN3_RX_DN<48>[128]P4E_PEX0_STN3_TX_C_DN<48> [128]SizeDoc NumberRevDate: SheetofReviewerDesignerDepartmentProject
Page TitleCCBU D11 257Tuesday, August 29, 2023<project_name><Designer> GRANDTETON_SWB_20230829011 PEX_0_STN_23(2/11)<Reviewer>SizeDoc NumberRevDate: SheetofReviewerDesignerDepartmentProject
Page TitleCCBU D11 257Tuesday, August 29, 2023<project_name><Designer> GRANDTETON_SWB_20230829011 PEX_0_STN_23(2/11)<Reviewer>SizeDoc NumberRevDate: SheetofReviewerDesignerDepartmentProject
Page TitleCCBU D11 257Tuesday, August 29, 2023<project_name><Designer> GRANDTETON_SWB_20230829011 PEX_0_STN_23(2/11)<Reviewer>
C96 DIFF BUS_0.22UFC89 DIFF BUS_0.22UFC94 DIFF BUS_0.22UFC73 DIFF BUS_0.22UFC92 DIFF BUS_0.22UFC91 DIFF BUS_0.22UFC77 DIFF BUS_0.22UFC68 DIFF BUS_0.22UFC83 DIFF BUS_0.22UF3/26PEX0CSS26-0A0P-01RXP47BH9RXN47BJ9RXP46BF10RXN46BG10RXP45BH11RXN45BJ11RXP44BF12RXN44BG12RXP43BH13RXN43BJ13RXP42BF14RXN42BG14RXP41BH15RXN41BJ15RXP40BF16RXN40BG16RXP39BH17RXN39BJ17RXP38BF18RXN38BG18RXP37BH19RXN37BJ19RXP36BF20RXN36BG20RXP35BH21RXN35BJ21RXP34BF22RXN34BG22RXP33BH23RXN33BJ23RXP32BF24RXN32BG24TXP47BC9TXN47BD9TXP46BA10TXN46BB10TXP45BC11TXN45BD11TXP44BA12TXN44BB12TXP43BC13TXN43BD13TXP42BA14TXN42BB14TXP41BC15TXN41BD15TXP40BA16TXN40BB16TXP39BC17TXN39BD17TXP38BA18TXN38BB18TXP37BC19TXN37BD19TXP36BA20TXN36BB20TXP35BC21TXN35BD21TXP34BA22TXN34BB22TXP33BC23TXN33BD23TXP32BA24TXN32BB24C75 DIFF BUS_0.22UFC80 DIFF BUS_0.22UFC76 DIFF BUS_0.22UF
C3986 DIFF BUS_0.22UF
C82 DIFF BUS_0.22UFC78 DIFF BUS_0.22UFC71 DIFF BUS_0.22UFC81 DIFF BUS_0.22UFC93 DIFF BUS_0.22UFC74 DIFF BUS_0.22UF
C3984 DIFF BUS_0.22UFC3987 DIFF BUS_0.22UF
C65 DIFF BUS_0.22UFC86 DIFF BUS_0.22UFC95 DIFF BUS_0.22UFC3985 DIFF BUS_0.22UF
C72 DIFF BUS_0.22UF4/26PEX0DSS26-0A0P-01RXP63BF8RXN63BG8RXP62BH7RXN62BJ7RXP61BF6RXN61BG6RXP60BH5RXN60BJ5RXP59BF4RXN59BG4RXP58BH3RXN58BJ3RXP57BG2RXN57BG1RXP56AY2RXN56AY1RXP55AW4RXN55AW3RXP54AV2RXN54AV1RXP53AU4RXN53AU3RXP52AT2RXN52AT1RXP51AR4RXN51AR3RXP50AP2RXN50AP1RXP49AN4RXN49AN3RXP48AM2RXN48AM1TXP63BA8TXN63BB8TXP62BC7TXN62BD7TXP61BA6TXN61BB6TXP60BC5TXN60BD5TXP59BA4TXN59BB4TXP58BC3TXN58BD3TXP57BE2TXN57BE1TXP56BB2TXN56BB1TXP55AW7TXN55AW6TXP54AV9TXN54AV8TXP53AU7TXN53AU6TXP52AT9TXN52AT8TXP51AR7TXN51AR6TXP50AP9TXN50AP8TXP49AN7TXN49AN6TXP48AM9TXN48AM8
C66 DIFF BUS_0.22UFC90 DIFF BUS_0.22UFC85 DIFF BUS_0.22UFC88 DIFF BUS_0.22UFC87 DIFF BUS_0.22UFC67 DIFF BUS_0.22UFC70 DIFF BUS_0.22UFC69 DIFF BUS_0.22UFC84 DIFF BUS_0.22UFC79 DIFF BUS_0.22UFP5E_PEX0_STN2_TX_DP<47>P5E_PEX0_STN2_TX_DN<47>P5E_PEX0_STN2_TX_DP<39>P5E_PEX0_STN2_TX_DN<39>P5E_PEX0_STN2_TX_DP<46>P5E_PEX0_STN2_TX_DN<46>P5E_PEX0_STN2_TX_DP<45>P5E_PEX0_STN2_TX_DN<45>P5E_PEX0_STN2_TX_DP<44>P5E_PEX0_STN2_TX_DN<44>P5E_PEX0_STN2_TX_DP<43>P5E_PEX0_STN2_TX_DN<43>P5E_PEX0_STN2_TX_DP<42>P5E_PEX0_STN2_TX_DN<42>P5E_PEX0_STN2_TX_DP<41>P5E_PEX0_STN2_TX_DN<41>P5E_PEX0_STN2_TX_DP<40>P5E_PEX0_STN2_TX_DN<40>P5E_PEX0_STN2_TX_DP<38>P5E_PEX0_STN2_TX_DN<38>P5E_PEX0_STN2_TX_DP<37>P5E_PEX0_STN2_TX_DN<37>P5E_PEX0_STN2_TX_DP<36>P5E_PEX0_STN2_TX_DN<36>P5E_PEX0_STN2_TX_DP<35>P5E_PEX0_STN2_TX_DN<35>P5E_PEX0_STN2_TX_DP<34>P5E_PEX0_STN2_TX_DN<34>P5E_PEX0_STN2_TX_DP<33>P5E_PEX0_STN2_TX_DN<33>P5E_PEX0_STN2_TX_DP<32>P5E_PEX0_STN2_TX_DN<32>P5E_PEX0_STN2_TX_C_DP<47>P5E_PEX0_STN2_TX_C_DN<47>P5E_PEX0_STN2_TX_C_DP<46>P5E_PEX0_STN2_TX_C_DN<46>P5E_PEX0_STN2_TX_C_DP<45>P5E_PEX0_STN2_TX_C_DN<45>P5E_PEX0_STN2_TX_C_DP<44>P5E_PEX0_STN2_TX_C_DN<44>P5E_PEX0_STN2_TX_C_DP<43>P5E_PEX0_STN2_TX_C_DN<43>P5E_PEX0_STN2_TX_C_DP<42>P5E_PEX0_STN2_TX_C_DN<42>P5E_PEX0_STN2_TX_C_DP<41>P5E_PEX0_STN2_TX_C_DN<41>P5E_PEX0_STN2_TX_C_DP<40>P5E_PEX0_STN2_TX_C_DN<40>P5E_PEX0_STN2_TX_C_DP<39>P5E_PEX0_STN2_TX_C_DN<39>P5E_PEX0_STN2_TX_C_DP<38>P5E_PEX0_STN2_TX_C_DN<38>P5E_PEX0_STN2_TX_C_DP<37>P5E_PEX0_STN2_TX_C_DN<37>P5E_PEX0_STN2_TX_C_DP<36>P5E_PEX0_STN2_TX_C_DN<36>P5E_PEX0_STN2_TX_C_DP<35>P5E_PEX0_STN2_TX_C_DN<35>P5E_PEX0_STN2_TX_C_DP<34>P5E_PEX0_STN2_TX_C_DN<34>P5E_PEX0_STN2_TX_C_DP<33>P5E_PEX0_STN2_TX_C_DN<33>P5E_PEX0_STN2_TX_C_DP<32>P5E_PEX0_STN2_TX_C_DN<32>P5E_PEX0_STN2_RX_DP<47>P5E_PEX0_STN2_RX_DN<47>P5E_PEX0_STN2_RX_DP<46>P5E_PEX0_STN2_RX_DN<46>P5E_PEX0_STN2_RX_DP<45>P5E_PEX0_STN2_RX_DN<45>P5E_PEX0_STN2_RX_DP<44>P5E_PEX0_STN2_RX_DN<44>P5E_PEX0_STN2_RX_DP<43>P5E_PEX0_STN2_RX_DN<43>P5E_PEX0_STN2_RX_DP<42>P5E_PEX0_STN2_RX_DN<42>P5E_PEX0_STN2_RX_DP<41>P5E_PEX0_STN2_RX_DN<41>P5E_PEX0_STN2_RX_DP<40>P5E_PEX0_STN2_RX_DN<40>P5E_PEX0_STN2_RX_DP<39>P5E_PEX0_STN2_RX_DN<39>P5E_PEX0_STN2_RX_DP<38>P5E_PEX0_STN2_RX_DN<38>P5E_PEX0_STN2_RX_DP<37>P5E_PEX0_STN2_RX_DN<37>P5E_PEX0_STN2_RX_DP<36>P5E_PEX0_STN2_RX_DN<36>P5E_PEX0_STN2_RX_DP<35>P5E_PEX0_STN2_RX_DN<35>P5E_PEX0_STN2_RX_DP<34>P5E_PEX0_STN2_RX_DN<34>P5E_PEX0_STN2_RX_DP<33>P5E_PEX0_STN2_RX_DN<33>P5E_PEX0_STN2_RX_DP<32>P5E_PEX0_STN2_RX_DN<32>P4E_PEX0_STN3_RX_DP<49>P4E_PEX0_STN3_RX_DN<49>P4E_PEX0_STN3_TX_DP<49>P4E_PEX0_STN3_TX_DN<49>P4E_PEX0_STN3_TX_C_DP<49>P4E_PEX0_STN3_TX_C_DN<49>P4E_PEX0_STN3_RX_DP<48>P4E_PEX0_STN3_TX_DP<48>P4E_PEX0_STN3_TX_C_DP<48>P4E_PEX0_STN3_RX_DN<48>P4E_PEX0_STN3_TX_DN<48>P4E_PEX0_STN3_TX_C_DN<48>



5
5
4
4
3
3
2
2
1
1
D D
C C
B B
A A
PEX_0_STN_45(3/11)
P5E_PEX0_STN4_RX_DP<79>[124]P5E_PEX0_STN4_TX_C_DP<79> [124]P5E_PEX0_STN4_RX_DN<79>[124]P5E_PEX0_STN4_TX_C_DN<79> [124]P5E_PEX0_STN4_RX_DP<78>[124]P5E_PEX0_STN4_TX_C_DP<78> [124]P5E_PEX0_STN4_RX_DN<78>[124]P5E_PEX0_STN4_TX_C_DN<78> [124]P5E_PEX0_STN4_RX_DP<77>[125]P5E_PEX0_STN4_TX_C_DP<77> [125]P5E_PEX0_STN4_RX_DN<77>[125]P5E_PEX0_STN4_TX_C_DN<77> [125]P5E_PEX0_STN4_RX_DP<76>[125]P5E_PEX0_STN4_TX_C_DP<76> [125]P5E_PEX0_STN4_RX_DN<76>[125]P5E_PEX0_STN4_TX_C_DN<76> [125]P5E_PEX0_STN4_RX_DP<75>[126]P5E_PEX0_STN4_TX_C_DP<75> [126]P5E_PEX0_STN4_RX_DN<75>[126]P5E_PEX0_STN4_TX_C_DN<75> [126]P5E_PEX0_STN4_RX_DP<74>[126]P5E_PEX0_STN4_TX_C_DP<74> [126]P5E_PEX0_STN4_RX_DN<74>[126]P5E_PEX0_STN4_TX_C_DN<74> [126]P5E_PEX0_STN4_RX_DP<73>[127]P5E_PEX0_STN4_TX_C_DP<73> [127]P5E_PEX0_STN4_RX_DN<73>[127]P5E_PEX0_STN4_TX_C_DN<73> [127]P5E_PEX0_STN4_RX_DP<72>[127]P5E_PEX0_STN4_TX_C_DP<72> [127]P5E_PEX0_STN4_RX_DN<72>[127]P5E_PEX0_STN4_TX_C_DN<72> [127]P5E_PEX0_STN4_RX_DP<71>[124]P5E_PEX0_STN4_TX_C_DP<71> [124]P5E_PEX0_STN4_RX_DN<71>[124]P5E_PEX0_STN4_TX_C_DN<71> [124]P5E_PEX0_STN4_RX_DP<70>[124]P5E_PEX0_STN4_TX_C_DP<70> [124]P5E_PEX0_STN4_RX_DN<70>[124]P5E_PEX0_STN4_TX_C_DN<70> [124]P5E_PEX0_STN4_RX_DP<69>[125]P5E_PEX0_STN4_TX_C_DP<69> [125]P5E_PEX0_STN4_RX_DN<69>[125]P5E_PEX0_STN4_TX_C_DN<69> [125]P5E_PEX0_STN4_RX_DP<68>[125]P5E_PEX0_STN4_TX_C_DP<68> [125]P5E_PEX0_STN4_RX_DN<68>[125]P5E_PEX0_STN4_TX_C_DN<68> [125]P5E_PEX0_STN4_RX_DP<67>[126]P5E_PEX0_STN4_TX_C_DP<67> [126]P5E_PEX0_STN4_RX_DN<67>[126]P5E_PEX0_STN4_TX_C_DN<67> [126]P5E_PEX0_STN4_RX_DP<66>[126]P5E_PEX0_STN4_TX_C_DP<66> [126]P5E_PEX0_STN4_RX_DN<66>[126]P5E_PEX0_STN4_TX_C_DN<66> [126]P5E_PEX0_STN4_RX_DP<65>[127]P5E_PEX0_STN4_TX_C_DP<65> [127]P5E_PEX0_STN4_RX_DN<65>[127]P5E_PEX0_STN4_TX_C_DN<65> [127]P5E_PEX0_STN4_RX_DP<64>[127]P5E_PEX0_STN4_TX_C_DP<64> [127]P5E_PEX0_STN4_RX_DN<64>[127]P5E_PEX0_STN4_TX_C_DN<64> [127]P5E_PEX0_STN5_RX_DP<95>[132]P5E_PEX0_STN5_TX_C_DP<95> [132]P5E_PEX0_STN5_RX_DN<95>[132]P5E_PEX0_STN5_TX_C_DN<95> [132]P5E_PEX0_STN5_RX_DP<94>[132]P5E_PEX0_STN5_TX_C_DP<94> [132]P5E_PEX0_STN5_RX_DN<94>[132]P5E_PEX0_STN5_TX_C_DN<94> [132]P5E_PEX0_STN5_RX_DP<93>[131]P5E_PEX0_STN5_TX_C_DP<93> [131]P5E_PEX0_STN5_RX_DN<93>[131]P5E_PEX0_STN5_TX_C_DN<93> [131]P5E_PEX0_STN5_RX_DP<92>[131]P5E_PEX0_STN5_TX_C_DP<92> [131]P5E_PEX0_STN5_RX_DN<92>[131]P5E_PEX0_STN5_TX_C_DN<92> [131]P5E_PEX0_STN5_RX_DP<91>[130]P5E_PEX0_STN5_TX_C_DP<91> [130]P5E_PEX0_STN5_RX_DN<91>[130]P5E_PEX0_STN5_TX_C_DN<91> [130]P5E_PEX0_STN5_RX_DP<90>[130]P5E_PEX0_STN5_TX_C_DP<90> [130]P5E_PEX0_STN5_RX_DN<90>[130]P5E_PEX0_STN5_TX_C_DN<90> [130]P5E_PEX0_STN5_RX_DP<89>[129]P5E_PEX0_STN5_TX_C_DP<89> [129]P5E_PEX0_STN5_RX_DN<89>[129]P5E_PEX0_STN5_TX_C_DN<89> [129]P5E_PEX0_STN5_RX_DP<88>[129]P5E_PEX0_STN5_TX_C_DP<88> [129]P5E_PEX0_STN5_RX_DN<88>[129]P5E_PEX0_STN5_TX_C_DN<88> [129]P5E_PEX0_STN5_RX_DP<87>[132]P5E_PEX0_STN5_TX_C_DP<87> [132]P5E_PEX0_STN5_RX_DN<87>[132]P5E_PEX0_STN5_TX_C_DN<87> [132]P5E_PEX0_STN5_RX_DP<86>[132]P5E_PEX0_STN5_TX_C_DP<86> [132]P5E_PEX0_STN5_RX_DN<86>[132]P5E_PEX0_STN5_TX_C_DN<86> [132]P5E_PEX0_STN5_RX_DP<85>[131]P5E_PEX0_STN5_TX_C_DP<85> [131]P5E_PEX0_STN5_RX_DN<85>[131]P5E_PEX0_STN5_TX_C_DN<85> [131]P5E_PEX0_STN5_RX_DP<84>[131]P5E_PEX0_STN5_TX_C_DP<84> [131]P5E_PEX0_STN5_RX_DN<84>[131]P5E_PEX0_STN5_TX_C_DN<84> [131]P5E_PEX0_STN5_RX_DP<83>[130]P5E_PEX0_STN5_TX_C_DP<83> [130]P5E_PEX0_STN5_RX_DN<83>[130]P5E_PEX0_STN5_TX_C_DN<83> [130]P5E_PEX0_STN5_RX_DP<82>[130]P5E_PEX0_STN5_TX_C_DP<82> [130]P5E_PEX0_STN5_RX_DN<82>[130]P5E_PEX0_STN5_TX_C_DN<82> [130]P5E_PEX0_STN5_RX_DP<81>[129]P5E_PEX0_STN5_TX_C_DP<81> [129]P5E_PEX0_STN5_RX_DN<81>[129]P5E_PEX0_STN5_TX_C_DN<81> [129]P5E_PEX0_STN5_RX_DP<80>[129]P5E_PEX0_STN5_TX_C_DP<80> [129]P5E_PEX0_STN5_RX_DN<80>[129]P5E_PEX0_STN5_TX_C_DN<80> [129]SizeDoc NumberRevDate: SheetofReviewerDesignerDepartmentProject
Page TitleCCBU D12 257Tuesday, August 29, 2023<project_name><Designer> GRANDTETON_SWB_20230829012 PEX_0_STN_45(3/11)<Reviewer>SizeDoc NumberRevDate: SheetofReviewerDesignerDepartmentProject
Page TitleCCBU D12 257Tuesday, August 29, 2023<project_name><Designer> GRANDTETON_SWB_20230829012 PEX_0_STN_45(3/11)<Reviewer>SizeDoc NumberRevDate: SheetofReviewerDesignerDepartmentProject
Page TitleCCBU D12 257Tuesday, August 29, 2023<project_name><Designer> GRANDTETON_SWB_20230829012 PEX_0_STN_45(3/11)<Reviewer>C106 DIFF BUS_0.22UFC100 DIFF BUS_0.22UFC2165 DIFF BUS_0.22UFC2178 DIFF BUS_0.22UFC2163 DIFF BUS_0.22UFC107 DIFF BUS_0.22UFC127 DIFF BUS_0.22UFC110 DIFF BUS_0.22UFC112 DIFF BUS_0.22UFC2166 DIFF BUS_0.22UFC2152 DIFF BUS_0.22UF
C105 DIFF BUS_0.22UFC2176 DIFF BUS_0.22UFC114 DIFF BUS_0.22UF
C2156 DIFF BUS_0.22UF
C122 DIFF BUS_0.22UF
C2160 DIFF BUS_0.22UFC2171 DIFF BUS_0.22UFC120 DIFF BUS_0.22UFC2182 DIFF BUS_0.22UFC2169 DIFF BUS_0.22UFC111 DIFF BUS_0.22UFC119 DIFF BUS_0.22UFC2177 DIFF BUS_0.22UFC103 DIFF BUS_0.22UFC104 DIFF BUS_0.22UFC2159 DIFF BUS_0.22UF
C115 DIFF BUS_0.22UFC124 DIFF BUS_0.22UF
C2154 DIFF BUS_0.22UF
C118 DIFF BUS_0.22UFC121 DIFF BUS_0.22UF
C2167 DIFF BUS_0.22UFC108 DIFF BUS_0.22UFC97 DIFF BUS_0.22UFC2173 DIFF BUS_0.22UFC2153 DIFF BUS_0.22UFC2164 DIFF BUS_0.22UFC2175 DIFF BUS_0.22UFC2162 DIFF BUS_0.22UFC98 DIFF BUS_0.22UFC101 DIFF BUS_0.22UFC2179 DIFF BUS_0.22UFC2158 DIFF BUS_0.22UF
C123 DIFF BUS_0.22UF
5/26PEX0ESS26-0A0P-01RXP79D40RXN79C40RXP78B41RXN78A41RXP77D42RXN77C42RXP76B43RXN76A43RXP75D44RXN75C44RXP74B45RXN74A45RXP73D46RXN73C46RXP72B47RXN72A47RXP71C48RXN71C49RXP70K48RXN70K49RXP69L46RXN69L47RXP68M48RXN68M49RXP67N46RXN67N47RXP66P48RXN66P49RXP65R46RXN65R47RXP64T48RXN64T49TXP79J40TXN79H40TXP78G41TXN78F41TXP77J42TXN77H42TXP76G43TXN76F43TXP75J44TXN75H44TXP74G45TXN74F45TXP73J46TXN73H46TXP72G47TXN72F47TXP71E48TXN71E49TXP70H48TXN70H49TXP69L43TXN69L44TXP68M41TXN68M42TXP67N43TXN67N44TXP66P41TXN66P42TXP65R43TXN65R44TXP64T41TXN64T42C113 DIFF BUS_0.22UFC102 DIFF BUS_0.22UFC117 DIFF BUS_0.22UFC126 DIFF BUS_0.22UFC116 DIFF BUS_0.22UFC2170 DIFF BUS_0.22UF6/26PEX0FSS26-0A0P-01RXP95B39RXN95A39RXP94D38RXN94C38RXP93B37RXN93A37RXP92D36RXN92C36RXP91B35RXN91A35RXP90D34RXN90C34RXP89B33RXN89A33RXP88D32RXN88C32RXP87B31RXN87A31RXP86D30RXN86C30RXP85B29RXN85A29RXP84D28RXN84C28RXP83B27RXN83A27RXP82D26RXN82C26RXP81B25RXN81A25RXP80D24RXN80C24TXP95G39TXN95F39TXP94J38TXN94H38TXP93G37TXN93F37TXP92J36TXN92H36TXP91G35TXN91F35TXP90J34TXN90H34TXP89G33TXN89F33TXP88J32TXN88H32TXP87G31TXN87F31TXP86J30TXN86H30TXP85G29TXN85F29TXP84J28TXN84H28TXP83G27TXN83F27TXP82J26TXN82H26TXP81G25TXN81F25TXP80J24TXN80H24
C2155 DIFF BUS_0.22UFC2157 DIFF BUS_0.22UFC2174 DIFF BUS_0.22UF
C128 DIFF BUS_0.22UFC125 DIFF BUS_0.22UFC2181 DIFF BUS_0.22UFC109 DIFF BUS_0.22UFC2180 DIFF BUS_0.22UFC2161 DIFF BUS_0.22UFC2183 DIFF BUS_0.22UFC2168 DIFF BUS_0.22UFC99 DIFF BUS_0.22UFC2172 DIFF BUS_0.22UFP5E_PEX0_STN4_RX_DP<79>P5E_PEX0_STN4_TX_DP<79>P5E_PEX0_STN4_TX_C_DP<79>P5E_PEX0_STN4_RX_DN<79>P5E_PEX0_STN4_TX_DN<79>P5E_PEX0_STN4_TX_C_DN<79>P5E_PEX0_STN4_RX_DP<78>P5E_PEX0_STN4_TX_DP<78>P5E_PEX0_STN4_TX_C_DP<78>P5E_PEX0_STN4_RX_DN<78>P5E_PEX0_STN4_TX_DN<78>P5E_PEX0_STN4_TX_C_DN<78>P5E_PEX0_STN4_RX_DP<77>P5E_PEX0_STN4_TX_DP<77>P5E_PEX0_STN4_TX_C_DP<77>P5E_PEX0_STN4_RX_DN<77>P5E_PEX0_STN4_TX_DN<77>P5E_PEX0_STN4_TX_C_DN<77>P5E_PEX0_STN4_RX_DP<76>P5E_PEX0_STN4_TX_DP<76>P5E_PEX0_STN4_TX_C_DP<76>P5E_PEX0_STN4_RX_DN<76>P5E_PEX0_STN4_TX_DN<76>P5E_PEX0_STN4_TX_C_DN<76>P5E_PEX0_STN4_RX_DP<75>P5E_PEX0_STN4_TX_DP<75>P5E_PEX0_STN4_TX_C_DP<75>P5E_PEX0_STN4_RX_DN<75>P5E_PEX0_STN4_TX_DN<75>P5E_PEX0_STN4_TX_C_DN<75>P5E_PEX0_STN4_RX_DP<74>P5E_PEX0_STN4_TX_DP<74>P5E_PEX0_STN4_TX_C_DP<74>P5E_PEX0_STN4_RX_DN<74>P5E_PEX0_STN4_TX_DN<74>P5E_PEX0_STN4_TX_C_DN<74>P5E_PEX0_STN4_RX_DP<73>P5E_PEX0_STN4_TX_DP<73>P5E_PEX0_STN4_TX_C_DP<73>P5E_PEX0_STN4_RX_DN<73>P5E_PEX0_STN4_TX_DN<73>P5E_PEX0_STN4_TX_C_DN<73>P5E_PEX0_STN4_RX_DP<72>P5E_PEX0_STN4_TX_DP<72>P5E_PEX0_STN4_TX_C_DP<72>P5E_PEX0_STN4_RX_DN<72>P5E_PEX0_STN4_TX_DN<72>P5E_PEX0_STN4_TX_C_DN<72>P5E_PEX0_STN4_RX_DP<71>P5E_PEX0_STN4_TX_DP<71>P5E_PEX0_STN4_TX_C_DP<71>P5E_PEX0_STN4_RX_DN<71>P5E_PEX0_STN4_TX_DN<71>P5E_PEX0_STN4_TX_C_DN<71>P5E_PEX0_STN4_RX_DP<70>P5E_PEX0_STN4_TX_DP<70>P5E_PEX0_STN4_TX_C_DP<70>P5E_PEX0_STN4_RX_DN<70>P5E_PEX0_STN4_TX_DN<70>P5E_PEX0_STN4_TX_C_DN<70>P5E_PEX0_STN4_RX_DP<69>P5E_PEX0_STN4_TX_DP<69>P5E_PEX0_STN4_TX_C_DP<69>P5E_PEX0_STN4_RX_DN<69>P5E_PEX0_STN4_TX_DN<69>P5E_PEX0_STN4_TX_C_DN<69>P5E_PEX0_STN4_RX_DP<68>P5E_PEX0_STN4_TX_DP<68>P5E_PEX0_STN4_TX_C_DP<68>P5E_PEX0_STN4_RX_DN<68>P5E_PEX0_STN4_TX_DN<68>P5E_PEX0_STN4_TX_C_DN<68>P5E_PEX0_STN4_RX_DP<67>P5E_PEX0_STN4_TX_DP<67>P5E_PEX0_STN4_TX_C_DP<67>P5E_PEX0_STN4_RX_DN<67>P5E_PEX0_STN4_TX_DN<67>P5E_PEX0_STN4_TX_C_DN<67>P5E_PEX0_STN4_RX_DP<66>P5E_PEX0_STN4_TX_DP<66>P5E_PEX0_STN4_TX_C_DP<66>P5E_PEX0_STN4_RX_DN<66>P5E_PEX0_STN4_TX_DN<66>P5E_PEX0_STN4_TX_C_DN<66>P5E_PEX0_STN4_RX_DP<65>P5E_PEX0_STN4_TX_DP<65>P5E_PEX0_STN4_TX_C_DP<65>P5E_PEX0_STN4_RX_DN<65>P5E_PEX0_STN4_TX_DN<65>P5E_PEX0_STN4_TX_C_DN<65>P5E_PEX0_STN4_RX_DP<64>P5E_PEX0_STN4_TX_DP<64>P5E_PEX0_STN4_TX_C_DP<64>P5E_PEX0_STN4_RX_DN<64>P5E_PEX0_STN4_TX_DN<64>P5E_PEX0_STN4_TX_C_DN<64>P5E_PEX0_STN5_RX_DP<95>P5E_PEX0_STN5_TX_DP<95>P5E_PEX0_STN5_TX_C_DP<95>P5E_PEX0_STN5_RX_DN<95>P5E_PEX0_STN5_TX_DN<95>P5E_PEX0_STN5_TX_C_DN<95>P5E_PEX0_STN5_RX_DP<94>P5E_PEX0_STN5_TX_DP<94>P5E_PEX0_STN5_TX_C_DP<94>P5E_PEX0_STN5_RX_DN<94>P5E_PEX0_STN5_TX_DN<94>P5E_PEX0_STN5_TX_C_DN<94>P5E_PEX0_STN5_RX_DP<93>P5E_PEX0_STN5_TX_DP<93>P5E_PEX0_STN5_TX_C_DP<93>P5E_PEX0_STN5_RX_DN<93>P5E_PEX0_STN5_TX_DN<93>P5E_PEX0_STN5_TX_C_DN<93>P5E_PEX0_STN5_RX_DP<92>P5E_PEX0_STN5_TX_DP<92>P5E_PEX0_STN5_TX_C_DP<92>P5E_PEX0_STN5_RX_DN<92>P5E_PEX0_STN5_TX_DN<92>P5E_PEX0_STN5_TX_C_DN<92>P5E_PEX0_STN5_RX_DP<91>P5E_PEX0_STN5_TX_DP<91>P5E_PEX0_STN5_TX_C_DP<91>P5E_PEX0_STN5_RX_DN<91>P5E_PEX0_STN5_TX_DN<91>P5E_PEX0_STN5_TX_C_DN<91>P5E_PEX0_STN5_RX_DP<90>P5E_PEX0_STN5_TX_DP<90>P5E_PEX0_STN5_TX_C_DP<90>P5E_PEX0_STN5_RX_DN<90>P5E_PEX0_STN5_TX_DN<90>P5E_PEX0_STN5_TX_C_DN<90>P5E_PEX0_STN5_RX_DP<89>P5E_PEX0_STN5_TX_DP<89>P5E_PEX0_STN5_TX_C_DP<89>P5E_PEX0_STN5_RX_DN<89>P5E_PEX0_STN5_TX_DN<89>P5E_PEX0_STN5_TX_C_DN<89>P5E_PEX0_STN5_RX_DP<88>P5E_PEX0_STN5_TX_DP<88>P5E_PEX0_STN5_TX_C_DP<88>P5E_PEX0_STN5_RX_DN<88>P5E_PEX0_STN5_TX_DN<88>P5E_PEX0_STN5_TX_C_DN<88>P5E_PEX0_STN5_RX_DP<87>P5E_PEX0_STN5_TX_DP<87>P5E_PEX0_STN5_TX_C_DP<87>P5E_PEX0_STN5_RX_DN<87>P5E_PEX0_STN5_TX_DN<87>P5E_PEX0_STN5_TX_C_DN<87>P5E_PEX0_STN5_RX_DP<86>P5E_PEX0_STN5_TX_DP<86>P5E_PEX0_STN5_TX_C_DP<86>P5E_PEX0_STN5_RX_DN<86>P5E_PEX0_STN5_TX_DN<86>P5E_PEX0_STN5_TX_C_DN<86>P5E_PEX0_STN5_RX_DP<85>P5E_PEX0_STN5_TX_DP<85>P5E_PEX0_STN5_TX_C_DP<85>P5E_PEX0_STN5_RX_DN<85>P5E_PEX0_STN5_TX_DN<85>P5E_PEX0_STN5_TX_C_DN<85>P5E_PEX0_STN5_RX_DP<84>P5E_PEX0_STN5_TX_DP<84>P5E_PEX0_STN5_TX_C_DP<84>P5E_PEX0_STN5_RX_DN<84>P5E_PEX0_STN5_TX_DN<84>P5E_PEX0_STN5_TX_C_DN<84>P5E_PEX0_STN5_RX_DP<83>P5E_PEX0_STN5_TX_DP<83>P5E_PEX0_STN5_TX_C_DP<83>P5E_PEX0_STN5_RX_DN<83>P5E_PEX0_STN5_TX_DN<83>P5E_PEX0_STN5_TX_C_DN<83>P5E_PEX0_STN5_RX_DP<82>P5E_PEX0_STN5_TX_DP<82>P5E_PEX0_STN5_TX_C_DP<82>P5E_PEX0_STN5_RX_DN<82>P5E_PEX0_STN5_TX_DN<82>P5E_PEX0_STN5_TX_C_DN<82>P5E_PEX0_STN5_RX_DP<81>P5E_PEX0_STN5_TX_DP<81>P5E_PEX0_STN5_TX_C_DP<81>P5E_PEX0_STN5_RX_DN<81>P5E_PEX0_STN5_TX_DN<81>P5E_PEX0_STN5_TX_C_DN<81>P5E_PEX0_STN5_RX_DP<80>P5E_PEX0_STN5_TX_DP<80>P5E_PEX0_STN5_TX_C_DP<80>P5E_PEX0_STN5_RX_DN<80>P5E_PEX0_STN5_TX_DN<80>P5E_PEX0_STN5_TX_C_DN<80>



5
5
4
4
3
3
2
2
1
1
D D
C C
B B
A A
PEX_0_STN_67(4/11)
P5E_PEX0_STN7_TX_C_DP<112> [124]P5E_PEX0_STN7_TX_C_DN<112> [124]P5E_PEX0_STN7_TX_C_DP<113> [124]P5E_PEX0_STN7_TX_C_DN<113> [124]P5E_PEX0_STN7_TX_C_DP<115> [125]P5E_PEX0_STN7_TX_C_DN<115> [125]P5E_PEX0_STN7_TX_C_DP<114> [125]P5E_PEX0_STN7_TX_C_DN<114> [125]P5E_PEX0_STN7_TX_C_DP<119> [127]P5E_PEX0_STN7_TX_C_DN<119> [127]P5E_PEX0_STN7_TX_C_DP<118> [127]P5E_PEX0_STN7_TX_C_DN<118> [127]P5E_PEX0_STN7_TX_C_DP<117> [126]P5E_PEX0_STN7_TX_C_DN<117> [126]P5E_PEX0_STN7_TX_C_DP<116> [126]P5E_PEX0_STN7_TX_C_DN<116> [126]P5E_PEX0_STN7_TX_C_DP<120> [124]P5E_PEX0_STN7_TX_C_DN<120> [124]P5E_PEX0_STN7_TX_C_DP<121> [124]P5E_PEX0_STN7_TX_C_DN<121> [124]P5E_PEX0_STN7_TX_C_DP<123> [125]P5E_PEX0_STN7_TX_C_DN<123> [125]P5E_PEX0_STN7_TX_C_DP<122> [125]P5E_PEX0_STN7_TX_C_DN<122> [125]P5E_PEX0_STN7_TX_C_DP<127> [127]P5E_PEX0_STN7_TX_C_DN<127> [127]P5E_PEX0_STN7_TX_C_DP<126> [127]P5E_PEX0_STN7_TX_C_DN<126> [127]P5E_PEX0_STN7_TX_C_DP<125> [126]P5E_PEX0_STN7_TX_C_DN<125> [126]P5E_PEX0_STN7_TX_C_DP<124> [126]P5E_PEX0_STN7_TX_C_DN<124> [126]P5E_PEX0_STN7_RX_DP<127>[127]P5E_PEX0_STN7_RX_DN<127>[127]P5E_PEX0_STN7_RX_DP<126>[127]P5E_PEX0_STN7_RX_DN<126>[127]P5E_PEX0_STN7_RX_DP<125>[126]P5E_PEX0_STN7_RX_DN<125>[126]P5E_PEX0_STN7_RX_DP<124>[126]P5E_PEX0_STN7_RX_DN<124>[126]P5E_PEX0_STN7_RX_DP<123>[125]P5E_PEX0_STN7_RX_DN<123>[125]P5E_PEX0_STN7_RX_DP<122>[125]P5E_PEX0_STN7_RX_DN<122>[125]P5E_PEX0_STN7_RX_DP<121>[124]P5E_PEX0_STN7_RX_DN<121>[124]P5E_PEX0_STN7_RX_DP<120>[124]P5E_PEX0_STN7_RX_DN<120>[124]P5E_PEX0_STN7_RX_DP<119>[127]P5E_PEX0_STN7_RX_DN<119>[127]P5E_PEX0_STN7_RX_DP<118>[127]P5E_PEX0_STN7_RX_DN<118>[127]P5E_PEX0_STN7_RX_DP<117>[126]P5E_PEX0_STN7_RX_DN<117>[126]P5E_PEX0_STN7_RX_DP<116>[126]P5E_PEX0_STN7_RX_DN<116>[126]P5E_PEX0_STN7_RX_DP<115>[125]P5E_PEX0_STN7_RX_DN<115>[125]P5E_PEX0_STN7_RX_DP<114>[125]P5E_PEX0_STN7_RX_DN<114>[125]P5E_PEX0_STN7_RX_DP<113>[124]P5E_PEX0_STN7_RX_DN<113>[124]P5E_PEX0_STN7_RX_DP<112>[124]P5E_PEX0_STN7_RX_DN<112>[124]
P5E_PEX0_STN6_RX_DP<111>[129]P5E_PEX0_STN6_TX_C_DP<111> [129]P5E_PEX0_STN6_RX_DN<111>[129]P5E_PEX0_STN6_TX_C_DN<111> [129]P5E_PEX0_STN6_RX_DP<110>[129]P5E_PEX0_STN6_TX_C_DP<110> [129]P5E_PEX0_STN6_RX_DN<110>[129]P5E_PEX0_STN6_TX_C_DN<110> [129]P5E_PEX0_STN6_RX_DP<109>[130]P5E_PEX0_STN6_TX_C_DP<109> [130]P5E_PEX0_STN6_RX_DN<109>[130]P5E_PEX0_STN6_TX_C_DN<109> [130]P5E_PEX0_STN6_RX_DP<108>[130]P5E_PEX0_STN6_TX_C_DP<108> [130]P5E_PEX0_STN6_RX_DN<108>[130]P5E_PEX0_STN6_TX_C_DN<108> [130]P5E_PEX0_STN6_RX_DP<107>[131]P5E_PEX0_STN6_TX_C_DP<107> [131]P5E_PEX0_STN6_RX_DN<107>[131]P5E_PEX0_STN6_TX_C_DN<107> [131]P5E_PEX0_STN6_RX_DP<106>[131]P5E_PEX0_STN6_TX_C_DP<106> [131]P5E_PEX0_STN6_RX_DN<106>[131]P5E_PEX0_STN6_TX_C_DN<106> [131]P5E_PEX0_STN6_RX_DP<105>[132]P5E_PEX0_STN6_TX_C_DP<105> [132]P5E_PEX0_STN6_RX_DN<105>[132]P5E_PEX0_STN6_TX_C_DN<105> [132]P5E_PEX0_STN6_RX_DP<104>[132]P5E_PEX0_STN6_TX_C_DP<104> [132]P5E_PEX0_STN6_RX_DN<104>[132]P5E_PEX0_STN6_TX_C_DN<104> [132]P5E_PEX0_STN6_RX_DP<103>[129]P5E_PEX0_STN6_TX_C_DP<103> [129]P5E_PEX0_STN6_RX_DN<103>[129]P5E_PEX0_STN6_TX_C_DN<103> [129]P5E_PEX0_STN6_RX_DP<102>[129]P5E_PEX0_STN6_TX_C_DP<102> [129]P5E_PEX0_STN6_RX_DN<102>[129]P5E_PEX0_STN6_TX_C_DN<102> [129]P5E_PEX0_STN6_RX_DP<101>[130]P5E_PEX0_STN6_TX_C_DP<101> [130]P5E_PEX0_STN6_RX_DN<101>[130]P5E_PEX0_STN6_TX_C_DN<101> [130]P5E_PEX0_STN6_RX_DP<100>[130]P5E_PEX0_STN6_TX_C_DP<100> [130]P5E_PEX0_STN6_RX_DN<100>[130]P5E_PEX0_STN6_TX_C_DN<100> [130]P5E_PEX0_STN6_RX_DP<99>[131]P5E_PEX0_STN6_TX_C_DP<99> [131]P5E_PEX0_STN6_RX_DN<99>[131]P5E_PEX0_STN6_TX_C_DN<99> [131]P5E_PEX0_STN6_RX_DP<98>[131]P5E_PEX0_STN6_TX_C_DP<98> [131]P5E_PEX0_STN6_RX_DN<98>[131]P5E_PEX0_STN6_TX_C_DN<98> [131]P5E_PEX0_STN6_RX_DP<97>[132]P5E_PEX0_STN6_TX_C_DP<97> [132]P5E_PEX0_STN6_RX_DN<97>[132]P5E_PEX0_STN6_TX_C_DN<97> [132]P5E_PEX0_STN6_RX_DP<96>[132]P5E_PEX0_STN6_TX_C_DP<96> [132]P5E_PEX0_STN6_RX_DN<96>[132]P5E_PEX0_STN6_TX_C_DN<96> [132]
SizeDoc NumberRevDate: SheetofReviewerDesignerDepartmentProject
Page TitleCCBU D13 257Tuesday, August 29, 2023<project_name><Designer> GRANDTETON_SWB_20230829013 PEX_0_STN_67(4/11)<Reviewer>SizeDoc NumberRevDate: SheetofReviewerDesignerDepartmentProject
Page TitleCCBU D13 257Tuesday, August 29, 2023<project_name><Designer> GRANDTETON_SWB_20230829013 PEX_0_STN_67(4/11)<Reviewer>SizeDoc NumberRevDate: SheetofReviewerDesignerDepartmentProject
Page TitleCCBU D13 257Tuesday, August 29, 2023<project_name><Designer> GRANDTETON_SWB_20230829013 PEX_0_STN_67(4/11)<Reviewer>
C165 DIFF BUS_0.22UFC158 DIFF BUS_0.22UFC146 DIFF BUS_0.22UFC161 DIFF BUS_0.22UFC139 DIFF BUS_0.22UF
C183 DIFF BUS_0.22UF
C136 DIFF BUS_0.22UF
C174 DIFF BUS_0.22UFC171 DIFF BUS_0.22UFC148 DIFF BUS_0.22UFC140 DIFF BUS_0.22UFC175 DIFF BUS_0.22UFC177 DIFF BUS_0.22UFC144 DIFF BUS_0.22UFC129 DIFF BUS_0.22UFC156 DIFF BUS_0.22UFC169 DIFF BUS_0.22UFC147 DIFF BUS_0.22UF8/26PEX0HSS26-0A0P-01RXP127B7RXN127A7RXP126D6RXN126C6RXP125B5RXN125A5RXP124D4RXN124C4RXP123B3RXN123A3RXP122C2RXN122C1RXP121K2RXN121K1RXP120L4RXN120L3RXP119M2RXN119M1RXP118N4RXN118N3RXP117P2RXN117P1RXP116R4RXN116R3RXP115T2RXN115T1RXP114U4RXN114U3RXP113V2RXN113V1RXP112W4RXN112W3TXP127G7TXN127F7TXP126J6TXN126H6TXP125G5TXN125F5TXP124J4TXN124H4TXP123G3TXN123F3TXP122E2TXN122E1TXP121H2TXN121H1TXP120L7TXN120L6TXP119M9TXN119M8TXP118N7TXN118N6TXP117P9TXN117P8TXP116R7TXN116R6TXP115T9TXN115T8TXP114U7TXN114U6TXP113V9TXN113V8TXP112W7TXN112W6
C154 DIFF BUS_0.22UFC149 DIFF BUS_0.22UFC180 DIFF BUS_0.22UFC163 DIFF BUS_0.22UFC131 DIFF BUS_0.22UFC166 DIFF BUS_0.22UFC173 DIFF BUS_0.22UFC176 DIFF BUS_0.22UFC185 DIFF BUS_0.22UFC188 DIFF BUS_0.22UFC151 DIFF BUS_0.22UFC162 DIFF BUS_0.22UFC132 DIFF BUS_0.22UFC133 DIFF BUS_0.22UFC130 DIFF BUS_0.22UFC150 DIFF BUS_0.22UFC184 DIFF BUS_0.22UFC153 DIFF BUS_0.22UFC160 DIFF BUS_0.22UFC164 DIFF BUS_0.22UFC168 DIFF BUS_0.22UFC143 DIFF BUS_0.22UFC152 DIFF BUS_0.22UFC142 DIFF BUS_0.22UFC135 DIFF BUS_0.22UFC137 DIFF BUS_0.22UF
C192 DIFF BUS_0.22UFC159 DIFF BUS_0.22UFC141 DIFF BUS_0.22UF
C182 DIFF BUS_0.22UFC189 DIFF BUS_0.22UFC181 DIFF BUS_0.22UFC170 DIFF BUS_0.22UFC145 DIFF BUS_0.22UFC172 DIFF BUS_0.22UFC157 DIFF BUS_0.22UFC190 DIFF BUS_0.22UFC155 DIFF BUS_0.22UFC134 DIFF BUS_0.22UF7/26PEX0GSS26-0A0P-01RXP111D8RXN111C8RXP110B9RXN110A9RXP109D10RXN109C10RXP108B11RXN108A11RXP107D12RXN107C12RXP106B13RXN106A13RXP105D14RXN105C14RXP104B15RXN104A15RXP103D16RXN103C16RXP102B17RXN102A17RXP101D18RXN101C18RXP100B19RXN100A19RXP99D20RXN99C20RXP98B21RXN98A21RXP97D22RXN97C22RXP96B23RXN96A23TXP111J8TXN111H8TXP110G9TXN110F9TXP109J10TXN109H10TXP108G11TXN108F11TXP107J12TXN107H12TXP106G13TXN106F13TXP105J14TXN105H14TXP104G15TXN104F15TXP103J16TXN103H16TXP102G17TXN102F17TXP101J18TXN101H18TXP100G19TXN100F19TXP99J20TXN99H20TXP98G21TXN98F21TXP97J22TXN97H22TXP96G23TXN96F23C186 DIFF BUS_0.22UF
C138 DIFF BUS_0.22UF
C187 DIFF BUS_0.22UFC167 DIFF BUS_0.22UFC179 DIFF BUS_0.22UFC191 DIFF BUS_0.22UFC178 DIFF BUS_0.22UFP5E_PEX0_STN7_TX_DP<112>P5E_PEX0_STN7_TX_C_DP<112>P5E_PEX0_STN7_TX_DN<112>P5E_PEX0_STN7_TX_C_DN<112>P5E_PEX0_STN7_TX_DP<113>P5E_PEX0_STN7_TX_DN<113>P5E_PEX0_STN7_TX_DP<115>P5E_PEX0_STN7_TX_DN<115>P5E_PEX0_STN7_TX_DP<114>P5E_PEX0_STN7_TX_DN<114>P5E_PEX0_STN7_TX_DP<119>P5E_PEX0_STN7_TX_DN<119>P5E_PEX0_STN7_TX_DP<118>P5E_PEX0_STN7_TX_DN<118>P5E_PEX0_STN7_TX_DP<117>P5E_PEX0_STN7_TX_DN<117>P5E_PEX0_STN7_TX_DP<116>P5E_PEX0_STN7_TX_DN<116>P5E_PEX0_STN7_TX_C_DP<113>P5E_PEX0_STN7_TX_C_DN<113>P5E_PEX0_STN7_TX_C_DP<115>P5E_PEX0_STN7_TX_C_DN<115>P5E_PEX0_STN7_TX_C_DP<114>P5E_PEX0_STN7_TX_C_DN<114>P5E_PEX0_STN7_TX_C_DP<119>P5E_PEX0_STN7_TX_C_DN<119>P5E_PEX0_STN7_TX_C_DP<118>P5E_PEX0_STN7_TX_C_DN<118>P5E_PEX0_STN7_TX_C_DP<117>P5E_PEX0_STN7_TX_C_DN<117P5E_PEX0_STN7_TX_C_DP<116>P5E_PEX0_STN7_TX_C_DN<116>P5E_PEX0_STN7_TX_DP<120>P5E_PEX0_STN7_TX_DN<120>P5E_PEX0_STN7_TX_DP<121>P5E_PEX0_STN7_TX_DN<121>P5E_PEX0_STN7_TX_DP<122>P5E_PEX0_STN7_TX_DN<122>P5E_PEX0_STN7_TX_DP<123>P5E_PEX0_STN7_TX_DN<123>P5E_PEX0_STN7_TX_DP<124>P5E_PEX0_STN7_TX_DN<124>P5E_PEX0_STN7_TX_DP<125>P5E_PEX0_STN7_TX_DN<125>P5E_PEX0_STN7_TX_DP<126>P5E_PEX0_STN7_TX_DN<126>P5E_PEX0_STN7_TX_DP<127>P5E_PEX0_STN7_TX_DN<127>P5E_PEX0_STN7_TX_C_DP<120>P5E_PEX0_STN7_TX_C_DN<120>P5E_PEX0_STN7_TX_C_DP<121>P5E_PEX0_STN7_TX_C_DN<121>P5E_PEX0_STN7_TX_C_DP<123>P5E_PEX0_STN7_TX_C_DN<123>P5E_PEX0_STN7_TX_C_DP<122>P5E_PEX0_STN7_TX_C_DN<122>P5E_PEX0_STN7_TX_C_DP<127>P5E_PEX0_STN7_TX_C_DN<127>P5E_PEX0_STN7_TX_C_DP<126>P5E_PEX0_STN7_TX_C_DN<126>P5E_PEX0_STN7_TX_C_DP<125>P5E_PEX0_STN7_TX_C_DN<125>P5E_PEX0_STN7_TX_C_DP<124>P5E_PEX0_STN7_TX_C_DN<124>P5E_PEX0_STN7_RX_DP<127>P5E_PEX0_STN7_RX_DN<127>P5E_PEX0_STN7_RX_DP<126>P5E_PEX0_STN7_RX_DN<126>P5E_PEX0_STN7_RX_DP<125>P5E_PEX0_STN7_RX_DN<125>P5E_PEX0_STN7_RX_DP<124>P5E_PEX0_STN7_RX_DN<124>P5E_PEX0_STN7_RX_DP<123>P5E_PEX0_STN7_RX_DN<123>P5E_PEX0_STN7_RX_DP<122>P5E_PEX0_STN7_RX_DN<122>P5E_PEX0_STN7_RX_DP<121>P5E_PEX0_STN7_RX_DN<121>P5E_PEX0_STN7_RX_DP<120>P5E_PEX0_STN7_RX_DN<120>P5E_PEX0_STN7_RX_DP<119>P5E_PEX0_STN7_RX_DN<119>P5E_PEX0_STN7_RX_DP<118>P5E_PEX0_STN7_RX_DN<118>P5E_PEX0_STN7_RX_DP<117>P5E_PEX0_STN7_RX_DN<117>P5E_PEX0_STN7_RX_DP<116>P5E_PEX0_STN7_RX_DN<116>P5E_PEX0_STN7_RX_DP<115>P5E_PEX0_STN7_RX_DN<115>P5E_PEX0_STN7_RX_DP<114>P5E_PEX0_STN7_RX_DN<114>P5E_PEX0_STN7_RX_DP<113>P5E_PEX0_STN7_RX_DN<113>P5E_PEX0_STN7_RX_DP<112>P5E_PEX0_STN7_RX_DN<112>
P5E_PEX0_STN6_RX_DP<111>P5E_PEX0_STN6_TX_DP<111>P5E_PEX0_STN6_TX_C_DP<111>P5E_PEX0_STN6_RX_DN<111>P5E_PEX0_STN6_TX_DN<111>P5E_PEX0_STN6_TX_C_DN<111>P5E_PEX0_STN6_RX_DP<110>P5E_PEX0_STN6_TX_DP<110>P5E_PEX0_STN6_TX_C_DP<110>P5E_PEX0_STN6_RX_DN<110>P5E_PEX0_STN6_TX_DN<110>P5E_PEX0_STN6_TX_C_DN<110>P5E_PEX0_STN6_RX_DP<109>P5E_PEX0_STN6_TX_DP<109>P5E_PEX0_STN6_TX_C_DP<109>P5E_PEX0_STN6_RX_DN<109>P5E_PEX0_STN6_TX_DN<109>P5E_PEX0_STN6_TX_C_DN<109>P5E_PEX0_STN6_RX_DP<108>P5E_PEX0_STN6_TX_DP<108>P5E_PEX0_STN6_TX_C_DP<108>P5E_PEX0_STN6_RX_DN<108>P5E_PEX0_STN6_TX_DN<108>P5E_PEX0_STN6_TX_C_DN<108>P5E_PEX0_STN6_RX_DP<107>P5E_PEX0_STN6_TX_DP<107>P5E_PEX0_STN6_TX_C_DP<107>P5E_PEX0_STN6_RX_DN<107>P5E_PEX0_STN6_TX_DN<107>P5E_PEX0_STN6_TX_C_DN<107>P5E_PEX0_STN6_RX_DP<106>P5E_PEX0_STN6_TX_DP<106>P5E_PEX0_STN6_TX_C_DP<106>P5E_PEX0_STN6_RX_DN<106>P5E_PEX0_STN6_TX_DN<106>P5E_PEX0_STN6_TX_C_DN<106>P5E_PEX0_STN6_RX_DP<105>P5E_PEX0_STN6_TX_DP<105>P5E_PEX0_STN6_TX_C_DP<105>P5E_PEX0_STN6_RX_DN<105>P5E_PEX0_STN6_TX_DN<105>P5E_PEX0_STN6_TX_C_DN<105>P5E_PEX0_STN6_RX_DP<104>P5E_PEX0_STN6_TX_DP<104>P5E_PEX0_STN6_TX_C_DP<104>P5E_PEX0_STN6_RX_DN<104>P5E_PEX0_STN6_TX_DN<104>P5E_PEX0_STN6_TX_C_DN<104>P5E_PEX0_STN6_RX_DP<103>P5E_PEX0_STN6_TX_DP<103>P5E_PEX0_STN6_TX_C_DP<103>P5E_PEX0_STN6_RX_DN<103>P5E_PEX0_STN6_TX_DN<103>P5E_PEX0_STN6_TX_C_DN<103>P5E_PEX0_STN6_RX_DP<102>P5E_PEX0_STN6_TX_DP<102>P5E_PEX0_STN6_TX_C_DP<102>P5E_PEX0_STN6_RX_DN<102>P5E_PEX0_STN6_TX_DN<102>P5E_PEX0_STN6_TX_C_DN<102>P5E_PEX0_STN6_RX_DP<101>P5E_PEX0_STN6_TX_DP<101>P5E_PEX0_STN6_TX_C_DP<101>P5E_PEX0_STN6_RX_DN<101>P5E_PEX0_STN6_TX_DN<101>P5E_PEX0_STN6_TX_C_DN<101>P5E_PEX0_STN6_RX_DP<100>P5E_PEX0_STN6_TX_DP<100>P5E_PEX0_STN6_TX_C_DP<100>P5E_PEX0_STN6_RX_DN<100>P5E_PEX0_STN6_TX_DN<100>P5E_PEX0_STN6_TX_C_DN<100>P5E_PEX0_STN6_RX_DP<99>P5E_PEX0_STN6_TX_DP<99>P5E_PEX0_STN6_TX_C_DP<99>P5E_PEX0_STN6_RX_DN<99>P5E_PEX0_STN6_TX_DN<99>P5E_PEX0_STN6_TX_C_DN<99>P5E_PEX0_STN6_RX_DP<98>P5E_PEX0_STN6_TX_DP<98>P5E_PEX0_STN6_TX_C_DP<98>P5E_PEX0_STN6_RX_DN<98>P5E_PEX0_STN6_TX_DN<98>P5E_PEX0_STN6_TX_C_DN<98>P5E_PEX0_STN6_RX_DP<97>P5E_PEX0_STN6_TX_DP<97>P5E_PEX0_STN6_TX_C_DP<97>P5E_PEX0_STN6_RX_DN<97>P5E_PEX0_STN6_TX_DN<97>P5E_PEX0_STN6_TX_C_DN<97>P5E_PEX0_STN6_RX_DP<96>P5E_PEX0_STN6_TX_DP<96>P5E_PEX0_STN6_TX_C_DP<96>P5E_PEX0_STN6_RX_DN<96>P5E_PEX0_STN6_TX_DN<96>P5E_PEX0_STN6_TX_C_DN<96>



5
5
4
4
3
3
2
2
1
1
D D
C C
B B
A A
PEX_0_STN_8(5/11)
CLK_100M_DB2000QL_PEX0_S1_R_DP [79]CLK_100M_DB2000QL_PEX0_S1_R_DN [79]CLK_100M_DB800ZL_PEX0_S0_R_DP [83]CLK_100M_DB800ZL_PEX0_S0_R_DN [83]CLK_100M_PEX0_REF_R_DP[82]CLK_100M_PEX0_REF_R_DN[82]RST_PEX0_PERST_R_N[118]RST_PEX0_S3_PERST_R_N [14]RST_PEX0_S1_PERST_R_N [14]RST_PEX0_S0_PERST_R_N [14]RST_PEX0_S1_PERST_R_N[14]RST_PEX0_S0_PERST_R_N[14]RST_PEX0_S3_PERST_R_N[14]CLK_100M_DB800ZL_PEX0_S3_R_DP [84]CLK_100M_DB800ZL_PEX0_S3_R_DN [84]P1V8_PEXP1V8_PEXSizeDoc NumberRevDate: SheetofReviewerDesignerDepartmentProject
Page TitleCCBU D14 257Tuesday, August 29, 2023<project_name><Designer> GRANDTETON_SWB_20230829014 PEX_0_STN_8(5/11)<Reviewer>SizeDoc NumberRevDate: SheetofReviewerDesignerDepartmentProject
Page TitleCCBU D14 257Tuesday, August 29, 2023<project_name><Designer> GRANDTETON_SWB_20230829014 PEX_0_STN_8(5/11)<Reviewer>SizeDoc NumberRevDate: SheetofReviewerDesignerDepartmentProject
Page TitleCCBU D14 257Tuesday, August 29, 2023<project_name><Designer> GRANDTETON_SWB_20230829014 PEX_0_STN_8(5/11)<Reviewer>R6387 33 R0402-0201
9/26PEX0ISS26-0A0P-01RXP143AM48RXN143AM49RXP142AL46RXN142AL47RXP141AK48RXN141AK49RXP140AJ46RXN140AJ47RXP139AH48RXN139AH49RXP138AG46RXN138AG47RXP137AF48RXN137AF49RXP136AE46RXN136AE47RXP135AD48RXN135AD49RXP134AC46RXN134AC47RXP133AB48RXN133AB49RXP132AA46RXN132AA47RXP131Y48RXN131Y49RXP130W46RXN130W47RXP129V48RXN129V49RXP128U46RXN128U47TXP143AM41TXN143AM42TXP142AL43TXN142AL44TXP141AK41TXN141AK42TXP140AJ43TXN140AJ44TXP139AH41TXN139AH42TXP138AG43TXN138AG44TXP137AF41TXN137AF42TXP136AE43TXN136AE44TXP135AD41TXN135AD42TXP134AC43TXN134AC44TXP133AB41TXN133AB42TXP132AA43TXN132AA44TXP131Y41TXN131Y42TXP130W43TXN130W44TXP129V41TXN129V42TXP128U43TXN128U44C41850.1UF10%16VC0402-0201U425CSN74LVC3G34DCTR6284U425ASN74LVC3G34DCTR1784R436010K1% R0402-0201<Part Number>NIR63894.7KR0402-02015%R6388 33 R0402-0201R6386 33 R0402-020110/26PEX0JSS26-0A0P-01S7_PCE_PERST_NU38S6_PCE_PERST_NR38S5_PCE_PERST_NU39S4_PCE_PERST_NR39S3_PCE_PERST_NP38S2_PCE_PERST_NT39S1_PCE_PERST_NP39S0_PCE_PERST_NT38SYS_REF_CLK_PAA2SYS_REF_CLK_NAA1S7_PCE_REF_CLK_PAJ2S7_PCE_REF_CLK_NAJ1S6_PCE_REF_CLK_PAH5S6_PCE_REF_CLK_NAH4S5_PCE_REF_CLK_PAG2S5_PCE_REF_CLK_NAG1S4_PCE_REF_CLK_PAF5S4_PCE_REF_CLK_NAF4S3_PCE_REF_CLK_PAE2S3_PCE_REF_CLK_NAE1S2_PCE_REF_CLK_PAD5S2_PCE_REF_CLK_NAD4S1_PCE_REF_CLK_PAC2S1_PCE_REF_CLK_NAC1S0_PCE_REF_CLK_PAB5S0_PCE_REF_CLK_NAB4CLKREQ_INIT_NM13U425BSN74LVC3G34DCTR3584CLK_100M_DB2000QL_PEX0_S1_R_DPCLK_100M_DB2000QL_PEX0_S1_R_DNCLK_100M_DB800ZL_PEX0_S0_R_DPCLK_100M_DB800ZL_PEX0_S0_R_DNCLK_100M_PEX0_REF_R_DPCLK_100M_PEX0_REF_R_DNIRQ_PEX0_CLKREQ_INT_NRST_PEX0_PERST_R_NRST_PEX0_S3_PERST_NRST_PEX0_S3_PERST_R_NRST_PEX0_S1_PERST_NRST_PEX0_S1_PERST_R_NRST_PEX0_S0_PERST_NRST_PEX0_S0_PERST_R_NRST_PEX0_S1_PERST_R_NRST_PEX0_S0_PERST_R_NRST_PEX0_S3_PERST_R_NCLK_100M_DB800ZL_PEX0_S3_R_DPCLK_100M_DB800ZL_PEX0_S3_R_DN



5
5
4
4
3
3
2
2
1
1
D D
C C
B B
A A
Add Test Point
PEX_0_GPIO(6/11)
DVT_CHANGEPEX0_DBG_MODE4 [15]PEX0_DBG_MODE3 [15]PEX0_DBG_MODE2 [15]PEX0_DBG_MODE1 [15]PEX0_DBG_MODE0 [15]PEX0_DBG_SEL1 [15]PEX0_DBG_SEL0 [15]PEX0_MODE_SEL12 [15]PEX0_MODE_SEL11 [15]PEX0_MODE_SEL10 [15]PEX0_MODE_SEL9 [15]PEX0_MODE_SEL8 [15]PEX0_MODE_SEL7 [15]PEX0_MODE_SEL6 [15]PEX0_MODE_SEL5 [15]PEX0_MODE_SEL4 [15]PEX0_MODE_SEL3 [15]PEX0_MODE_SEL2 [15,121]PEX0_MODE_SEL1 [15,121]PEX0_MODE_SEL0 [15]PEX0_PCA9555_INT_R_N [72]PEX0_DBG_MODE4[15]PEX0_DBG_MODE3[15]PEX0_DBG_MODE2[15]PEX0_DBG_MODE1[15]PEX0_DBG_MODE0[15]PEX0_DBG_SEL1[15]PEX0_DBG_SEL0[15]PEX0_MODE_SEL12[15]PEX0_MODE_SEL11[15]PEX0_MODE_SEL10[15]PEX0_MODE_SEL9[15]PEX0_MODE_SEL8[15]PEX0_MODE_SEL7[15]PEX0_MODE_SEL6[15]PEX0_MODE_SEL5[15]PEX0_MODE_SEL4[15]PEX0_MODE_SEL3[15]PEX0_MODE_SEL2[15,121]PEX0_MODE_SEL1[15,121]PEX0_MODE_SEL0[15]PEX0_SYS_ERR_R_N [15]RST_PEX0_SYS_N [118]UART_PEX0_SDB_TX [67]UART_PEX0_SDB_BUF_RX [67]UART_PEX0_CLI_TX [68]UART_PEX0_CLI_BUF_RX [68]PEX0_SYS_ERR_R_N[15]PEX0_SYS_ERR_FPGA [118]
P1V8_PEXP1V8_PEXP1V8_PEXP1V8_PEXP3V3_AUXP3V3_LEDP1V8_PEX
P1V8_PEXP1V8_PEXSizeDoc NumberRevDate: SheetofReviewerDesignerDepartmentProject
Page TitleCCBU D15 257Tuesday, August 29, 2023<project_name><Designer> GRANDTETON_SWB_20230829015 PEX_0_GPIO(6/11)<Reviewer>SizeDoc NumberRevDate: SheetofReviewerDesignerDepartmentProject
Page TitleCCBU D15 257Tuesday, August 29, 2023<project_name><Designer> GRANDTETON_SWB_20230829015 PEX_0_GPIO(6/11)<Reviewer>SizeDoc NumberRevDate: SheetofReviewerDesignerDepartmentProject
Page TitleCCBU D15 257Tuesday, August 29, 2023<project_name><Designer> GRANDTETON_SWB_20230829015 PEX_0_GPIO(6/11)<Reviewer>
R11581KR0402-02011%NIR11871KR0402-02011%R11881KR0402-02011%R11181KR0402-02011%NIR11891KR0402-02011%R11591KR0402-02011%NIR12431KR0402-02011%NIR61534.7KR0402-02011%  
R11191KR0402-02011%NI
R12584.75K R0402-02011%
R11611KR0402-02011%R125610K R0402-02015%
R11261KR0402-02011%NI11/26PEX0KSS26-0A0P-01DBG_MODE4AW34DBG_MODE3AW26DBG_MODE2AW30DBG_MODE1L13DBG_MODE0L12DBG_SEL1M19DBG_SEL0L18MODE_SEL12AW32MODE_SEL11AW31MODE_SEL10AV32MODE_SEL9AV28MODE_SEL8AW29MODE_SEL7AV26MODE_SEL6AV31MODE_SEL5AW25MODE_SEL4AW28MODE_SEL3AV27MODE_SEL2AV25MODE_SEL1AW38MODE_SEL0AW27AVG_TRST_LM18AVG_TCKM15AVG_TDIL17AVG_TDOL19AVG_TMSM20AVG_PAD_TRI_LL16AVG_TR_TCKL20AVG_ATPG_MODE_LL15SHPC_INT_NAV29SPARE7M27SPARE6L28SPARE5L25SPARE4M25SPARE3L32SPARE2L27SPARE1L30SPARE0M26DFT_IDDTM16ADCTEMP_VINP0Y39ADCTEMP_VINP1AA39SYS_ERROR_NAV30SYS_PWR_ON_RST_NM17SDB_TXAL39SDB_RXAK39UART_TXAJ38UART_RXAK38
R11641KR0402-02011%NIR125410KR0402-02015%R12421KR0402-02011%NIR12401KR0402-02011%NIR12381KR0402-02011%NIR12361KR0402-02011%NIR125710K R0402-02015%R125310KR0402-02015%R12041KR0402-02011%R125110KR0402-02015%12/26PEX0LSS26-0A0P-01GPIO31AV13GPIO30AV12GPIO29AW12GPIO28AW16GPIO27AV17GPIO26AV16GPIO25AW13GPIO24AW17GPIO23AV14GPIO21AW14GPIO20AW18GPIO19AV19GPIO18AV15GPIO17AW15GPIO16AW19GPIO15AV36GPIO14AU39GPIO13AW35GPIO12AJ39GPIO11AN39GPIO10AM38GPIO9AR39GPIO8AP39GPIO7AR38GPIO6AP38GPIO5AM39GPIO4AU38GPIO3AV39GPIO2AT39GPIO1AV34GPIO0AW39GPIO63M24GPIO62L23GPIO61M23GPIO60M22GPIO59L22GPIO58L24GPIO57AV23GPIO56AW22GPIO55AV22GPIO54AV21GPIO53M32GPIO52L31GPIO51M34GPIO50N39GPIO49L29GPIO48M33GPIO47AW21GPIO46AW23GPIO45L33GPIO44M31GPIO43M30GPIO42L35GPIO41AN38GPIO40AL38GPIO39AW37GPIO38AV37GPIO37AV38GPIO36AV35GPIO35AW36GPIO34AV33GPIO33AT38GPIO32AW33EXT_GPIO_LATCH_NL37GPIO22AV18
R11691KR0402-02011%NIR1255 0 R0402-02015%R12341KR0402-02011%R124910KR0402-02015%R124710KR0402-02015%R11661KR0402-02011%NIR11601KR0402-02011%NIR11521KR0402-02011%NI
R417910KR0402-02015%NIQ12ABSS138BKS<Part Number>S11G12D16
R12161KR0402-02011%
R5727 33 R0402-02011%
R12151KR0402-02011%NIR12031KR0402-02011%R124410K 1%R0402-0201R395410KR0402-02015%R11531KR0402-02011%R11991KR0402-02011%R11651KR0402-02011%
R4180 1K R0402-02011%NI
R11961KR0402-02011%R11271KR0402-02011%NI R12331KR0402-02011%NI
Q12BBSS138BKS<Part Number>D23G25S24
R11541KR0402-02011%
R12594.75K R0402-02011%R11951KR0402-02011%
D1LED_BLUEACR124510K 1%R0402-0201<Part Number>R11931KR0402-02011%R11921KR0402-02011%NIR11551KR0402-02011%NI
R126049.9<Part Number>R0402-02011%1/16W
R11911KR0402-02011%NIR11901KR0402-02011%R12411KR0402-02011%NIR12391KR0402-02011%NIR12371KR0402-02011%NIR11561KR0402-02011%NIR124610KR0402-02015%R12351KR0402-02011%NIR11111KR0402-02011%
R12614.7KR0402-02011%  
R10861KR0402-02011%NI R11571KR0402-02011%NIR125210KR0402-02015%R11671KR0402-02011% R125010KR0402-02015%R124810KR0402-02015%R11681KR0402-02011%R10931KR0402-02011%NIR11861KR0402-02011%PEX0_DBG_MODE4PEX0_DBG_MODE3PEX0_DBG_MODE2PEX0_DBG_MODE1PEX0_DBG_MODE0PEX0_DBG_SEL1PEX0_DBG_SEL0PEX0_MODE_SEL12PEX0_MODE_SEL11PEX0_MODE_SEL10PEX0_MODE_SEL9PEX0_MODE_SEL8PEX0_MODE_SEL7PEX0_MODE_SEL6PEX0_MODE_SEL5PEX0_MODE_SEL4PEX0_MODE_SEL3PEX0_MODE_SEL2PEX0_MODE_SEL1PEX0_MODE_SEL0PEX0_DBG_MODE4PEX0_DBG_MODE3PEX0_DBG_MODE2PEX0_DBG_MODE1PEX0_DBG_MODE0PEX0_DBG_SEL1PEX0_DBG_SEL0PEX0_MODE_SEL12PEX0_MODE_SEL11PEX0_MODE_SEL10PEX0_MODE_SEL9PEX0_MODE_SEL8PEX0_MODE_SEL7PEX0_MODE_SEL6PEX0_MODE_SEL5PEX0_MODE_SEL4PEX0_MODE_SEL3PEX0_MODE_SEL2PEX0_MODE_SEL1PEX0_MODE_SEL0PEX0_SPARE7PEX0_SPARE6PEX0_SPARE5PEX0_SPARE4PEX0_SPARE3PEX0_SPARE2PEX0_SPARE1PEX0_SPARE0PEX0_DFT_IDDTRST_PEX0_SYS_NUART_PEX0_SDB_TXUART_PEX0_SDB_BUF_RXUART_PEX0_CLI_TXUART_PEX0_CLI_BUF_RXPEX0_SYS_ERR_NTP_PEX0_TMSTP_PEX0_TRST_LTP_PEX0_TDOTP_PEX0_TDITP_PEX0_TCKPU_PEX0_PAD_TRI_LPU_PEX0_TR_TCKPU_PEX0_ATPG_MODE_LPEX0_SYS_ERR_N_GLED_PEX0_SYS_ERR_NPEX0_SYS_ERR_3V3_NPEX0_ADCTEMP_VINP0PEX0_ADCTEMP_VINP1
PEX0_EXT_GPIO_LATCH_N



5
5
4
4
3
3
2
2
1
1
D D
C C
B B
A A
FLASH SOCKET
PEX 1.8V PortPCA9555 3.3V Port
To FPGA
PEX VER. A0
PEX VER. B0
Pull UP 3V3
CO-LAYOUT
PEX_0_FLASH(7/11)
SEL_FLASH_PEX0_BUF_R[63,88]SPI_PEX0_CS_MUX_N[16]SPI_PEX0_CLK_MUX[16]SPI_PEX0_CLK_R [16]SPI_BIC1_CLK_LS01_R1 [63]SPI_PEX0_CS_R_N [16]SPI_BIC1_CS0_LS01_R1_N [63]SPI_PEX0_CLK_R[16]SPI_PEX0_CS_R_N[16]SPI_PEX0_CS_MUX_N[16]SPI_PEX0_CLK_MUX[16]SPI_BIC1_MISO_LS01_R1 [63]SPI_BIC1_MOSI_LS01_R1 [63]SPI_PEX0_SDIO1_MUX[16]SPI_PEX0_SDIO0_MUX[16]SPI_PEX0_SDIO0_MUX[16]SPI_PEX0_SDIO1_MUX [16]SPI_PEX0_SDIO1_R [16]SPI_PEX0_SDIO0_R [16]SPI_PEX0_SDIO3_R[16]SPI_PEX0_SDIO2_R[16]SPI_PEX0_SDIO1_R[16]SPI_PEX0_SDIO0_R[16]SPI_PEX0_SDIO2_R[16]SPI_PEX0_SDIO3_R[16]I2C_PEX0_HOST_R_SDA [16]SMB_PEX0_PCA9555_SDA[72]SMB_PEX0_PCA9555_SCL[72]I2C_PEX0_HOST_R_SCL [16]
I2C_PEX0_HOST_R_SDA [16]I2C_PEX0_HOST_R_SCL [16]
SMB_PEX0_FPGA_SCL[115]SMB_PEX0_FPGA_SDA[115]
SMB_PEX0_SDA [95]SMB_PEX0_SCL [95]
PWRGD_P1V8_PEX_R[29,42,55,95,118,233]
SPI_PEX0_RST_R_N[16]SPI_PEX0_RST_R_N [16]P3V3_AUX
P1V8_PEXP1V8_PEXP3V3_AUXP1V8_PEX
P1V8_PEXP1V8_PEXP1V8_PEX
SizeDoc NumberRevDate: SheetofReviewerDesignerDepartmentProject
Page TitleCCBU D16 257Tuesday, August 29, 2023<project_name><Designer> GRANDTETON_SWB_20230829016 PEX_0_FLASH(7/11)<Reviewer>SizeDoc NumberRevDate: SheetofReviewerDesignerDepartmentProject
Page TitleCCBU D16 257Tuesday, August 29, 2023<project_name><Designer> GRANDTETON_SWB_20230829016 PEX_0_FLASH(7/11)<Reviewer>SizeDoc NumberRevDate: SheetofReviewerDesignerDepartmentProject
Page TitleCCBU D16 257Tuesday, August 29, 2023<project_name><Designer> GRANDTETON_SWB_20230829016 PEX_0_FLASH(7/11)<Reviewer>
R3293 0 R0402-02015%
C27550.1UF10%16VC0402-0201JPEX0SCONN16_ACASPI006P07<Part Number>VCC2HOLD_N1CS_N7WP_N9SI15SCK16VSS10SO8NC3PO24PO15PO06PO311PO412PO513PO614R61644.75K1%R0402-0201<Part Number>R40142K1/16W1%<Part Number>R0402-0201R3891 33 R0402-02011%R3873 0 R0402-02015%NIU313PCA9617ADP<Part Number>EN5VCCA1VCCB8SCLA2SDAA3SDAB6SCLB7GND4 R34371K<Part Number>R0402-02011%
R6659 33 R0402-02011%14/26PEX0NSS26-0A0P-01MXSTEST_0_TST1AN36MXSTEST_0_TST0AP36MXSTEST_1_TST1AT36MXSTEST_1_TST0AR36MXSTEST_2_TST1AP14MXSTEST_2_TST0AN14MXSTEST_3_TST1U36MXSTEST_3_TST0P36MXSTEST_4_TST1T36MXSTEST_4_TST0R36MXSTEST_5_TST1T14MXSTEST_5_TST0U14MXSTEST_6_TST1AA35MXSTEST_6_TST0AB35CLKOBSAK5CLKOBS_NAK4R3881 0 R0402-02015%NI13/26PEX0MSS26-0A0P-01SPI0_CS_N1AJ8SPI0_CS_N0AK7SPI0_FLASH_CS_NAJ7SPI0_RST_NAG7SPI0_CLKAH7SPI0_SDIO3AH8SPI0_SDIO2AG8SPI0_SDIO1AF8SPI0_SDIO0AF7SPI1_CS_N1AB7SPI1_CS_N0AB8SPI1_RST_NAD7SPI1_CLKAE7SPI1_SDIO3AE8SPI1_SDIO2AC8SPI1_SDIO1AD8SPI1_SDIO0AC7SIO_BLINKL26I2C0_SDAM39I2C0_SCLM35I2C1_SDAM37I2C1_SCLL38I2C2_SDAL36I2C2_SCLM36I2C3_SDAM38I2C3_SCLL34I2C_S_SDAL39I2C_S_SCLN38SHPC_SDAM28SHPC_SCLM29U65PI3CH480QEXS1E#15YA4YB7D113YC9YD12D014C110C011B16B05A13A02VCC16GND8 R6660 0 R0402-02015%
R34381K<Part Number>R0402-02011%
R3882 0 R0402-02015%NI
R3892 0 R0402-02015%
JPEX0_FW1<Part Number>1
R3874 0 R0402-02015%NIR3880 0 R0402-02015%
R3894 0 R0402-02015%
R40132K1/16W1%R0402-0201C27810.1UF10%16VC0402-0201R3442 4.7K R0402-02011%R3435 0 R0402-02015%R6805 33 R0402-02011%R3446 0 R0402-02015%U317W25Q256JWFIQNI<Part Number>HOLD#||RESET_IO3#1VCC2RESET#3NC14NC25NC36CS#7DO_IO18CLK16DI_IO015NC714NC613NC512NC411GND10WP_N_IO29 R3450 0 R0402-02015%
R3885 0 R0402-02015%R3294 0 R0402-02015%R3447 0 R0402-02015%R3893 33 R0402-02011%R61571KR0402-02011%
R3449 0 R0402-02015%
R3886 0 R0402-02015%R3434 0 R0402-02015%
R34391K<Part Number>R0402-02011%NI
R3883 0 R0402-02015%R3292 0 R0402-02015%R6806 33 R0402-02011%R3445 0 R0402-02015%C22160.1UF10%16VC0402-0201R3884 0 R0402-02015%
R38784.7KR0402-02015%R34411K<Part Number>R0402-02011%NI
R3295 0 R0402-02015%C22170.1UF10%16VC0402-0201R61631KR0402-02011%NI<Part Number>C27540.1UF10%16VC0402-0201
R6162 0 R0402-02015%R3448 0 R0402-02015%R38774.7KR0402-02015%R3947 0 R0402-02015%R3879 33 R0402-02011%
R394310K1%R0402-0201<Part Number>SPI_PEX0_CS_MUX_NSPI_PEX0_SDIO1_MUXSPI_PEX0_SDIO1_RSPI_BIC1_MISO_LS01_R1SPI_PEX0_CS_R_NSPI_BIC1_CS0_LS01_R1_NSEL_FLASH_PEX0_BUF_RSPI_PEX0_CS_NSPI_PEX0_CLKSPI_PEX0_SDIO1SPI_PEX0_SDIO0SPI_PEX0_CS_R_NSPI_PEX0_CLK_RSPI_PEX0_SDIO1_RSPI_PEX0_SDIO0_RSPI_PEX0_SDIO0_MUXSPI_PEX0_CLK_MUXSPI_PEX0_SDIO0_RSPI_BIC1_MOSI_LS01_R1SPI_PEX0_CLK_RSPI_BIC1_CLK_LS01_R1SPI_MUX_PEX0_EN_NSPI_PEX0_SDIO3_RSPI_PEX0_SDIO3SPI_PEX0_SDIO2_RSPI_PEX0_SDIO2SPI_PEX0_SDIO1_MUX_RSPI_PEX0_SDIO1_MUXSPI_PEX0_SDIO3_RSPI_PEX0_SDIO3_R1SPI_PEX0_CS_MUX_NSPI_PEX0_CS_MUX_R_NSPI_PEX0_SDIO2_RSPI_PEX0_SDIO2_R1SPI_PEX0_SDIO0_MUXSPI_PEX0_SDIO0_MUX_RSPI_PEX0_CLK_MUXSPI_PEX0_CLK_MUX_RSPI_PEX0_CS_MUX_R_NSPI_PEX0_SDIO3_R1SPI_PEX0_SDIO2_R1SMB_PEX0_HOST_LS_SCLSMB_PEX0_HOST_LS_SDA
I2C0_PEX0_SDAI2C0_PEX0_SCLI2C0_PEX0_SHPC_SDAI2C0_PEX0_SHPC_SCLI2C_PEX0_HOST_SDAI2C_PEX0_HOST_SCLSMB_PEX0_SLAVE_SDASMB_PEX0_SLAVE_SCLPU_PEX0_SIO_BLINK
PWRGD_P1V8_PEX0_RSPI_PEX0_CLK_MUX_RSPI_PEX0_CS_MUX_R_NSPI_PEX0_SDIO3_R1SPI_PEX0_SDIO2_R1SPI_PEX0_SDIO0_MUX_RSPI_PEX0_SDIO1_MUX_R
SPI_PEX0_RST_R_NSPI_PEX0_RST_NSPI_PEX0_RST_R_NSPI_PEX0_RST_R_NSPI_PEX0_RST_R_N
SMB_PEX0_SLAVE1_SCLSMB_PEX0_SLAVE1_SDASMB_PEX0_R_SCLSMB_PEX0_R_SDA



5
5
4
4
3
3
2
2
1
1
D D
C C
B B
A A
PEX0 P1V25_SERDES_VDDHTXDECOUPLING INFO.
Item QTY.
BGA BALLs 41
1000pF(0201) Caps
0.1uF(0201) Caps
1uF(0201) Caps
10uF(0603) Caps
11
25
5
2
PEX0 P1V25_SERDES_VDDHPLLDECOUPLING INFO.
Item QTY.
41BGA BALLs
1000pF(0201) Caps 11
0.1uF(0201) Caps 25
1uF(0201) Caps 5
10uF(0603) Caps 2
1
1
8
4
QTY.
13
PEX0 P1V8_SWDECOUPLING INFO.
10uF(0603) Caps
1uF(0201) Caps
0.1uF(0201) Caps
1000pF(0201) Caps
BGA BALLs
Item
1
1
8
4
QTY.
9
PEX0 P1V8_VDDADECOUPLING INFO.
10uF(0603) Caps
1uF(0201) Caps
0.1uF(0201) Caps
1000pF(0201) Caps
BGA BALLs
Item
Add Test Point
PEX_0_PWR Cap_1(8/11)
VSENSE_P0V8_PEX0_SKT_VSEN[223]VSENSE_P0V8_PEX0_SKT_VRTN[223]
P1V25_PEX0P1V25_SERDES_VDDPLL_PEX0P1V8_VDDA_PEX0P0V8_PEX0P0V8_PEX0P1V25_PEX0P1V25_SERDES_VDDPLL_PEX0
P0V8_SERDES_VDDA_PEX0P0V8_SERDES_VDDA_PEX0P1V8_PEXP1V8_VDDA_PEX0P1V8_PEXPCEPLL7_VDDA18_PEX0PCEPLL6_VDDA18_PEX0PCEPLL5_VDDA18_PEX0PCEPLL4_VDDA18_PEX0PCEPLL3_VDDA18_PEX0PCEPLL2_VDDA18_PEX0PCEPLL1_VDDA18_PEX0PCEPLL0_VDDA18_PEX0SYSPLL_VDDA18_PEX0
SizeDoc NumberRevDate: SheetofReviewerDesignerDepartmentProject
Page TitleCCBU D17 257Tuesday, August 29, 2023<project_name><Designer> GRANDTETON_SWB_20230829017 PEX_0_PWR Cap_1(8/11)<Reviewer>SizeDoc NumberRevDate: SheetofReviewerDesignerDepartmentProject
Page TitleCCBU D17 257Tuesday, August 29, 2023<project_name><Designer> GRANDTETON_SWB_20230829017 PEX_0_PWR Cap_1(8/11)<Reviewer>SizeDoc NumberRevDate: SheetofReviewerDesignerDepartmentProject
Page TitleCCBU D17 257Tuesday, August 29, 2023<project_name><Designer> GRANDTETON_SWB_20230829017 PEX_0_PWR Cap_1(8/11)<Reviewer>C29830.1UFC020110%6.3VC29750.1UFC020110%6.3VC29670.1UFC020110%6.3V
C29041UFC020120%4VC29730.1UFC020110%6.3VC29941000PFC02015%16V
C29310.1UFC020110%6.3VC29760.1UFC020110%6.3VC29571000PFC02015%16VC29521000PFC02015%16VC30120.1UFC020110%6.3V
C29181000PFC02015%16VC29151000PFC02015%16VC29200.1UFC020110%6.3VC29380.1UFC020110%6.3VC290210UFC060320%6.3VC29081UFC020120%4VC29700.1UFC020110%6.3VC29820.1UFC020110%6.3VC29220.1UFC020110%6.3VC299010UFC060320%6.3VC29581000PFC02015%16V17/26PEX0QSS26-0A0P-01VDDA_Y16Y16VDDA_Y17Y17VDDA_Y18Y18VDDA_Y19Y19VDDA_Y20Y20VDDA_Y21Y21VDDA_Y22Y22VDDA_Y23Y23VDDA_Y24Y24VDDA_Y25Y25VDDA_Y26Y26VDDA_Y27Y27VDDA_Y28Y28VDDA_Y29Y29VDDA_Y30Y30VDDA_Y31Y31VDDA_Y32Y32VDDA_Y33Y33VDDA_AB16AB16VDDA_AB17AB17VDDA_AB18AB18VDDA_AB19AB19VDDA_AB20AB20VDDA_AB21AB21VDDA_AB22AB22VDDA_AB23AB23VDDA_AB24AB24VDDA_AB25AB25VDDA_AB26AB26VDDA_AB27AB27VDDA_AB28AB28VDDA_AB29AB29VDDA_AB30AB30VDDA_AB31AB31VDDA_AB32AB32VDDA_AB33AB33VDDA_AD32AD32VDDA_AD33AD33VDDA_AD34AD34VDDA_AE33AE33VDDA_AE34AE34VDDA_AF32AF32VDDA_AF33AF33VDDA_AF34AF34VDDA_AH16AH16VDDA_AH17AH17VDDA_AH18AH18VDDA_AH19AH19VDDA_AH20AH20VDDA_AH21AH21VDDA_AH22AH22VDDA_AH23AH23VDDA_AH24AH24VDDA_AH25AH25VDDA_AH26AH26VDDA_AH27AH27VDDA_AH28AH28VDDA_AH29AH29VDDA_AH30AH30VDDA_AH31AH31VDDA_AH32AH32VDDA_AH33AH33VDDA_AK16AK16VDDA_AK17AK17VDDA_AK18AK18VDDA_AK19AK19VDDA_AK20AK20VDDA_AK21AK21VDDA_AK22AK22VDDA_AK23AK23VDDA_AK24AK24VDDA_AK25AK25VDDA_AK26AK26VDDA_AK27AK27VDDA_AK28AK28VDDA_AK29AK29VDDA_AK30AK30VDDA_AK31AK31VDDA_AK32AK32VDDA_AK33AK33C29810.1UFC020110%6.3VC29491UFC020120%4VC30140.1UFC020110%6.3VC29990.1UFC020110%6.3V
C29390.1UFC020110%6.3VC29400.1UFC020110%6.3VC29410.1UFC020110%6.3VC29710.1UFC020110%6.3VC29770.1UFC020110%6.3VC30080.1UFC020110%6.3V
C29141000PFC02015%16VC29650.1UFC020110%6.3VC29951000PFC02015%16VC30130.1UFC020110%6.3VC30110.1UFC020110%6.3V
C29430.1UFC020110%6.3VC29911000PFC02015%16VC29840.1UFC020110%6.3VC29561000PFC02015%16VC29230.1UFC020110%6.3VC29780.1UFC020110%6.3V
C29071UFC020120%4VC29121000PFC02015%16V
C30070.1UFC020110%6.3VC30010.1UFC020110%6.3VC29611000PFC02015%16VC29260.1UFC020110%6.3VC29210.1UFC020110%6.3VC29660.1UFC020110%6.3V
C29061UFC020120%4VC29131000PFC02015%16VC29720.1UFC020110%6.3VC29620.1UFC020110%6.3VC294410UFC060320%6.3VC294510UFC060320%6.3VC29250.1UFC020110%6.3V
C29981000PFC02015%16VC29511000PFC02015%16VC29800.1UFC020110%6.3VC29591000PFC02015%16VC29300.1UFC020110%6.3VC298810UFC060320%6.3V
C29171000PFC02015%16VC29640.1UFC020110%6.3VC29871UFC020120%4V
C29111000PFC02015%16V
C29971000PFC02015%16VC29680.1UFC020110%6.3VC29790.1UFC020110%6.3VC29630.1UFC020110%6.3V
C290310UFC060320%6.3VC29420.1UFC020110%6.3VC29190.1UFC020110%6.3V16/26PEX0PSS26-0A0P-01PCEPLL7_VDDA18AJ13PCEPLL6_VDDA18AH12PCEPLL5_VDDA18AG13PCEPLL4_VDDA18AF12PCEPLL3_VDDA18AE13PCEPLL2_VDDA18AD12PCEPLL1_VDDA18AB12PCEPLL0_VDDA18AA13SYSPLL_VDDA18AC13EDM_VDDW38VDDQ_EFUSEAM12VDD18_V35V35VDD18_W35W35VDD18_Y12Y12VDD18_Y35Y35VDD18_AE10AE10VDD18_AF10AF10VDD18_AH10AH10VDD18_AJ10AJ10VDD18_AK10AK10VDD18_AK12AK12VDD18_AK35AK35VDD18_AL35AL35VDD18_AM35AM35VDDA18_T35T35VDDA18_V14V14VDDA18_AA10AA10VDDA18_AA34AA34VDDA18_AA37AA37VDDA18_AB10AB10VDDA18_AC10AC10VDDA18_AM14AM14VDDA18_AP35AP35VDDA_SENSEAL15VSSA_SENSEAL14VDD_SENSEV39VSS_SENSEW39C30020.1UFC020110%6.3VC29690.1UFC020110%6.3VC29290.1UFC020110%6.3VC29860.1UFC020110%6.3VC29921000PFC02015%16V
C29350.1UFC020110%6.3V
C30050.1UFC020110%6.3VC29551000PFC02015%16VC29051UFC020120%4V
C29891UFC020120%4VC29850.1UFC020110%6.3VC29461UFC020120%4VC29961000PFC02015%16V
C29161000PFC02015%16VC29501UFC020120%4VC29280.1UFC020110%6.3VC29270.1UFC020110%6.3VC29091000PFC02015%16VC29320.1UFC020110%6.3V
C30000.1UFC020110%6.3V
C29101000PFC02015%16V
C29931000PFC02015%16VC30030.1UFC020110%6.3VC30060.1UFC020110%6.3VC29471UFC020120%4VC30040.1UFC020110%6.3V
C29330.1UFC020110%6.3VC29240.1UFC020110%6.3VC29531000PFC02015%16VC30090.1UFC020110%6.3V
C29360.1UFC020110%6.3VC29370.1UFC020110%6.3V15/26PEX0O
SS26-0A0P-01
VDD125_V16V16VDD125_V17V17VDD125_V18V18VDD125_V19V19VDD125_V20V20VDD125_V21V21VDD125_V22V22VDD125_V23V23VDD125_V24V24VDD125_V25V25VDD125_V26V26VDD125_V27V27VDD125_V28V28VDD125_V29V29VDD125_V30V30VDD125_V31V31VDD125_V32V32VDD125_V33V33VDD125_AC36AC36VDD125_AD36AD36VDD125_AE36AE36VDD125_AF36AF36VDD125_AG36AG36VDD125_AM16AM16VDD125_AM17AM17VDD125_AM18AM18VDD125_AM19AM19VDD125_AM20AM20VDD125_AM21AM21VDD125_AM22AM22VDD125_AM23AM23VDD125_AM24AM24VDD125_AM25AM25VDD125_AM26AM26VDD125_AM27AM27VDD125_AM28AM28VDD125_AM29AM29VDD125_AM30AM30VDD125_AM31AM31VDD125_AM32AM32VDD125_AM33AM33VDD_Y14Y14VDD_AA15AA15VDD_AB14AB14VDD_AC15AC15VDD_AC17AC17VDD_AC19AC19VDD_AC21AC21VDD_AC23AC23VDD_AC25AC25VDD_AC27AC27VDD_AC29AC29VDD_AC31AC31VDD_AC33AC33VDD_AD14AD14VDD_AD16AD16VDD_AD18AD18VDD_AD20AD20VDD_AD22AD22VDD_AD24AD24VDD_AD26AD26VDD_AD28AD28VDD_AD30AD30VDD_AE15AE15VDD_AE17AE17VDD_AE19AE19VDD_AE21AE21VDD_AE23AE23
VDDA125_T16T16VDDA125_T17T17VDDA125_T18T18VDDA125_T19T19VDDA125_T20T20VDDA125_T21T21VDDA125_T22T22VDDA125_T23T23VDDA125_T24T24VDDA125_T25T25VDDA125_T26T26VDDA125_T27T27VDDA125_T28T28VDDA125_T29T29VDDA125_T30T30VDDA125_T31T31VDDA125_T32T32VDDA125_T33T33VDDA125_AC38AC38VDDA125_AD38AD38VDDA125_AE38AE38VDDA125_AF38AF38VDDA125_AG38AG38VDDA125_AP16AP16VDDA125_AP17AP17VDDA125_AP18AP18VDDA125_AP19AP19VDDA125_AP20AP20VDDA125_AP21AP21VDDA125_AP22AP22VDDA125_AP23AP23VDDA125_AP24AP24VDDA125_AP25AP25VDDA125_AP26AP26VDDA125_AP28AP28VDDA125_AP29AP29VDDA125_AP30AP30VDDA125_AP31AP31VDDA125_AP32AP32VDDA125_AP33AP33VDD_AE25AE25VDD_AE27AE27VDD_AE29AE29VDD_AE31AE31VDD_AF14AF14VDD_AF16AF16VDD_AF18AF18VDD_AF20AF20VDD_AF22AF22VDD_AF24AF24VDD_AF26AF26VDD_AF28AF28VDD_AF30AF30VDD_AG15AG15VDD_AG17AG17VDD_AG19AG19VDD_AG21AG21VDD_AG23AG23VDD_AG25AG25VDD_AG27AG27VDD_AG29AG29VDD_AG31AG31VDD_AG33AG33VDD_AH14AH14VDD_AJ15AJ15VDD_AK14AK14VDDA125_AP27AP27C29601000PFC02015%16VC30100.1UFC020110%6.3VC29740.1UFC020110%6.3VC29481UFC020120%4VC29011000PFC02015%16VC29340.1UFC020110%6.3VC29541000PFC02015%16VTP_PEX0_VDDQ_EFUSE



5
5
4
4
3
3
2
2
1
1
D D
C C
B B
A A
33
Item
0.1uF(0201) Caps
PEX0 P0V8DECOUPLING INFO.
17
3
1000pF(0201) Caps
10uF(0603) Caps
QTY.
4
BGA BALLs
1uF(0201) Caps
53
1uF(0201) Caps
QTY.
4
0.1uF(0201) Caps
80
6
1000pF(0201) Caps
PEX0 P0V8_SERDES_VDDADECOUPLING INFO.
44
BGA BALLs
10uF(0603) Caps
30
Item
PEX_0_PWR Cap_2(9/11)
P0V8_SERDES_VDDA_PEX0P0V8_PEX0
SizeDoc NumberRevDate: SheetofReviewerDesignerDepartmentProject
Page TitleCCBU D18 257Tuesday, August 29, 2023<project_name><Designer> GRANDTETON_SWB_20230829018 PEX_0_PWR Cap_2(9/11)<Reviewer>SizeDoc NumberRevDate: SheetofReviewerDesignerDepartmentProject
Page TitleCCBU D18 257Tuesday, August 29, 2023<project_name><Designer> GRANDTETON_SWB_20230829018 PEX_0_PWR Cap_2(9/11)<Reviewer>SizeDoc NumberRevDate: SheetofReviewerDesignerDepartmentProject
Page TitleCCBU D18 257Tuesday, August 29, 2023<project_name><Designer> GRANDTETON_SWB_20230829018 PEX_0_PWR Cap_2(9/11)<Reviewer>
C11061UFC020120%4VC11410.1UFC020110%6.3VC11821000PFC02015%16VC11741000PFC02015%16VC11440.1UFC020110%6.3VC11861000PFC02015%16VC11340.1UFC020110%6.3VC12100.1UFC020110%6.3V
C11390.1UFC020110%6.3VC12170.1UFC020110%6.3V
C11031UFC020120%4VC11691000PFC02015%16VC11220.1UFC020110%6.3VC115810UFC060320%6.3VC12360.1UFC020110%6.3VC11901000PFC02015%16VC11520.1UFC020110%6.3VC12340.1UFC020110%6.3V
C11470.1UFC020110%6.3VC11051UFC020120%4VC11831000PFC02015%16VC11091000PFC02015%16V
C12020.1UFC020110%6.3V
C11200.1UFC020110%6.3VC115710UFC060320%6.3VC11801000PFC02015%16VC12130.1UFC020110%6.3VC11510.1UFC020110%6.3VC12180.1UFC020110%6.3VC116010UFC060320%6.3VC11911000PFC02015%16VC11931000PFC02015%16VC12090.1UFC020110%6.3VC11621UFC020120%4VC11921000PFC02015%16VC11871000PFC02015%16VC11671000PFC02015%16V
19/26PEX0S
SS26-0A0P-01
VSS_F30F30VSS_F32F32VSS_F34F34VSS_F38F38VSS_F40F40VSS_F42F42VSS_F44F44VSS_F46F46VSS_F48F48VSS_F49F49VSS_G1G1VSS_G2G2VSS_G4G4VSS_G6G6VSS_G8G8VSS_G10G10VSS_G12G12VSS_G14G14VSS_G16G16VSS_G18G18VSS_G20G20VSS_G22G22VSS_G24G24VSS_G26G26VSS_G28G28VSS_G30G30VSS_G32G32VSS_G34G34VSS_G36G36VSS_G38G38VSS_G40G40VSS_G42G42VSS_G44G44VSS_G46G46VSS_G48G48VSS_G49G49VSS_H3H3VSS_H5H5VSS_H7H7VSS_H9H9VSS_H11H11VSS_H13H13VSS_H15H15VSS_H17H17VSS_H19H19VSS_H21H21VSS_H23H23VSS_H25H25VSS_H27H27VSS_H29H29VSS_H31H31VSS_H33H33VSS_H35H35VSS_H37H37VSS_H39H39VSS_H41H41VSS_H43H43VSS_H45H45VSS_H47H47VSS_J1J1VSS_J2J2VSS_J3J3VSS_J5J5VSS_J7J7VSS_J9J9VSS_J11J11VSS_J13J13VSS_J15J15VSS_J17J17VSS_J19J19VSS_J21J21VSS_J23J23VSS_J25J25VSS_J27J27VSS_J29J29VSS_J31J31VSS_J33J33VSS_J35J35VSS_J37J37
VSS_J39J39VSS_J41J41VSS_J43J43VSS_J45J45VSS_J47J47VSS_J48J48VSS_J49J49VSS_K3K3VSS_K4K4VSS_K5K5VSS_K6K6VSS_K7K7VSS_K8K8VSS_K9K9VSS_K10K10VSS_K11K11VSS_K12K12VSS_K13K13VSS_K14K14VSS_K15K15VSS_K16K16VSS_K17K17VSS_K18K18VSS_K19K19VSS_K20K20VSS_K21K21VSS_K22K22VSS_K23K23VSS_K24K24VSS_K25K25VSS_K26K26VSS_K27K27VSS_K28K28VSS_K29K29VSS_K30K30VSS_K31K31VSS_K32K32VSS_K33K33VSS_K34K34VSS_K35K35VSS_K36K36VSS_K37K37VSS_K38K38VSS_K39K39VSS_K40K40VSS_K41K41VSS_K42K42VSS_K43K43VSS_K44K44VSS_K45K45VSS_K46K46VSS_K47K47VSS_L1L1VSS_L2L2VSS_L5L5VSS_L8L8VSS_L9L9VSS_L10L10VSS_L11L11VSS_L14L14VSS_L21L21VSS_L40L40VSS_L41L41VSS_L42L42VSS_L45L45VSS_L48L48VSS_L49L49VSS_M3M3VSS_M4M4VSS_M5M5VSS_M6M6VSS_M7M7VSS_M10M10VSS_M11M11VSS_M12M12VSS_M14M14VSS_M21M21VSS_M40M40VSS_M43M43VSS_M44M44
VSS_F36F36C11380.1UFC020110%6.3VC11121000PFC02015%16VC11811000PFC02015%16VC12390.1UFC020110%6.3V
C11550.1UFC020110%6.3VC12380.1UFC020110%6.3VC11990.1UFC020110%6.3V
C11360.1UFC020110%6.3VC11761000PFC02015%16VC11251000PFC02015%16VC11731000PFC02015%16VC11420.1UFC020110%6.3VC11460.1UFC020110%6.3VC11611UFC020120%4VC11190.1UFC020110%6.3V
C12210.1UFC020110%6.3VC12310.1UFC020110%6.3VC11781000PFC02015%16VC12370.1UFC020110%6.3VC11970.1UFC020110%6.3VC12040.1UFC020110%6.3VC11701000PFC02015%16VC12070.1UFC020110%6.3VC11881000PFC02015%16VC12280.1UFC020110%6.3VC12190.1UFC020110%6.3V
C11321000PFC02015%16VC11540.1UFC020110%6.3VC12080.1UFC020110%6.3VC12000.1UFC020110%6.3VC12320.1UFC020110%6.3V
C11241000PFC02015%16V
C12200.1UFC020110%6.3V
C11180.1UFC020110%6.3VC11490.1UFC020110%6.3VC11841000PFC02015%16VC11430.1UFC020110%6.3VC11711000PFC02015%16VC12030.1UFC020110%6.3VC11771000PFC02015%16V
C11041UFC020120%4V
C12270.1UFC020110%6.3VC11651UFC020120%4VC12240.1UFC020110%6.3V
C11140.1UFC020110%6.3VC11851000PFC02015%16VC11500.1UFC020110%6.3VC11400.1UFC020110%6.3VC12160.1UFC020110%6.3VC11791000PFC02015%16VC11071000PFC02015%16VC110210UFC060320%6.3V
C12140.1UFC020110%6.3V
C11311000PFC02015%16V
C12290.1UFC020110%6.3VC11641UFC020120%4VC11661UFC020120%4VC12060.1UFC020110%6.3VC12050.1UFC020110%6.3VC12330.1UFC020110%6.3V
C11530.1UFC020110%6.3VC11681000PFC02015%16VC11980.1UFC020110%6.3V
C11111000PFC02015%16VC11370.1UFC020110%6.3VC115910UFC060320%6.3VC12230.1UFC020110%6.3VC12260.1UFC020110%6.3V
C11210.1UFC020110%6.3VC11131000PFC02015%16V18/26PEX0R
SS26-0A0P-01
VSS_A2A2VSS_A4A4VSS_A6A6VSS_A8A8VSS_A10A10VSS_A12A12VSS_A14A14VSS_A16A16VSS_A18A18VSS_A20A20VSS_A22A22VSS_A24A24VSS_A26A26VSS_A28A28VSS_A30A30VSS_A32A32VSS_A34A34VSS_A36A36VSS_A38A38VSS_A40A40VSS_A42A42VSS_A44A44VSS_A46A46VSS_A48A48VSS_B1B1VSS_B2B2VSS_B4B4VSS_B6B6VSS_B8B8VSS_B10B10VSS_B12B12VSS_B14B14VSS_B16B16VSS_B18B18VSS_B20B20VSS_B22B22VSS_B24B24VSS_B26B26VSS_B28B28VSS_B30B30VSS_B32B32VSS_B34B34VSS_B36B36VSS_B38B38VSS_B40B40VSS_B42B42VSS_B44B44VSS_B46B46VSS_B48B48VSS_B49B49VSS_C3C3VSS_C5C5VSS_C7C7VSS_C9C9VSS_C11C11VSS_C13C13VSS_C15C15VSS_C17C17VSS_C19C19VSS_C21C21VSS_C23C23VSS_C25C25VSS_C27C27VSS_C29C29VSS_C31C31VSS_C33C33VSS_C35C35VSS_C37C37VSS_C39C39VSS_C41C41VSS_C43C43VSS_C45C45VSS_C47C47VSS_D1D1VSS_D2D2VSS_D3D3VSS_D5D5VSS_D7D7VSS_D9D9VSS_D11D11
VSS_D13D13VSS_D15D15VSS_D17D17VSS_D19D19VSS_D21D21VSS_D23D23VSS_D25D25VSS_D27D27VSS_D29D29VSS_D31D31VSS_D33D33VSS_D35D35VSS_D37D37VSS_D39D39VSS_D41D41VSS_D43D43VSS_D45D45VSS_D47D47VSS_D48D48VSS_D49D49VSS_E3E3VSS_E4E4VSS_E6E6VSS_E7E7VSS_E8E8VSS_E9E9VSS_E10E10VSS_E11E11VSS_E12E12VSS_E13E13VSS_E14E14VSS_E15E15VSS_E16E16VSS_E17E17VSS_E18E18VSS_E19E19VSS_E20E20VSS_E21E21VSS_E22E22VSS_E23E23VSS_E24E24VSS_E25E25VSS_E26E26VSS_E27E27VSS_E28E28VSS_E29E29VSS_E30E30VSS_E31E31VSS_E32E32VSS_E33E33VSS_E34E34VSS_E35E35VSS_E36E36VSS_E37E37VSS_E38E38VSS_E40E40VSS_E41E41VSS_E42E42VSS_E43E43VSS_E44E44VSS_E45E45VSS_E46E46VSS_E47E47VSS_F1F1VSS_F2F2VSS_F4F4VSS_F6F6VSS_F8F8VSS_F10F10VSS_F12F12VSS_F14F14VSS_F16F16VSS_F18F18VSS_F20F20VSS_F22F22VSS_F24F24VSS_F26F26VSS_F28F28VSS_E39E39VSS_E5E5C11961000PFC02015%16VC11450.1UFC020110%6.3VC12010.1UFC020110%6.3V
C11350.1UFC020110%6.3VC11301000PFC02015%16VC11751000PFC02015%16VC11721000PFC02015%16VC11291000PFC02015%16VC11101000PFC02015%16V
C12220.1UFC020110%6.3V
C11081000PFC02015%16VC11891000PFC02015%16V
C110110UFC060320%6.3VC11170.1UFC020110%6.3VC11631UFC020120%4VC12350.1UFC020110%6.3V
C11160.1UFC020110%6.3VC11231000PFC02015%16V
C12300.1UFC020110%6.3VC12110.1UFC020110%6.3V
C11271000PFC02015%16VC110010UFC060320%6.3VC11281000PFC02015%16VC11560.1UFC020110%6.3VC12400.1UFC020110%6.3VC11951000PFC02015%16VC11330.1UFC020110%6.3VC11480.1UFC020110%6.3VC11261000PFC02015%16VC11150.1UFC020110%6.3VC11941000PFC02015%16VC12120.1UFC020110%6.3VC12250.1UFC020110%6.3VC12150.1UFC020110%6.3V



5
5
4
4
3
3
2
2
1
1
D D
C C
B B
A A
Imax: 0.04A Imax: 0.04A Imax: 0.04A
Imax: 0.04A Imax: 0.04A Imax: 0.04A
Imax: 0.04AImax: 0.04A
PEX_0_PWR Cap_3(10/11)
Imax: 0.2A Imax: 0.1A
PCEPLL0_VDDA18_PEX0P1V8_PLL0_PEX0P1V8_PLL0_PEX0PCEPLL1_VDDA18_PEX0P1V8_PLL0_PEX0PCEPLL2_VDDA18_PEX0P1V8_PLL0_PEX0PCEPLL3_VDDA18_PEX0P1V8_PLL0_PEX0PCEPLL4_VDDA18_PEX0P1V8_PLL0_PEX0PCEPLL5_VDDA18_PEX0P1V8_PLL0_PEX0PCEPLL6_VDDA18_PEX0P1V8_PLL0_PEX0PCEPLL7_VDDA18_PEX0P1V8_PLL0_PEX0SYSPLL_VDDA18_PEX0P1V8_PLL0_PEX0P1V8_VDDA_PEX0PCEPLL5_VDDA18_PEX0_RPCEPLL4_VDDA18_PEX0_RPCEPLL3_VDDA18_PEX0_RPCEPLL0_VDDA18_PEX0_RPCEPLL1_VDDA18_PEX0_RPCEPLL2_VDDA18_PEX0_RPCEPLL6_VDDA18_PEX0_RPCEPLL7_VDDA18_PEX0_RSYSPLL_VDDA18_PEX0_RP1V8_VDDA_PEX0_RSizeDoc NumberRevDate: SheetofReviewerDesignerDepartmentProject
Page TitleCCBU D19 257Tuesday, August 29, 2023<project_name><Designer> GRANDTETON_SWB_20230829019 PEX_0_PWR Cap_3(10/11)<Reviewer>SizeDoc NumberRevDate: SheetofReviewerDesignerDepartmentProject
Page TitleCCBU D19 257Tuesday, August 29, 2023<project_name><Designer> GRANDTETON_SWB_20230829019 PEX_0_PWR Cap_3(10/11)<Reviewer>SizeDoc NumberRevDate: SheetofReviewerDesignerDepartmentProject
Page TitleCCBU D19 257Tuesday, August 29, 2023<project_name><Designer> GRANDTETON_SWB_20230829019 PEX_0_PWR Cap_3(10/11)<Reviewer>
C30290.1UFC020110%6.3VC301922UFC0603_H4020%6.3VC303522UFC0603_H4020%6.3VC30641UFC020120%4V
C30260.1UFC020110%6.3VC301722UFC0603_H4020%6.3V
C30661UFC020120%4V
C30201UFC020120%4VC30521UFC020120%4VC30401UFC020120%4VL91HCB2012KF-601T20<Part Number>21L89HCB2012KF-601T20<Part Number>21C303910UFC060320%6.3VC30440.1UFC020110%6.3VR45600.51C30410.1UFC020110%6.3VC30221UFC020120%4VC30251UFC020120%4VR45620.51C30341UFC020120%4VR45590.51C303322UFC0603_H4020%6.3VC305810UFC060320%6.3VC305122UFC0603_H4020%6.3VC306522UFC0603_H4020%6.3V
C303147UFC30431UFC020120%4VC30591UFC020120%4VC306710UFC060320%6.3V
C303047UF
C30681UFC020120%4V
C302410UFC060320%6.3V
C307347UFL96HCB2012KF-601T20<Part Number>21 C30600.1UFC020110%6.3VC30690.1UFC020110%6.3V
L90HCB2012KF-601T20<Part Number>21L93HCB2012KF-601T20<Part Number>21R45610.51C302710UFC060320%6.3V
C30720.1UFC020110%6.3V
C30230.1UFC020110%6.3VC303247UFC304210UFC060320%6.3VC30711UFC020120%4VR45640.51C30281UFC020120%4V
L97HCB2012KF-601T20<Part Number>21L94HCB2012KF-601T20<Part Number>21 R45630.51C305510UFC060320%6.3VC307447UF
C304847UFL88HCB2012KF-601T20<Part Number>21C30181UFC020120%4VC304510UFC060320%6.3VR45650.51R45670.51C307010UFC060320%6.3V
C30161UFC020120%4VC30461UFC020120%4VR45580.51C302110UFC060320%6.3V
R45660.51C304947UFC306147UFC30561UFC020120%4VC306322UFC0603_H4020%6.3V
L92HCB2012KF-601T20<Part Number>21 C30470.1UFC020110%6.3VC305322UFC0603_H4020%6.3VC30570.1UFC020110%6.3VC30381UFC020120%4VC305047UFC306247UF
C301522UFC0603_H4020%6.3VC30541UFC020120%4VC303722UFC0603_H4020%6.3VL95HCB2012KF-601T20<Part Number>21C30361UFC020120%4V



5
5
4
4
3
3
2
2
1
1
D D
C C
B B
A A
PEX_0_GND(11/11) SizeDoc NumberRevDate: SheetofReviewerDesignerDepartmentProject
Page TitleCCBU D20 257Tuesday, August 29, 2023<project_name><Designer> GRANDTETON_SWB_20230829020 PEX_0_GND(11/11)<Reviewer>SizeDoc NumberRevDate: SheetofReviewerDesignerDepartmentProject
Page TitleCCBU D20 257Tuesday, August 29, 2023<project_name><Designer> GRANDTETON_SWB_20230829020 PEX_0_GND(11/11)<Reviewer>SizeDoc NumberRevDate: SheetofReviewerDesignerDepartmentProject
Page TitleCCBU D20 257Tuesday, August 29, 2023<project_name><Designer> GRANDTETON_SWB_20230829020 PEX_0_GND(11/11)<Reviewer>
23/26PEX0W
SS26-0A0P-01
VSS_AJ36AJ36VSS_AJ37AJ37VSS_AJ40AJ40VSS_AJ41AJ41VSS_AJ42AJ42VSS_AJ45AJ45VSS_AJ48AJ48VSS_AJ49AJ49VSS_AK1AK1VSS_AK2AK2VSS_AK3AK3VSS_AK6AK6VSS_AK8AK8VSS_AK9AK9VSS_AK11AK11VSS_AK13AK13VSS_AK15AK15VSS_AK34AK34VSS_AK36AK36VSS_AK37AK37VSS_AK40AK40VSS_AK43AK43VSS_AK44AK44VSS_AK45AK45VSS_AK46AK46VSS_AK47AK47VSS_AL1AL1VSS_AL2AL2VSS_AL3AL3VSS_AL4AL4VSS_AL5AL5VSS_AL6AL6VSS_AL7AL7VSS_AL8AL8VSS_AL9AL9VSS_AL10AL10VSS_AL11AL11VSS_AL12AL12VSS_AL13AL13VSS_AL16AL16VSS_AL17AL17VSS_AL18AL18VSS_AL19AL19VSS_AL20AL20VSS_AL21AL21VSS_AL22AL22VSS_AL23AL23VSS_AL24AL24VSS_AL25AL25VSS_AL26AL26VSS_AL27AL27VSS_AL28AL28VSS_AL29AL29VSS_AL30AL30VSS_AL31AL31VSS_AL32AL32VSS_AL33AL33VSS_AL34AL34VSS_AL36AL36VSS_AL37AL37VSS_AL40AL40VSS_AL41AL41VSS_AL42AL42VSS_AL45AL45VSS_AL48AL48VSS_AL49AL49VSS_AM3AM3VSS_AM4AM4VSS_AM5AM5VSS_AM6AM6VSS_AM7AM7VSS_AM10AM10VSS_AM11AM11VSS_AM13AM13VSS_AM15AM15VSS_AM34AM34VSS_AM36AM36VSS_AM37AM37VSS_AM40AM40VSS_AM43AM43
VSS_AM44AM44VSS_AM45AM45VSS_AM46AM46VSS_AM47AM47VSS_AN1AN1VSS_AN2AN2VSS_AN5AN5VSS_AN8AN8VSS_AN9AN9VSS_AN10AN10VSS_AN11AN11VSS_AN12AN12VSS_AN13AN13VSS_AN15AN15VSS_AN16AN16VSS_AN17AN17VSS_AN18AN18VSS_AN19AN19VSS_AN20AN20VSS_AN21AN21VSS_AN22AN22VSS_AN23AN23VSS_AN24AN24VSS_AN25AN25VSS_AN26AN26VSS_AN27AN27VSS_AN28AN28VSS_AN29AN29VSS_AN30AN30VSS_AN31AN31VSS_AN32AN32VSS_AN33AN33VSS_AN34AN34VSS_AN35AN35VSS_AN37AN37VSS_AN40AN40VSS_AN41AN41VSS_AN42AN42VSS_AN45AN45VSS_AN48AN48VSS_AN49AN49VSS_AP3AP3VSS_AP4AP4VSS_AP5AP5VSS_AP6AP6VSS_AP7AP7VSS_AP10AP10VSS_AP11AP11VSS_AP12AP12VSS_AP13AP13VSS_AP15AP15VSS_AP34AP34VSS_AP37AP37VSS_AP40AP40VSS_AP43AP43VSS_AP44AP44VSS_AP45AP45VSS_AP46AP46VSS_AP47AP47VSS_AR1AR1VSS_AR2AR2VSS_AR5AR5VSS_AR8AR8VSS_AR9AR9VSS_AR10AR10VSS_AR11AR11VSS_AR12AR12VSS_AR13AR13VSS_AR14AR14VSS_AR15AR15VSS_AR16AR16VSS_AR17AR17VSS_AR18AR18VSS_AR19AR19VSS_AR20AR20VSS_AR21AR21VSS_AR22AR22VSS_AR23AR23VSS_AR24AR24VSS_AR25AR25
25/26PEX0Y
SS26-0A0P-01
VSS_AY39AY39VSS_AY40AY40VSS_AY41AY41VSS_AY42AY42VSS_AY43AY43VSS_AY44AY44VSS_AY45AY45VSS_AY46AY46VSS_AY47AY47VSS_BA1BA1VSS_BA2BA2VSS_BA3BA3VSS_BA5BA5VSS_BA7BA7VSS_BA9BA9VSS_BA11BA11VSS_BA13BA13VSS_BA15BA15VSS_BA17BA17VSS_BA19BA19VSS_BA21BA21VSS_BA23BA23VSS_BA25BA25VSS_BA27BA27VSS_BA29BA29VSS_BA31BA31VSS_BA33BA33VSS_BA35BA35VSS_BA37BA37VSS_BA39BA39VSS_BA41BA41VSS_BA43BA43VSS_BA45BA45VSS_BA47BA47VSS_BA48BA48VSS_BA49BA49VSS_BB3BB3VSS_BB5BB5VSS_BB7BB7VSS_BB9BB9VSS_BB11BB11VSS_BB13BB13VSS_BB15BB15VSS_BB17BB17VSS_BB19BB19VSS_BB21BB21VSS_BB23BB23VSS_BB25BB25VSS_BB27BB27VSS_BB29BB29VSS_BB31BB31VSS_BB33BB33VSS_BB35BB35VSS_BB37BB37VSS_BB39BB39VSS_BB41BB41VSS_BB43BB43VSS_BB45BB45VSS_BB47BB47VSS_BC1BC1VSS_BC2BC2VSS_BC4BC4VSS_BC6BC6VSS_BC8BC8VSS_BC10BC10VSS_BC12BC12VSS_BC14BC14VSS_BC16BC16VSS_BC18BC18VSS_BC20BC20VSS_BC22BC22VSS_BC24BC24VSS_BC26BC26VSS_BC28BC28VSS_BC30BC30VSS_BC32BC32VSS_BC34BC34VSS_BC36BC36VSS_BC38BC38VSS_BC40BC40
VSS_BC42BC42VSS_BC44BC44VSS_BC46BC46VSS_BC48BC48VSS_BC49BC49VSS_BD1BD1VSS_BD2BD2VSS_BD4BD4VSS_BD6BD6VSS_BD8BD8VSS_BD10BD10VSS_BD12BD12VSS_BD14BD14VSS_BD16BD16VSS_BD18BD18VSS_BD20BD20VSS_BD22BD22VSS_BD24BD24VSS_BD26BD26VSS_BD28BD28VSS_BD30BD30VSS_BD32BD32VSS_BD34BD34VSS_BD36BD36VSS_BD38BD38VSS_BD40BD40VSS_BD42BD42VSS_BD44BD44VSS_BD46BD46VSS_BD48BD48VSS_BD49BD49VSS_BE3BE3VSS_BE4BE4VSS_BE5BE5VSS_BE6BE6VSS_BE7BE7VSS_BE8BE8VSS_BE9BE9VSS_BE10BE10VSS_BE11BE11VSS_BE12BE12VSS_BE13BE13VSS_BE14BE14VSS_BE15BE15VSS_BE16BE16VSS_BE17BE17VSS_BE18BE18VSS_BE19BE19VSS_BE20BE20VSS_BE21BE21VSS_BE22BE22VSS_BE23BE23VSS_BE24BE24VSS_BE25BE25VSS_BE26BE26VSS_BE27BE27VSS_BE28BE28VSS_BE29BE29VSS_BE30BE30VSS_BE31BE31VSS_BE32BE32VSS_BE33BE33VSS_BE34BE34VSS_BE35BE35VSS_BE36BE36VSS_BE37BE37VSS_BE38BE38VSS_BE39BE39VSS_BE40BE40VSS_BE41BE41VSS_BE42BE42VSS_BE43BE43VSS_BE44BE44VSS_BE45BE45VSS_BE46BE46VSS_BE47BE47VSS_BF1BF1VSS_BF2BF2VSS_BF3BF3VSS_BF5BF5
22/26PEX0V
SS26-0A0P-01
VSS_AC28AC28VSS_AC30AC30VSS_AC32AC32VSS_AC34AC34VSS_AC35AC35VSS_AC37AC37VSS_AC39AC39VSS_AC40AC40VSS_AC41AC41VSS_AC42AC42VSS_AC45AC45VSS_AC48AC48VSS_AC49AC49VSS_AD1AD1VSS_AD2AD2VSS_AD3AD3VSS_AD6AD6VSS_AD9AD9VSS_AD10AD10VSS_AD11AD11VSS_AD15AD15VSS_AD17AD17VSS_AD19AD19VSS_AD21AD21VSS_AD23AD23VSS_AD25AD25VSS_AD27AD27VSS_AD29AD29VSS_AD31AD31VSS_AD35AD35VSS_AD37AD37VSS_AD39AD39VSS_AD40AD40VSS_AD43AD43VSS_AD44AD44VSS_AD45AD45VSS_AD46AD46VSS_AD47AD47VSS_AE3AE3VSS_AE4AE4VSS_AE5AE5VSS_AE6AE6VSS_AE9AE9VSS_AE11AE11VSS_AE14AE14VSS_AE16AE16VSS_AE18AE18VSS_AE20AE20VSS_AE22AE22VSS_AE24AE24VSS_AE26AE26VSS_AE28AE28VSS_AE30AE30VSS_AE32AE32VSS_AE35AE35VSS_AE37AE37VSS_AE39AE39VSS_AE40AE40VSS_AE41AE41VSS_AE42AE42VSS_AE45AE45VSS_AE48AE48VSS_AE49AE49VSS_AF1AF1VSS_AF2AF2VSS_AF3AF3VSS_AF6AF6VSS_AF9AF9VSS_AF11AF11VSS_AF15AF15VSS_AF17AF17VSS_AF19AF19VSS_AF21AF21VSS_AF23AF23VSS_AF25AF25VSS_AF27AF27VSS_AF29AF29VSS_AF31AF31VSS_AF35AF35VSS_AF37AF37
VSS_AF39AF39VSS_AF40AF40VSS_AF43AF43VSS_AF44AF44VSS_AF45AF45VSS_AF46AF46VSS_AF47AF47VSS_AG3AG3VSS_AG4AG4VSS_AG5AG5VSS_AG6AG6VSS_AG9AG9VSS_AG10AG10VSS_AG11AG11VSS_AG14AG14VSS_AG16AG16VSS_AG18AG18VSS_AG20AG20VSS_AG22AG22VSS_AG24AG24VSS_AG26AG26VSS_AG28AG28VSS_AG30AG30VSS_AG32AG32VSS_AG34AG34VSS_AG35AG35VSS_AG37AG37VSS_AG39AG39VSS_AG40AG40VSS_AG41AG41VSS_AG42AG42VSS_AG45AG45VSS_AG48AG48VSS_AG49AG49VSS_AH1AH1VSS_AH2AH2VSS_AH3AH3VSS_AH6AH6VSS_AH9AH9VSS_AH11AH11VSS_AH15AH15VSS_AH34AH34VSS_AH35AH35VSS_AH36AH36VSS_AH37AH37VSS_AH38AH38VSS_AH39AH39VSS_AH40AH40VSS_AH43AH43VSS_AH44AH44VSS_AH45AH45VSS_AH46AH46VSS_AH47AH47VSS_AJ3AJ3VSS_AJ4AJ4VSS_AJ5AJ5VSS_AJ6AJ6VSS_AJ9AJ9VSS_AJ11AJ11VSS_AJ14AJ14VSS_AJ16AJ16VSS_AJ17AJ17VSS_AJ18AJ18VSS_AJ19AJ19VSS_AJ20AJ20VSS_AJ21AJ21VSS_AJ22AJ22VSS_AJ23AJ23VSS_AJ24AJ24VSS_AJ25AJ25VSS_AJ26AJ26VSS_AJ27AJ27VSS_AJ28AJ28VSS_AJ29AJ29VSS_AJ30AJ30VSS_AJ31AJ31VSS_AJ32AJ32VSS_AJ33AJ33VSS_AJ34AJ34VSS_AJ35AJ35
20/26PEX0T
SS26-0A0P-01
VSS_M45M45VSS_M46M46VSS_M47M47VSS_N1N1VSS_N2N2VSS_N5N5VSS_N8N8VSS_N9N9VSS_N10N10VSS_N11N11VSS_N12N12VSS_N13N13VSS_N14N14VSS_N15N15VSS_N16N16VSS_N17N17VSS_N18N18VSS_N19N19VSS_N20N20VSS_N21N21VSS_N22N22VSS_N23N23VSS_N24N24VSS_N25N25VSS_N26N26VSS_N27N27VSS_N28N28VSS_N29N29VSS_N30N30VSS_N31N31VSS_N32N32VSS_N33N33VSS_N34N34VSS_N35N35VSS_N36N36VSS_N37N37VSS_N40N40VSS_N41N41VSS_N42N42VSS_N45N45VSS_N48N48VSS_N49N49VSS_P3P3VSS_P4P4VSS_P5P5VSS_P6P6VSS_P7P7VSS_P10P10VSS_P11P11VSS_P12P12VSS_P13P13VSS_P14P14VSS_P15P15VSS_P16P16VSS_P17P17VSS_P18P18VSS_P19P19VSS_P20P20VSS_P21P21VSS_P22P22VSS_P23P23VSS_P24P24VSS_P25P25VSS_P26P26VSS_P27P27VSS_P28P28VSS_P29P29VSS_P30P30VSS_P31P31VSS_P32P32VSS_P33P33VSS_P34P34VSS_P35P35VSS_P37P37VSS_P40P40VSS_P43P43VSS_P44P44VSS_P45P45VSS_P46P46VSS_P47P47
VSS_R1R1VSS_R2R2VSS_R5R5VSS_R8R8VSS_R9R9VSS_R10R10VSS_R11R11VSS_R12R12VSS_R13R13VSS_R14R14VSS_R15R15VSS_R16R16VSS_R17R17VSS_R18R18VSS_R19R19VSS_R20R20VSS_R21R21VSS_R22R22VSS_R23R23VSS_R24R24VSS_R25R25VSS_R26R26VSS_R27R27VSS_R28R28VSS_R29R29VSS_R30R30VSS_R31R31VSS_R32R32VSS_R33R33VSS_R34R34VSS_R35R35VSS_R37R37VSS_R40R40VSS_R41R41VSS_R42R42VSS_R45R45VSS_R48R48VSS_R49R49VSS_T3T3VSS_T4T4VSS_T5T5VSS_T6T6VSS_T7T7VSS_T10T10VSS_T11T11VSS_T12T12VSS_T13T13VSS_T15T15VSS_T34T34VSS_T37T37VSS_T40T40VSS_T43T43VSS_T44T44VSS_T45T45VSS_T46T46VSS_T47T47VSS_U1U1VSS_U2U2VSS_U5U5VSS_U8U8VSS_U9U9VSS_U10U10VSS_U11U11VSS_U12U12VSS_U13U13VSS_U15U15VSS_U16U16VSS_U17U17VSS_U18U18VSS_U19U19VSS_U20U20VSS_U21U21VSS_U22U22VSS_U23U23VSS_U24U24VSS_U25U25VSS_U26U26VSS_U27U27VSS_U28U28VSS_U29U29
26/26PEX0ZSS26-0A0P-01VSS_BF7BF7VSS_BF9BF9VSS_BF11BF11VSS_BF13BF13VSS_BF15BF15VSS_BF17BF17VSS_BF19BF19VSS_BF21BF21VSS_BF23BF23VSS_BF25BF25VSS_BF27BF27VSS_BF29BF29VSS_BF31BF31VSS_BF33BF33VSS_BF35BF35VSS_BF37BF37VSS_BF39BF39VSS_BF41BF41VSS_BF43BF43VSS_BF45BF45VSS_BF47BF47VSS_BF48BF48VSS_BF49BF49VSS_BG3BG3VSS_BG5BG5VSS_BG7BG7VSS_BG9BG9VSS_BG11BG11VSS_BG13BG13VSS_BG15BG15VSS_BG17BG17VSS_BG19BG19VSS_BG21BG21VSS_BG23BG23VSS_BG25BG25VSS_BG27BG27VSS_BG29BG29VSS_BG31BG31VSS_BG33BG33VSS_BG35BG35VSS_BG37BG37VSS_BG39BG39VSS_BG41BG41VSS_BG43BG43VSS_BG45BG45VSS_BG47BG47VSS_BH1BH1VSS_BH2BH2VSS_BH4BH4VSS_BH6BH6VSS_BH8BH8VSS_BH10BH10VSS_BH12BH12VSS_BH14BH14VSS_BH16BH16VSS_BH18BH18VSS_BH20BH20VSS_BH22BH22VSS_BH24BH24VSS_BH26BH26VSS_BH28BH28VSS_BH30BH30VSS_BH32BH32VSS_BH34BH34VSS_BH36BH36VSS_BH38BH38VSS_BH40BH40VSS_BH42BH42VSS_BH44BH44VSS_BH46BH46VSS_BH48BH48VSS_BH49BH49VSS_BJ2BJ2VSS_BJ4BJ4VSS_BJ6BJ6VSS_BJ8BJ8VSS_BJ10BJ10VSS_BJ12BJ12VSS_BJ14BJ14VSS_BJ16BJ16VSS_BJ18BJ18VSS_BJ20BJ20VSS_BJ22BJ22VSS_BJ24BJ24VSS_BJ26BJ26VSS_BJ28BJ28VSS_BJ30BJ30VSS_BJ32BJ32VSS_BJ34BJ34VSS_BJ36BJ36VSS_BJ38BJ38VSS_BJ40BJ40VSS_BJ42BJ42VSS_BJ44BJ44VSS_BJ46BJ46VSS_BJ48BJ48PLL_VSSA_AA12AA12PLL_VSSA_AB13AB13PLL_VSSA_AC12AC12PLL_VSSA_AD13AD13PLL_VSSA_AE12AE12PLL_VSSA_AF13AF13PLL_VSSA_AG12AG12PLL_VSSA_AH13AH13PLL_VSSA_AJ12AJ1221/26PEX0U
SS26-0A0P-01
VSS_U30U30VSS_U31U31VSS_U32U32VSS_U33U33VSS_U34U34VSS_U35U35VSS_U37U37VSS_U40U40VSS_U41U41VSS_U42U42VSS_U45U45VSS_U48U48VSS_U49U49VSS_V3V3VSS_V4V4VSS_V5V5VSS_V6V6VSS_V7V7VSS_V10V10VSS_V11V11VSS_V12V12VSS_V13V13VSS_V15V15VSS_V34V34VSS_V36V36VSS_V37V37VSS_V38V38VSS_V40V40VSS_V43V43VSS_V44V44VSS_V45V45VSS_V46V46VSS_V47V47VSS_W1W1VSS_W2W2VSS_W5W5VSS_W8W8VSS_W9W9VSS_W10W10VSS_W11W11VSS_W12W12VSS_W13W13VSS_W14W14VSS_W15W15VSS_W16W16VSS_W17W17VSS_W18W18VSS_W19W19VSS_W20W20VSS_W21W21VSS_W22W22VSS_W23W23VSS_W24W24VSS_W25W25VSS_W26W26VSS_W27W27VSS_W28W28VSS_W29W29VSS_W30W30VSS_W31W31VSS_W32W32VSS_W33W33VSS_W34W34VSS_W36W36VSS_W37W37VSS_W40W40VSS_W41W41VSS_W42W42VSS_W45W45VSS_W48W48VSS_W49W49VSS_Y1Y1VSS_Y2Y2VSS_Y3Y3VSS_Y4Y4VSS_Y5Y5VSS_Y6Y6VSS_Y7Y7VSS_Y8Y8VSS_Y9Y9
VSS_Y10Y10VSS_Y11Y11VSS_Y13Y13VSS_Y15Y15VSS_Y34Y34VSS_Y36Y36VSS_Y37Y37VSS_Y38Y38VSS_Y40Y40VSS_Y44Y44VSS_Y45Y45VSS_Y46Y46VSS_Y47Y47VSS_AA3AA3VSS_AA4AA4VSS_AA5AA5VSS_AA6AA6VSS_AA7AA7VSS_AA8AA8VSS_AA9AA9VSS_AA11AA11VSS_AA14AA14VSS_AA16AA16VSS_AA17AA17VSS_AA18AA18VSS_AA19AA19VSS_AA20AA20VSS_AA21AA21VSS_AA22AA22VSS_AA23AA23VSS_AA24AA24VSS_AA25AA25VSS_AA26AA26VSS_AA27AA27VSS_AA28AA28VSS_AA29AA29VSS_AA30AA30VSS_AA31AA31VSS_AA32AA32VSS_AA33AA33VSS_AA36AA36VSS_AA38AA38VSS_AA40AA40VSS_AA41AA41VSS_AA42AA42VSS_AA45AA45VSS_AA48AA48VSS_AA49AA49VSS_AB1AB1VSS_AB2AB2VSS_AB3AB3VSS_AB6AB6VSS_AB9AB9VSS_AB11AB11VSS_AB15AB15VSS_AB34AB34VSS_AB36AB36VSS_AB37AB37VSS_AB38AB38VSS_AB39AB39VSS_AB40AB40VSS_AB43AB43VSS_AB44AB44VSS_AB45AB45VSS_AB46AB46VSS_AB47AB47VSS_AC3AC3VSS_AC4AC4VSS_AC5AC5VSS_AC6AC6VSS_AC9AC9VSS_AC11AC11VSS_AC14AC14VSS_AC16AC16VSS_AC18AC18VSS_AC20AC20VSS_AC22AC22VSS_AC24AC24VSS_AC26AC26
VSS_Y43Y4324/26PEX0X
SS26-0A0P-01
VSS_AR26AR26VSS_AR27AR27VSS_AR28AR28VSS_AR29AR29VSS_AR30AR30VSS_AR31AR31VSS_AR32AR32VSS_AR33AR33VSS_AR34AR34VSS_AR35AR35VSS_AR37AR37VSS_AR40AR40VSS_AR41AR41VSS_AR42AR42VSS_AR45AR45VSS_AR48AR48VSS_AR49AR49VSS_AT3AT3VSS_AT4AT4VSS_AT5AT5VSS_AT6AT6VSS_AT7AT7VSS_AT10AT10VSS_AT11AT11VSS_AT12AT12VSS_AT13AT13VSS_AT14AT14VSS_AT15AT15VSS_AT16AT16VSS_AT17AT17VSS_AT18AT18VSS_AT19AT19VSS_AT20AT20VSS_AT21AT21VSS_AT22AT22VSS_AT23AT23VSS_AT24AT24VSS_AT25AT25VSS_AT26AT26VSS_AT27AT27VSS_AT28AT28VSS_AT29AT29VSS_AT30AT30VSS_AT31AT31VSS_AT32AT32VSS_AT33AT33VSS_AT34AT34VSS_AT35AT35VSS_AT37AT37VSS_AT40AT40VSS_AT43AT43VSS_AT44AT44VSS_AT45AT45VSS_AT46AT46VSS_AT47AT47VSS_AU1AU1VSS_AU2AU2VSS_AU5AU5VSS_AU8AU8VSS_AU9AU9VSS_AU10AU10VSS_AU11AU11VSS_AU12AU12VSS_AU13AU13VSS_AU14AU14VSS_AU15AU15VSS_AU16AU16VSS_AU17AU17VSS_AU18AU18VSS_AU19AU19VSS_AU20AU20VSS_AU21AU21VSS_AU22AU22VSS_AU23AU23VSS_AU24AU24VSS_AU25AU25VSS_AU26AU26VSS_AU27AU27VSS_AU28AU28VSS_AU29AU29
VSS_AU30AU30VSS_AU31AU31VSS_AU32AU32VSS_AU33AU33VSS_AU34AU34VSS_AU35AU35VSS_AU36AU36VSS_AU37AU37VSS_AU40AU40VSS_AU41AU41VSS_AU42AU42VSS_AU45AU45VSS_AU48AU48VSS_AU49AU49VSS_AV3AV3VSS_AV4AV4VSS_AV5AV5VSS_AV6AV6VSS_AV7AV7VSS_AV10AV10VSS_AV11AV11VSS_AV20AV20VSS_AV24AV24VSS_AV40AV40VSS_AV43AV43VSS_AV44AV44VSS_AV45AV45VSS_AV46AV46VSS_AV47AV47VSS_AW1AW1VSS_AW2AW2VSS_AW5AW5VSS_AW8AW8VSS_AW9AW9VSS_AW10AW10VSS_AW11AW11VSS_AW20AW20VSS_AW24AW24VSS_AW40AW40VSS_AW41AW41VSS_AW42AW42VSS_AW45AW45VSS_AW48AW48VSS_AW49AW49VSS_AY3AY3VSS_AY4AY4VSS_AY5AY5VSS_AY6AY6VSS_AY7AY7VSS_AY8AY8VSS_AY9AY9VSS_AY10AY10VSS_AY11AY11VSS_AY12AY12VSS_AY13AY13VSS_AY14AY14VSS_AY15AY15VSS_AY16AY16VSS_AY17AY17VSS_AY18AY18VSS_AY19AY19VSS_AY20AY20VSS_AY21AY21VSS_AY22AY22VSS_AY23AY23VSS_AY24AY24VSS_AY25AY25VSS_AY26AY26VSS_AY27AY27VSS_AY28AY28VSS_AY29AY29VSS_AY30AY30VSS_AY31AY31VSS_AY32AY32VSS_AY33AY33VSS_AY34AY34VSS_AY35AY35VSS_AY36AY36VSS_AY37AY37VSS_AY38AY38



5
5
4
4
3
3
2
2
1
1
D D
C C
B B
A A
PEX_0_PWR_FILTER
Co-Layout CAD NOTE:BUCK CAP NEAR FILTER CAD NOTE:NEAR PACKAGE EDGE
Co-Layout CAD NOTE:BUCK CAP NEAR FILTER CAD NOTE:NEAR PACKAGE EDGE
DCR : 0.0021 ohm
P0V8_PEX0P0V8_PEX0P0V8_SERDES_VDDA_PEX0
P1V25_SERDES_VDDPLL_PEX0P1V25_PEX0P1V25_PEX0SizeDoc NumberRevDate: SheetofReviewerDesignerDepartmentProject
Page TitleCCBU D21 257Tuesday, August 29, 2023<project_name><Designer> GRANDTETON_SWB_2023082921 PEX_0_PWR_FILTER<Reviewer>SizeDoc NumberRevDate: SheetofReviewerDesignerDepartmentProject
Page TitleCCBU D21 257Tuesday, August 29, 2023<project_name><Designer> GRANDTETON_SWB_2023082921 PEX_0_PWR_FILTER<Reviewer>SizeDoc NumberRevDate: SheetofReviewerDesignerDepartmentProject
Page TitleCCBU D21 257Tuesday, August 29, 2023<project_name><Designer> GRANDTETON_SWB_2023082921 PEX_0_PWR_FILTER<Reviewer>C423547UF
C420622UFC0603_H4020%6.3VL50BLM31SN500SN1L21C4230100UFC0805_H61_SEL20%4VC422147UFR64580.51L82BLM31SN500SN1L21C42361UFC020120%4V
0.01R5784NI2B1B2A1AC421722UFC0603_H4020%6.3VC419447UF
C4245100UF20%4V
R64590.51C42221UFC020120%4VC4231100UF20%4VL83BLM31SN500SN1L21R64510.51L47BLM31SN500SN1L21
C42371UFC020120%4V
C420722UFC0603_H4020%6.3VR64600.510.01R5785NI2B1B2A1AC42231UFC020120%4V
C41951UFC020120%4V
R64690.51
C420447UF
C42381UFC020120%4VR64610.51
R64530.51
C42241UFC020120%4VR64700.51
L48BLM31SN500SN1L21 C42101UFC020120%4VC419647UFR64620.51C42391UFC020120%4VR64710.510.01R5786NI2B1B2A1AC42251UFC020120%4V
R64540.51C419747UFR64630.51C42111UFC020120%4VR64720.510.01R6128NI2B1B2A1A
C419847UFR64640.51
C41901UFC020120%4VC42081UFC020120%4VR64500.51
R64730.51
R64490.51C419947UFR64650.51C421247UF
0.01R6129NI2B1B2A1A0.01R6126NI2B1B2A1AC424047UFR64740.51
R64520.51
C422647UF
C419147UFC42001UFC020120%4VR64660.51C421347UFC424147UF
C420347UF
C423247UF0.01R6127NI2B1B2A1A
C42091UFC020120%4V
C422747UFC421847UFC420247UFR64550.51C421447UF0.01R5783NI2B1B2A1AC420547UF
L84BLM31SN500SN1L21C42011UFC020120%4V
C424247UFC423347UF
C419247UFL49BLM31SN500SN1L21C422847UFC421947UFR64560.51C421547UFC424347UFL85BLM31SN500SN1L21C423447UFC422947UFC422047UFR64570.51C421622UFC0603_H4020%6.3VC419347UF
C4244100UFC0805_H61_SEL20%4V



5
5
4
4
3
3
2
2
1
1
D D
C C
B B
A A
BLANK SizeDoc NumberRevDate: SheetofReviewerDesignerDepartmentProject
Page TitleCCBU D22 257Tuesday, August 29, 2023<project_name><Designer> GRANDTETON_SWB_20230829022 BLANK<Reviewer>SizeDoc NumberRevDate: SheetofReviewerDesignerDepartmentProject
Page TitleCCBU D22 257Tuesday, August 29, 2023<project_name><Designer> GRANDTETON_SWB_20230829022 BLANK<Reviewer>SizeDoc NumberRevDate: SheetofReviewerDesignerDepartmentProject
Page TitleCCBU D22 257Tuesday, August 29, 2023<project_name><Designer> GRANDTETON_SWB_20230829022 BLANK<Reviewer>



5
5
4
4
3
3
2
2
1
1
D D
C C
B B
A A
PEX_1_STN_01(1/11)
P5E_PEX1_STN0_RX_DP<15>[177]P5E_PEX1_STN0_RX_DN<15>[177]P5E_PEX1_STN0_RX_DP<14>[177]P5E_PEX1_STN0_RX_DN<14>[177]P5E_PEX1_STN0_RX_DP<13>[177]P5E_PEX1_STN0_RX_DN<13>[177]P5E_PEX1_STN0_RX_DP<12>[177]P5E_PEX1_STN0_RX_DN<12>[177]P5E_PEX1_STN0_RX_DP<11>[177]P5E_PEX1_STN0_RX_DN<11>[177]P5E_PEX1_STN0_RX_DP<10>[177]P5E_PEX1_STN0_RX_DN<10>[177]P5E_PEX1_STN0_RX_DP<9>[177]P5E_PEX1_STN0_RX_DN<9>[177]P5E_PEX1_STN0_RX_DP<8>[177]P5E_PEX1_STN0_RX_DN<8>[177]P5E_PEX1_STN0_RX_DP<7>[177]P5E_PEX1_STN0_RX_DN<7>[177]P5E_PEX1_STN0_RX_DP<6>[177]P5E_PEX1_STN0_RX_DN<6>[177]P5E_PEX1_STN0_RX_DP<5>[177]P5E_PEX1_STN0_RX_DN<5>[177]P5E_PEX1_STN0_RX_DP<4>[177]P5E_PEX1_STN0_RX_DN<4>[177]P5E_PEX1_STN0_RX_DP<3>[177]P5E_PEX1_STN0_RX_DN<3>[177]P5E_PEX1_STN0_RX_DP<2>[177]P5E_PEX1_STN0_RX_DN<2>[177]P5E_PEX1_STN0_RX_DP<1>[177]P5E_PEX1_STN0_RX_DN<1>[177]P5E_PEX1_STN0_RX_DP<0>[177]P5E_PEX1_STN0_RX_DN<0>[177]P5E_PEX1_STN1_RX_DP<31>[174]P5E_PEX1_STN1_RX_DN<31>[174]P5E_PEX1_STN1_RX_DP<30>[174]P5E_PEX1_STN1_RX_DN<30>[174]P5E_PEX1_STN1_RX_DP<29>[174]P5E_PEX1_STN1_RX_DN<29>[174]P5E_PEX1_STN1_RX_DP<28>[174]P5E_PEX1_STN1_RX_DN<28>[174]P5E_PEX1_STN1_RX_DP<27>[174]P5E_PEX1_STN1_RX_DN<27>[174]P5E_PEX1_STN1_RX_DP<26>[174]P5E_PEX1_STN1_RX_DN<26>[174]P5E_PEX1_STN1_RX_DP<25>[174]P5E_PEX1_STN1_RX_DN<25>[174]P5E_PEX1_STN1_RX_DP<24>[174]P5E_PEX1_STN1_RX_DN<24>[174]P5E_PEX1_STN1_RX_DP<23>[174]P5E_PEX1_STN1_RX_DN<23>[174]P5E_PEX1_STN1_RX_DP<22>[174]P5E_PEX1_STN1_RX_DN<22>[174]P5E_PEX1_STN1_RX_DP<21>[174]P5E_PEX1_STN1_RX_DN<21>[174]P5E_PEX1_STN1_RX_DP<20>[174]P5E_PEX1_STN1_RX_DN<20>[174]P5E_PEX1_STN1_RX_DP<19>[174]P5E_PEX1_STN1_RX_DN<19>[174]P5E_PEX1_STN1_RX_DP<18>[174]P5E_PEX1_STN1_RX_DN<18>[174]P5E_PEX1_STN1_RX_DP<17>[174]P5E_PEX1_STN1_RX_DN<17>[174]P5E_PEX1_STN1_RX_DP<16>[174]P5E_PEX1_STN1_RX_DN<16>[174]
P5E_PEX1_STN0_TX_C_DP<15> [177]P5E_PEX1_STN0_TX_C_DN<15> [177]P5E_PEX1_STN0_TX_C_DN<14> [177]P5E_PEX1_STN0_TX_C_DP<14> [177]P5E_PEX1_STN0_TX_C_DP<13> [177]P5E_PEX1_STN0_TX_C_DN<13> [177]P5E_PEX1_STN0_TX_C_DN<12> [177]P5E_PEX1_STN0_TX_C_DP<12> [177]P5E_PEX1_STN0_TX_C_DP<11> [177]P5E_PEX1_STN0_TX_C_DN<11> [177]P5E_PEX1_STN0_TX_C_DP<10> [177]P5E_PEX1_STN0_TX_C_DN<10> [177]P5E_PEX1_STN0_TX_C_DP<9> [177]P5E_PEX1_STN0_TX_C_DN<9> [177]P5E_PEX1_STN0_TX_C_DP<8> [177]P5E_PEX1_STN0_TX_C_DN<8> [177]P5E_PEX1_STN0_TX_C_DP<7> [177]P5E_PEX1_STN0_TX_C_DN<7> [177]P5E_PEX1_STN0_TX_C_DP<6> [177]P5E_PEX1_STN0_TX_C_DN<6> [177]P5E_PEX1_STN0_TX_C_DP<5> [177]P5E_PEX1_STN0_TX_C_DN<5> [177]P5E_PEX1_STN0_TX_C_DP<4> [177]P5E_PEX1_STN0_TX_C_DN<4> [177]P5E_PEX1_STN0_TX_C_DP<3> [177]P5E_PEX1_STN0_TX_C_DN<3> [177]P5E_PEX1_STN0_TX_C_DP<2> [177]P5E_PEX1_STN0_TX_C_DN<2> [177]P5E_PEX1_STN0_TX_C_DP<1> [177]P5E_PEX1_STN0_TX_C_DN<1> [177]P5E_PEX1_STN0_TX_C_DP<0> [177]P5E_PEX1_STN0_TX_C_DN<0> [177]P5E_PEX1_STN1_TX_C_DN<31> [174]P5E_PEX1_STN1_TX_C_DP<31> [174]P5E_PEX1_STN1_TX_C_DP<30> [174]P5E_PEX1_STN1_TX_C_DN<30> [174]P5E_PEX1_STN1_TX_C_DN<29> [174]P5E_PEX1_STN1_TX_C_DP<29> [174]P5E_PEX1_STN1_TX_C_DP<28> [174]P5E_PEX1_STN1_TX_C_DN<28> [174]P5E_PEX1_STN1_TX_C_DN<27> [174]P5E_PEX1_STN1_TX_C_DP<27> [174]P5E_PEX1_STN1_TX_C_DP<26> [174]P5E_PEX1_STN1_TX_C_DN<26> [174]P5E_PEX1_STN1_TX_C_DN<25> [174]P5E_PEX1_STN1_TX_C_DP<25> [174]P5E_PEX1_STN1_TX_C_DP<24> [174]P5E_PEX1_STN1_TX_C_DN<24> [174]P5E_PEX1_STN1_TX_C_DN<23> [174]P5E_PEX1_STN1_TX_C_DP<23> [174]P5E_PEX1_STN1_TX_C_DP<22> [174]P5E_PEX1_STN1_TX_C_DN<22> [174]P5E_PEX1_STN1_TX_C_DN<21> [174]P5E_PEX1_STN1_TX_C_DP<21> [174]P5E_PEX1_STN1_TX_C_DP<20> [174]P5E_PEX1_STN1_TX_C_DN<20> [174]P5E_PEX1_STN1_TX_C_DN<19> [174]P5E_PEX1_STN1_TX_C_DP<19> [174]P5E_PEX1_STN1_TX_C_DP<18> [174]P5E_PEX1_STN1_TX_C_DN<18> [174]P5E_PEX1_STN1_TX_C_DN<17> [174]P5E_PEX1_STN1_TX_C_DP<17> [174]P5E_PEX1_STN1_TX_C_DP<16> [174]P5E_PEX1_STN1_TX_C_DN<16> [174]SizeDoc NumberRevDate: SheetofReviewerDesignerDepartmentProject
Page TitleCCBU D23 257Tuesday, August 29, 2023<project_name><Designer> GRANDTETON_SWB_20230829023 PEX_1_STN_01(1/11)<Reviewer>SizeDoc NumberRevDate: SheetofReviewerDesignerDepartmentProject
Page TitleCCBU D23 257Tuesday, August 29, 2023<project_name><Designer> GRANDTETON_SWB_20230829023 PEX_1_STN_01(1/11)<Reviewer>SizeDoc NumberRevDate: SheetofReviewerDesignerDepartmentProject
Page TitleCCBU D23 257Tuesday, August 29, 2023<project_name><Designer> GRANDTETON_SWB_20230829023 PEX_1_STN_01(1/11)<Reviewer>C272 DIFF BUS_0.22UFC247 DIFF BUS_0.22UFC262 DIFF BUS_0.22UFC237 DIFF BUS_0.22UFC227 DIFF BUS_0.22UFC252 DIFF BUS_0.22UFC242 DIFF BUS_0.22UFC217 DIFF BUS_0.22UFC232 DIFF BUS_0.22UFC222 DIFF BUS_0.22UFC212 DIFF BUS_0.22UF
C273 DIFF BUS_0.22UFC263 DIFF BUS_0.22UFC253 DIFF BUS_0.22UFC268 DIFF BUS_0.22UFC243 DIFF BUS_0.22UFC233 DIFF BUS_0.22UFC258 DIFF BUS_0.22UFC248 DIFF BUS_0.22UFC223 DIFF BUS_0.22UFC238 DIFF BUS_0.22UFC213 DIFF BUS_0.22UFC228 DIFF BUS_0.22UFC218 DIFF BUS_0.22UF
C269 DIFF BUS_0.22UFC259 DIFF BUS_0.22UFC249 DIFF BUS_0.22UFC274 DIFF BUS_0.22UF
C239 DIFF BUS_0.22UFC264 DIFF BUS_0.22UFC254 DIFF BUS_0.22UFC229 DIFF BUS_0.22UFC244 DIFF BUS_0.22UFC219 DIFF BUS_0.22UFC234 DIFF BUS_0.22UFC224 DIFF BUS_0.22UFC214 DIFF BUS_0.22UF
C275 DIFF BUS_0.22UFC265 DIFF BUS_0.22UFC255 DIFF BUS_0.22UFC270 DIFF BUS_0.22UFC245 DIFF BUS_0.22UFC260 DIFF BUS_0.22UFC235 DIFF BUS_0.22UFC250 DIFF BUS_0.22UFC225 DIFF BUS_0.22UFC215 DIFF BUS_0.22UFC240 DIFF BUS_0.22UFC230 DIFF BUS_0.22UFC220 DIFF BUS_0.22UF
C271 DIFF BUS_0.22UFC261 DIFF BUS_0.22UF2/26PEX1BSS26-0A0P-01RXP31BF40RXN31BG40RXP30BH39RXN30BJ39RXP29BF38RXN29BG38RXP28BH37RXN28BJ37RXP27BF36RXN27BG36RXP26BH35RXN26BJ35RXP25BF34RXN25BG34RXP24BH33RXN24BJ33RXP23BF32RXN23BG32RXP22BH31RXN22BJ31RXP21BF30RXN21BG30RXP20BH29RXN20BJ29RXP19BF28RXN19BG28RXP18BH27RXN18BJ27RXP17BF26RXN17BG26RXP16BH25RXN16BJ25TXP31BA40TXN31BB40TXP30BC39TXN30BD39TXP29BA38TXN29BB38TXP28BC37TXN28BD37TXP27BA36TXN27BB36TXP26BC35TXN26BD35TXP25BA34TXN25BB34TXP24BC33TXN24BD33TXP23BA32TXN23BB32TXP22BC31TXN22BD31TXP21BA30TXN21BB30TXP20BC29TXN20BD29TXP19BA28TXN19BB28TXP18BC27TXN18BD27TXP17BA26TXP16BC25TXN16BD25TXN17BB26C251 DIFF BUS_0.22UFC266 DIFF BUS_0.22UFC241 DIFF BUS_0.22UFC256 DIFF BUS_0.22UFC231 DIFF BUS_0.22UFC221 DIFF BUS_0.22UF
1/26
PEX1ASS26-0A0P-01RXP15BH41RXN15BJ41RXP14BF42RXN14BG42RXP13BH43RXN13BJ43RXP12BF44RXN12BG44RXP11BH45RXN11BJ45RXP10BF46RXN10BG46RXP9BH47RXN9BJ47RXP8BG48RXN8BG49RXP7AY48RXN7AY49RXP6AW46RXN6AW47RXP5AV48RXN5AV49RXP4AU46RXN4AU47RXP3AT48RXN3AT49RXP2AR46RXN2AR47RXP1AP48RXN1AP49RXP0AN46RXN0AN47TXP15BC41TXN15BD41TXP14BA42TXN14BB42TXP13BC43TXN13BD43TXP12BA44TXN12BB44TXP11BC45TXN11BD45TXP10BA46TXN10BB46TXP9BC47TXN9BD47TXP8BE48TXN8BE49TXP7BB48TXN7BB49TXP6AW43TXN6AW44TXP5AV41TXN5AV42TXP4AU43TXN4AU44TXP3AT41TXN3AT42TXP2AR43TXN2AR44TXP1AP41TXN1AP42TXP0AN43TXN0AN44C246 DIFF BUS_0.22UFC236 DIFF BUS_0.22UFC226 DIFF BUS_0.22UFC216 DIFF BUS_0.22UF
C267 DIFF BUS_0.22UFC257 DIFF BUS_0.22UF
P5E_PEX1_STN0_RX_DP<15>P5E_PEX1_STN0_RX_DN<15>P5E_PEX1_STN0_RX_DP<14>P5E_PEX1_STN0_RX_DN<14>P5E_PEX1_STN0_RX_DP<13>P5E_PEX1_STN0_RX_DN<13>P5E_PEX1_STN0_RX_DP<12>P5E_PEX1_STN0_RX_DN<12>P5E_PEX1_STN0_RX_DP<11>P5E_PEX1_STN0_RX_DN<11>P5E_PEX1_STN0_RX_DP<10>P5E_PEX1_STN0_RX_DN<10>P5E_PEX1_STN0_RX_DP<9>P5E_PEX1_STN0_RX_DN<9>P5E_PEX1_STN0_RX_DP<8>P5E_PEX1_STN0_RX_DN<8>P5E_PEX1_STN0_RX_DP<7>P5E_PEX1_STN0_RX_DN<7>P5E_PEX1_STN0_RX_DP<6>P5E_PEX1_STN0_RX_DN<6>P5E_PEX1_STN0_RX_DP<5>P5E_PEX1_STN0_RX_DN<5>P5E_PEX1_STN0_RX_DP<4>P5E_PEX1_STN0_RX_DN<4>P5E_PEX1_STN0_RX_DP<3>P5E_PEX1_STN0_RX_DN<3>P5E_PEX1_STN0_RX_DP<2>P5E_PEX1_STN0_RX_DN<2>P5E_PEX1_STN0_RX_DP<1>P5E_PEX1_STN0_RX_DN<1>P5E_PEX1_STN0_RX_DP<0>P5E_PEX1_STN0_RX_DN<0>P5E_PEX1_STN1_RX_DP<31>P5E_PEX1_STN1_RX_DN<31>P5E_PEX1_STN1_RX_DP<30>P5E_PEX1_STN1_RX_DN<30>P5E_PEX1_STN1_RX_DP<29>P5E_PEX1_STN1_RX_DN<29>P5E_PEX1_STN1_RX_DP<28>P5E_PEX1_STN1_RX_DN<28>P5E_PEX1_STN1_RX_DP<27>P5E_PEX1_STN1_RX_DN<27>P5E_PEX1_STN1_RX_DP<26>P5E_PEX1_STN1_RX_DN<26>P5E_PEX1_STN1_RX_DP<25>P5E_PEX1_STN1_RX_DN<25>P5E_PEX1_STN1_RX_DP<24>P5E_PEX1_STN1_RX_DN<24>P5E_PEX1_STN1_RX_DP<23>P5E_PEX1_STN1_RX_DN<23>P5E_PEX1_STN1_RX_DP<22>P5E_PEX1_STN1_RX_DN<22>P5E_PEX1_STN1_RX_DP<21>P5E_PEX1_STN1_RX_DN<21>P5E_PEX1_STN1_RX_DP<20>P5E_PEX1_STN1_RX_DN<20>P5E_PEX1_STN1_RX_DP<19>P5E_PEX1_STN1_RX_DN<19>P5E_PEX1_STN1_RX_DP<18>P5E_PEX1_STN1_RX_DN<18>P5E_PEX1_STN1_RX_DP<17>P5E_PEX1_STN1_RX_DN<17>P5E_PEX1_STN1_RX_DP<16>P5E_PEX1_STN1_RX_DN<16>
P5E_PEX1_STN0_TX_DP<15>P5E_PEX1_STN0_TX_C_DP<15>P5E_PEX1_STN0_TX_DN<15>P5E_PEX1_STN0_TX_C_DN<15>P5E_PEX1_STN0_TX_DN<14>P5E_PEX1_STN0_TX_C_DN<14>P5E_PEX1_STN0_TX_DP<14>P5E_PEX1_STN0_TX_C_DP<14>P5E_PEX1_STN0_TX_DP<13>P5E_PEX1_STN0_TX_C_DP<13>P5E_PEX1_STN0_TX_DN<13>P5E_PEX1_STN0_TX_C_DN<13>P5E_PEX1_STN0_TX_DN<12>P5E_PEX1_STN0_TX_C_DN<12>P5E_PEX1_STN0_TX_DP<12>P5E_PEX1_STN0_TX_C_DP<12>P5E_PEX1_STN0_TX_DP<11>P5E_PEX1_STN0_TX_C_DP<11>P5E_PEX1_STN0_TX_DN<11>P5E_PEX1_STN0_TX_C_DN<11>P5E_PEX1_STN0_TX_DP<10>P5E_PEX1_STN0_TX_C_DP<10>P5E_PEX1_STN0_TX_DN<10>P5E_PEX1_STN0_TX_C_DN<10>P5E_PEX1_STN0_TX_DP<9>P5E_PEX1_STN0_TX_C_DP<9>P5E_PEX1_STN0_TX_DN<9>P5E_PEX1_STN0_TX_C_DN<9>P5E_PEX1_STN0_TX_DP<8>P5E_PEX1_STN0_TX_C_DP<8>P5E_PEX1_STN0_TX_DN<8>P5E_PEX1_STN0_TX_C_DN<8>P5E_PEX1_STN0_TX_DP<7>P5E_PEX1_STN0_TX_C_DP<7>P5E_PEX1_STN0_TX_DN<7>P5E_PEX1_STN0_TX_C_DN<7>P5E_PEX1_STN0_TX_DP<6>P5E_PEX1_STN0_TX_C_DP<6>P5E_PEX1_STN0_TX_DN<6>P5E_PEX1_STN0_TX_C_DN<6>P5E_PEX1_STN0_TX_DP<5>P5E_PEX1_STN0_TX_C_DP<5>P5E_PEX1_STN0_TX_DN<5>P5E_PEX1_STN0_TX_C_DN<5>P5E_PEX1_STN0_TX_DP<4>P5E_PEX1_STN0_TX_C_DP<4>P5E_PEX1_STN0_TX_DN<4>P5E_PEX1_STN0_TX_C_DN<4>P5E_PEX1_STN0_TX_DP<3>P5E_PEX1_STN0_TX_C_DP<3>P5E_PEX1_STN0_TX_DN<3>P5E_PEX1_STN0_TX_C_DN<3>P5E_PEX1_STN0_TX_DP<2>P5E_PEX1_STN0_TX_C_DP<2>P5E_PEX1_STN0_TX_DN<2>P5E_PEX1_STN0_TX_C_DN<2>P5E_PEX1_STN0_TX_DP<1>P5E_PEX1_STN0_TX_C_DP<1>P5E_PEX1_STN0_TX_DN<1>P5E_PEX1_STN0_TX_C_DN<1>P5E_PEX1_STN0_TX_DP<0>P5E_PEX1_STN0_TX_C_DP<0>P5E_PEX1_STN0_TX_DN<0>P5E_PEX1_STN0_TX_C_DN<0>P5E_PEX1_STN1_TX_DN<31>P5E_PEX1_STN1_TX_C_DN<31>P5E_PEX1_STN1_TX_DP<31>P5E_PEX1_STN1_TX_C_DP<31>P5E_PEX1_STN1_TX_DP<30>P5E_PEX1_STN1_TX_C_DP<30>P5E_PEX1_STN1_TX_DN<30>P5E_PEX1_STN1_TX_C_DN<30>P5E_PEX1_STN1_TX_DN<29>P5E_PEX1_STN1_TX_C_DN<29>P5E_PEX1_STN1_TX_DP<29>P5E_PEX1_STN1_TX_C_DP<29>P5E_PEX1_STN1_TX_DP<28>P5E_PEX1_STN1_TX_C_DP<28>P5E_PEX1_STN1_TX_DN<28>P5E_PEX1_STN1_TX_C_DN<28>P5E_PEX1_STN1_TX_DN<27>P5E_PEX1_STN1_TX_C_DN<27>P5E_PEX1_STN1_TX_DP<27>P5E_PEX1_STN1_TX_C_DP<27>P5E_PEX1_STN1_TX_DP<26>P5E_PEX1_STN1_TX_C_DP<26>P5E_PEX1_STN1_TX_DN<26>P5E_PEX1_STN1_TX_C_DN<26>P5E_PEX1_STN1_TX_DN<25>P5E_PEX1_STN1_TX_C_DN<25>P5E_PEX1_STN1_TX_DP<25>P5E_PEX1_STN1_TX_C_DP<25>P5E_PEX1_STN1_TX_DP<24>P5E_PEX1_STN1_TX_C_DP<24>P5E_PEX1_STN1_TX_DN<24>P5E_PEX1_STN1_TX_C_DN<24>P5E_PEX1_STN1_TX_DN<23>P5E_PEX1_STN1_TX_C_DN<23>P5E_PEX1_STN1_TX_DP<23>P5E_PEX1_STN1_TX_C_DP<23>P5E_PEX1_STN1_TX_DP<22>P5E_PEX1_STN1_TX_C_DP<22>P5E_PEX1_STN1_TX_DN<22>P5E_PEX1_STN1_TX_C_DN<22>P5E_PEX1_STN1_TX_DN<21>P5E_PEX1_STN1_TX_C_DN<21>P5E_PEX1_STN1_TX_DP<21>P5E_PEX1_STN1_TX_C_DP<21>P5E_PEX1_STN1_TX_DP<20>P5E_PEX1_STN1_TX_C_DP<20>P5E_PEX1_STN1_TX_DN<20>P5E_PEX1_STN1_TX_C_DN<20>P5E_PEX1_STN1_TX_DN<19>P5E_PEX1_STN1_TX_C_DN<19>P5E_PEX1_STN1_TX_DP<19>P5E_PEX1_STN1_TX_C_DP<19>P5E_PEX1_STN1_TX_DP<18>P5E_PEX1_STN1_TX_C_DP<18>P5E_PEX1_STN1_TX_DN<18>P5E_PEX1_STN1_TX_C_DN<18>P5E_PEX1_STN1_TX_DN<17>P5E_PEX1_STN1_TX_C_DN<17>P5E_PEX1_STN1_TX_DP<17>P5E_PEX1_STN1_TX_C_DP<17>P5E_PEX1_STN1_TX_DP<16>P5E_PEX1_STN1_TX_C_DP<16>P5E_PEX1_STN1_TX_DN<16>P5E_PEX1_STN1_TX_C_DN<16>



5
5
4
4
3
3
2
2
1
1
D D
C C
B B
A A
PEX_1_STN_23(2/11)
P5E_PEX1_STN2_RX_DP<47>[196]P5E_PEX1_STN2_TX_C_DP<47> [196]P5E_PEX1_STN2_RX_DN<47>[196]P5E_PEX1_STN2_TX_C_DN<47> [196]P5E_PEX1_STN2_RX_DP<46>[196]P5E_PEX1_STN2_TX_C_DP<46> [196]P5E_PEX1_STN2_RX_DN<46>[196]P5E_PEX1_STN2_TX_C_DN<46> [196]P5E_PEX1_STN2_RX_DP<45>[196]P5E_PEX1_STN2_TX_C_DP<45> [196]P5E_PEX1_STN2_RX_DN<45>[196]P5E_PEX1_STN2_TX_C_DN<45> [196]P5E_PEX1_STN2_RX_DP<44>[196]P5E_PEX1_STN2_TX_C_DP<44> [196]P5E_PEX1_STN2_RX_DN<44>[196]P5E_PEX1_STN2_TX_C_DN<44> [196]P5E_PEX1_STN2_RX_DP<43>[196]P5E_PEX1_STN2_TX_C_DP<43> [196]P5E_PEX1_STN2_RX_DN<43>[196]P5E_PEX1_STN2_TX_C_DN<43> [196]P5E_PEX1_STN2_RX_DP<42>[196]P5E_PEX1_STN2_TX_C_DP<42> [196]P5E_PEX1_STN2_RX_DN<42>[196]P5E_PEX1_STN2_TX_C_DN<42> [196]P5E_PEX1_STN2_RX_DP<41>[196]P5E_PEX1_STN2_TX_C_DP<41> [196]P5E_PEX1_STN2_RX_DN<41>[196]P5E_PEX1_STN2_TX_C_DN<41> [196]P5E_PEX1_STN2_RX_DP<40>[196]P5E_PEX1_STN2_TX_C_DP<40> [196]P5E_PEX1_STN2_RX_DN<40>[196]P5E_PEX1_STN2_TX_C_DN<40> [196]P5E_PEX1_STN2_RX_DP<39>[197]P5E_PEX1_STN2_TX_C_DP<39> [197]P5E_PEX1_STN2_RX_DN<39>[197]P5E_PEX1_STN2_TX_C_DN<39> [197]P5E_PEX1_STN2_RX_DP<38>[197]P5E_PEX1_STN2_TX_C_DP<38> [197]P5E_PEX1_STN2_RX_DN<38>[197]P5E_PEX1_STN2_TX_C_DN<38> [197]P5E_PEX1_STN2_RX_DP<37>[197]P5E_PEX1_STN2_TX_C_DP<37> [197]P5E_PEX1_STN2_RX_DN<37>[197]P5E_PEX1_STN2_TX_C_DN<37> [197]P5E_PEX1_STN2_RX_DP<36>[197]P5E_PEX1_STN2_TX_C_DP<36> [197]P5E_PEX1_STN2_RX_DN<36>[197]P5E_PEX1_STN2_TX_C_DN<36> [197]P5E_PEX1_STN2_RX_DP<35>[197]P5E_PEX1_STN2_TX_C_DP<35> [197]P5E_PEX1_STN2_RX_DN<35>[197]P5E_PEX1_STN2_TX_C_DN<35> [197]P5E_PEX1_STN2_RX_DP<34>[197]P5E_PEX1_STN2_TX_C_DP<34> [197]P5E_PEX1_STN2_RX_DN<34>[197]P5E_PEX1_STN2_TX_C_DN<34> [197]P5E_PEX1_STN2_RX_DP<33>[197]P5E_PEX1_STN2_TX_C_DP<33> [197]P5E_PEX1_STN2_RX_DN<33>[197]P5E_PEX1_STN2_TX_C_DN<33> [197]P5E_PEX1_STN2_RX_DP<32>[197]P5E_PEX1_STN2_TX_C_DP<32> [197]P5E_PEX1_STN2_RX_DN<32>[197]P5E_PEX1_STN2_TX_C_DN<32> [197]
SizeDoc NumberRevDate: SheetofReviewerDesignerDepartmentProject
Page TitleCCBU D24 257Tuesday, August 29, 2023<project_name><Designer> GRANDTETON_SWB_20230829024 PEX_1_STN_23(2/11)<Reviewer>SizeDoc NumberRevDate: SheetofReviewerDesignerDepartmentProject
Page TitleCCBU D24 257Tuesday, August 29, 2023<project_name><Designer> GRANDTETON_SWB_20230829024 PEX_1_STN_23(2/11)<Reviewer>SizeDoc NumberRevDate: SheetofReviewerDesignerDepartmentProject
Page TitleCCBU D24 257Tuesday, August 29, 2023<project_name><Designer> GRANDTETON_SWB_20230829024 PEX_1_STN_23(2/11)<Reviewer>
C305 DIFF BUS_0.22UFC301 DIFF BUS_0.22UFC297 DIFF BUS_0.22UFC293 DIFF BUS_0.22UFC289 DIFF BUS_0.22UFC285 DIFF BUS_0.22UFC281 DIFF BUS_0.22UFC277 DIFF BUS_0.22UFC306 DIFF BUS_0.22UFC302 DIFF BUS_0.22UFC298 DIFF BUS_0.22UFC294 DIFF BUS_0.22UFC290 DIFF BUS_0.22UF3/26PEX1CSS26-0A0P-01RXP47BH9RXN47BJ9RXP46BF10RXN46BG10RXP45BH11RXN45BJ11RXP44BF12RXN44BG12RXP43BH13RXN43BJ13RXP42BF14RXN42BG14RXP41BH15RXN41BJ15RXP40BF16RXN40BG16RXP39BH17RXN39BJ17RXP38BF18RXN38BG18RXP37BH19RXN37BJ19RXP36BF20RXN36BG20RXP35BH21RXN35BJ21RXP34BF22RXN34BG22RXP33BH23RXN33BJ23RXP32BF24RXN32BG24TXP47BC9TXN47BD9TXP46BA10TXN46BB10TXP45BC11TXN45BD11TXP44BA12TXN44BB12TXP43BC13TXN43BD13TXP42BA14TXN42BB14TXP41BC15TXN41BD15TXP40BA16TXN40BB16TXP39BC17TXN39BD17TXP38BA18TXN38BB18TXP37BC19TXN37BD19TXP36BA20TXN36BB20TXP35BC21TXN35BD21TXP34BA22TXN34BB22TXP33BC23TXN33BD23TXP32BA24TXN32BB24C286 DIFF BUS_0.22UFC282 DIFF BUS_0.22UFC278 DIFF BUS_0.22UF4/26PEX1DSS26-0A0P-01RXP63BF8RXN63BG8RXP62BH7RXN62BJ7RXP61BF6RXN61BG6RXP60BH5RXN60BJ5RXP59BF4RXN59BG4RXP58BH3RXN58BJ3RXP57BG2RXN57BG1RXP56AY2RXN56AY1RXP55AW4RXN55AW3RXP54AV2RXN54AV1RXP53AU4RXN53AU3RXP52AT2RXN52AT1RXP51AR4RXN51AR3RXP50AP2RXN50AP1RXP49AN4RXN49AN3RXP48AM2RXN48AM1TXP63BA8TXN63BB8TXP62BC7TXN62BD7TXP61BA6TXN61BB6TXP60BC5TXN60BD5TXP59BA4TXN59BB4TXP58BC3TXN58BD3TXP57BE2TXN57BE1TXP56BB2TXN56BB1TXP55AW7TXN55AW6TXP54AV9TXN54AV8TXP53AU7TXN53AU6TXP52AT9TXN52AT8TXP51AR7TXN51AR6TXP50AP9TXN50AP8TXP49AN7TXN49AN6TXP48AM9TXN48AM8C307 DIFF BUS_0.22UFC303 DIFF BUS_0.22UFC299 DIFF BUS_0.22UFC295 DIFF BUS_0.22UFC291 DIFF BUS_0.22UFC287 DIFF BUS_0.22UFC283 DIFF BUS_0.22UFC279 DIFF BUS_0.22UFC304 DIFF BUS_0.22UFC300 DIFF BUS_0.22UFC296 DIFF BUS_0.22UFC292 DIFF BUS_0.22UFC288 DIFF BUS_0.22UFC284 DIFF BUS_0.22UFC280 DIFF BUS_0.22UFC276 DIFF BUS_0.22UFP5E_PEX1_STN2_RX_DP<47>P5E_PEX1_STN2_TX_DP<47>P5E_PEX1_STN2_TX_C_DP<47>P5E_PEX1_STN2_RX_DN<47>P5E_PEX1_STN2_TX_DN<47>P5E_PEX1_STN2_TX_C_DN<47>P5E_PEX1_STN2_RX_DP<46>P5E_PEX1_STN2_TX_DP<46>P5E_PEX1_STN2_TX_C_DP<46>P5E_PEX1_STN2_RX_DN<46>P5E_PEX1_STN2_TX_DN<46>P5E_PEX1_STN2_TX_C_DN<46>P5E_PEX1_STN2_RX_DP<45>P5E_PEX1_STN2_TX_DP<45>P5E_PEX1_STN2_TX_C_DP<45>P5E_PEX1_STN2_RX_DN<45>P5E_PEX1_STN2_TX_DN<45>P5E_PEX1_STN2_TX_C_DN<45>P5E_PEX1_STN2_RX_DP<44>P5E_PEX1_STN2_TX_DP<44>P5E_PEX1_STN2_TX_C_DP<44>P5E_PEX1_STN2_RX_DN<44>P5E_PEX1_STN2_TX_DN<44>P5E_PEX1_STN2_TX_C_DN<44>P5E_PEX1_STN2_RX_DP<43>P5E_PEX1_STN2_TX_DP<43>P5E_PEX1_STN2_TX_C_DP<43>P5E_PEX1_STN2_RX_DN<43>P5E_PEX1_STN2_TX_DN<43>P5E_PEX1_STN2_TX_C_DN<43>P5E_PEX1_STN2_RX_DP<42>P5E_PEX1_STN2_TX_DP<42>P5E_PEX1_STN2_TX_C_DP<42>P5E_PEX1_STN2_RX_DN<42>P5E_PEX1_STN2_TX_DN<42>P5E_PEX1_STN2_TX_C_DN<42>P5E_PEX1_STN2_RX_DP<41>P5E_PEX1_STN2_TX_DP<41>P5E_PEX1_STN2_TX_C_DP<41>P5E_PEX1_STN2_RX_DN<41>P5E_PEX1_STN2_TX_DN<41>P5E_PEX1_STN2_TX_C_DN<41>P5E_PEX1_STN2_RX_DP<40>P5E_PEX1_STN2_TX_DP<40>P5E_PEX1_STN2_TX_C_DP<40>P5E_PEX1_STN2_RX_DN<40>P5E_PEX1_STN2_TX_DN<40>P5E_PEX1_STN2_TX_C_DN<40>P5E_PEX1_STN2_RX_DP<39>P5E_PEX1_STN2_TX_DP<39>P5E_PEX1_STN2_TX_C_DP<39>P5E_PEX1_STN2_RX_DN<39>P5E_PEX1_STN2_TX_DN<39>P5E_PEX1_STN2_TX_C_DN<39>P5E_PEX1_STN2_RX_DP<38>P5E_PEX1_STN2_TX_DP<38>P5E_PEX1_STN2_TX_C_DP<38>P5E_PEX1_STN2_RX_DN<38>P5E_PEX1_STN2_TX_DN<38>P5E_PEX1_STN2_TX_C_DN<38>P5E_PEX1_STN2_RX_DP<37>P5E_PEX1_STN2_TX_DP<37>P5E_PEX1_STN2_TX_C_DP<37>P5E_PEX1_STN2_RX_DN<37>P5E_PEX1_STN2_TX_DN<37>P5E_PEX1_STN2_TX_C_DN<37>P5E_PEX1_STN2_RX_DP<36>P5E_PEX1_STN2_TX_DP<36>P5E_PEX1_STN2_TX_C_DP<36>P5E_PEX1_STN2_RX_DN<36>P5E_PEX1_STN2_TX_DN<36>P5E_PEX1_STN2_TX_C_DN<36>P5E_PEX1_STN2_RX_DP<35>P5E_PEX1_STN2_TX_DP<35>P5E_PEX1_STN2_TX_C_DP<35>P5E_PEX1_STN2_RX_DN<35>P5E_PEX1_STN2_TX_DN<35>P5E_PEX1_STN2_TX_C_DN<35>P5E_PEX1_STN2_RX_DP<34>P5E_PEX1_STN2_TX_DP<34>P5E_PEX1_STN2_TX_C_DP<34>P5E_PEX1_STN2_RX_DN<34>P5E_PEX1_STN2_TX_DN<34>P5E_PEX1_STN2_TX_C_DN<34>P5E_PEX1_STN2_RX_DP<33>P5E_PEX1_STN2_TX_DP<33>P5E_PEX1_STN2_TX_C_DP<33>P5E_PEX1_STN2_RX_DN<33>P5E_PEX1_STN2_TX_DN<33>P5E_PEX1_STN2_TX_C_DN<33>P5E_PEX1_STN2_RX_DP<32>P5E_PEX1_STN2_TX_DP<32>P5E_PEX1_STN2_TX_C_DP<32>P5E_PEX1_STN2_RX_DN<32>P5E_PEX1_STN2_TX_DN<32>P5E_PEX1_STN2_TX_C_DN<32>



5
5
4
4
3
3
2
2
1
1
D D
C C
B B
A A
PEX_1_STN_45(3/11)
P5E_PEX1_STN5_RX_DP<95>[137]P5E_PEX1_STN5_TX_C_DP<95> [137]P5E_PEX1_STN5_RX_DN<95>[137]P5E_PEX1_STN5_TX_C_DN<95> [137]P5E_PEX1_STN5_RX_DP<94>[137]P5E_PEX1_STN5_TX_C_DP<94> [137]P5E_PEX1_STN5_RX_DN<94>[137]P5E_PEX1_STN5_TX_C_DN<94> [137]P5E_PEX1_STN5_RX_DP<93>[136]P5E_PEX1_STN5_TX_C_DP<93> [136]P5E_PEX1_STN5_RX_DN<93>[136]P5E_PEX1_STN5_TX_C_DN<93> [136]P5E_PEX1_STN5_RX_DP<92>[136]P5E_PEX1_STN5_TX_C_DP<92> [136]P5E_PEX1_STN5_RX_DN<92>[136]P5E_PEX1_STN5_TX_C_DN<92> [136]P5E_PEX1_STN5_RX_DP<91>[135]P5E_PEX1_STN5_TX_C_DP<91> [135]P5E_PEX1_STN5_RX_DN<91>[135]P5E_PEX1_STN5_TX_C_DN<91> [135]P5E_PEX1_STN5_RX_DP<90>[135]P5E_PEX1_STN5_TX_C_DP<90> [135]P5E_PEX1_STN5_RX_DN<90>[135]P5E_PEX1_STN5_TX_C_DN<90> [135]P5E_PEX1_STN5_RX_DP<89>[134]P5E_PEX1_STN5_TX_C_DP<89> [134]P5E_PEX1_STN5_RX_DN<89>[134]P5E_PEX1_STN5_TX_C_DN<89> [134]P5E_PEX1_STN5_RX_DP<88>[134]P5E_PEX1_STN5_TX_C_DP<88> [134]P5E_PEX1_STN5_RX_DN<88>[134]P5E_PEX1_STN5_TX_C_DN<88> [134]P5E_PEX1_STN5_RX_DP<87>[137]P5E_PEX1_STN5_TX_C_DP<87> [137]P5E_PEX1_STN5_RX_DN<87>[137]P5E_PEX1_STN5_TX_C_DN<87> [137]P5E_PEX1_STN5_RX_DP<86>[137]P5E_PEX1_STN5_TX_C_DP<86> [137]P5E_PEX1_STN5_RX_DN<86>[137]P5E_PEX1_STN5_TX_C_DN<86> [137]P5E_PEX1_STN5_RX_DP<85>[136]P5E_PEX1_STN5_TX_C_DP<85> [136]P5E_PEX1_STN5_RX_DN<85>[136]P5E_PEX1_STN5_TX_C_DN<85> [136]P5E_PEX1_STN5_RX_DP<84>[136]P5E_PEX1_STN5_TX_C_DP<84> [136]P5E_PEX1_STN5_RX_DN<84>[136]P5E_PEX1_STN5_TX_C_DN<84> [136]P5E_PEX1_STN5_RX_DP<83>[135]P5E_PEX1_STN5_TX_C_DP<83> [135]P5E_PEX1_STN5_RX_DN<83>[135]P5E_PEX1_STN5_TX_C_DN<83> [135]P5E_PEX1_STN5_RX_DP<82>[135]P5E_PEX1_STN5_TX_C_DP<82> [135]P5E_PEX1_STN5_RX_DN<82>[135]P5E_PEX1_STN5_TX_C_DN<82> [135]P5E_PEX1_STN5_RX_DP<81>[134]P5E_PEX1_STN5_TX_C_DP<81> [134]P5E_PEX1_STN5_RX_DN<81>[134]P5E_PEX1_STN5_TX_C_DN<81> [134]P5E_PEX1_STN5_RX_DP<80>[134]P5E_PEX1_STN5_TX_C_DP<80> [134]P5E_PEX1_STN5_RX_DN<80>[134]P5E_PEX1_STN5_TX_C_DN<80> [134]
P5E_PEX1_STN4_RX_DP<79>[139]P5E_PEX1_STN4_TX_C_DP<79> [139]P5E_PEX1_STN4_RX_DN<79>[139]P5E_PEX1_STN4_TX_C_DN<79> [139]P5E_PEX1_STN4_RX_DP<78>[139]P5E_PEX1_STN4_TX_C_DP<78> [139]P5E_PEX1_STN4_RX_DN<78>[139]P5E_PEX1_STN4_TX_C_DN<78> [139]P5E_PEX1_STN4_RX_DP<77>[140]P5E_PEX1_STN4_TX_C_DP<77> [140]P5E_PEX1_STN4_RX_DN<77>[140]P5E_PEX1_STN4_TX_C_DN<77> [140]P5E_PEX1_STN4_RX_DP<76>[140]P5E_PEX1_STN4_TX_C_DP<76> [140]P5E_PEX1_STN4_RX_DN<76>[140]P5E_PEX1_STN4_TX_C_DN<76> [140]P5E_PEX1_STN4_RX_DP<75>[141]P5E_PEX1_STN4_TX_C_DP<75> [141]P5E_PEX1_STN4_RX_DN<75>[141]P5E_PEX1_STN4_TX_C_DN<75> [141]P5E_PEX1_STN4_RX_DP<74>[141]P5E_PEX1_STN4_TX_C_DP<74> [141]P5E_PEX1_STN4_RX_DN<74>[141]P5E_PEX1_STN4_TX_C_DN<74> [141]P5E_PEX1_STN4_RX_DP<73>[142]P5E_PEX1_STN4_TX_C_DP<73> [142]P5E_PEX1_STN4_RX_DN<73>[142]P5E_PEX1_STN4_TX_C_DN<73> [142]P5E_PEX1_STN4_RX_DP<72>[142]P5E_PEX1_STN4_TX_C_DP<72> [142]P5E_PEX1_STN4_RX_DN<72>[142]P5E_PEX1_STN4_TX_C_DN<72> [142]P5E_PEX1_STN4_RX_DP<71>[139]P5E_PEX1_STN4_TX_C_DP<71> [139]P5E_PEX1_STN4_RX_DN<71>[139]P5E_PEX1_STN4_TX_C_DN<71> [139]P5E_PEX1_STN4_RX_DP<70>[139]P5E_PEX1_STN4_TX_C_DP<70> [139]P5E_PEX1_STN4_RX_DN<70>[139]P5E_PEX1_STN4_TX_C_DN<70> [139]P5E_PEX1_STN4_RX_DP<69>[140]P5E_PEX1_STN4_TX_C_DP<69> [140]P5E_PEX1_STN4_RX_DN<69>[140]P5E_PEX1_STN4_TX_C_DN<69> [140]P5E_PEX1_STN4_RX_DP<68>[140]P5E_PEX1_STN4_TX_C_DP<68> [140]P5E_PEX1_STN4_RX_DN<68>[140]P5E_PEX1_STN4_TX_C_DN<68> [140]P5E_PEX1_STN4_RX_DP<67>[141]P5E_PEX1_STN4_TX_C_DP<67> [141]P5E_PEX1_STN4_RX_DN<67>[141]P5E_PEX1_STN4_TX_C_DN<67> [141]P5E_PEX1_STN4_RX_DP<66>[141]P5E_PEX1_STN4_TX_C_DP<66> [141]P5E_PEX1_STN4_RX_DN<66>[141]P5E_PEX1_STN4_TX_C_DN<66> [141]P5E_PEX1_STN4_RX_DP<65>[142]P5E_PEX1_STN4_TX_C_DP<65> [142]P5E_PEX1_STN4_RX_DN<65>[142]P5E_PEX1_STN4_TX_C_DN<65> [142]P5E_PEX1_STN4_RX_DP<64>[142]P5E_PEX1_STN4_TX_C_DP<64> [142]P5E_PEX1_STN4_RX_DN<64>[142]P5E_PEX1_STN4_TX_C_DN<64> [142]
SizeDoc NumberRevDate: SheetofReviewerDesignerDepartmentProject
Page TitleCCBU D25 257Tuesday, August 29, 2023<project_name><Designer> GRANDTETON_SWB_20230829025 PEX_1_STN_45(3/11)<Reviewer>SizeDoc NumberRevDate: SheetofReviewerDesignerDepartmentProject
Page TitleCCBU D25 257Tuesday, August 29, 2023<project_name><Designer> GRANDTETON_SWB_20230829025 PEX_1_STN_45(3/11)<Reviewer>SizeDoc NumberRevDate: SheetofReviewerDesignerDepartmentProject
Page TitleCCBU D25 257Tuesday, August 29, 2023<project_name><Designer> GRANDTETON_SWB_20230829025 PEX_1_STN_45(3/11)<Reviewer>
C2526 DIFF BUS_0.22UFC2513 DIFF BUS_0.22UFC2535 DIFF BUS_0.22UF
C2273 DIFF BUS_0.22UFC2269 DIFF BUS_0.22UFC2265 DIFF BUS_0.22UFC2261 DIFF BUS_0.22UF
C2522 DIFF BUS_0.22UFC2257 DIFF BUS_0.22UFC2531 DIFF BUS_0.22UFC2253 DIFF BUS_0.22UFC2249 DIFF BUS_0.22UFC2245 DIFF BUS_0.22UFC2518 DIFF BUS_0.22UFC2540 DIFF BUS_0.22UFC2527 DIFF BUS_0.22UFC2514 DIFF BUS_0.22UF
C2274 DIFF BUS_0.22UF
C2536 DIFF BUS_0.22UFC2270 DIFF BUS_0.22UF
C2523 DIFF BUS_0.22UF
C2266 DIFF BUS_0.22UFC2262 DIFF BUS_0.22UFC2258 DIFF BUS_0.22UFC2254 DIFF BUS_0.22UFC2250 DIFF BUS_0.22UFC2246 DIFF BUS_0.22UF6/26PEX1FSS26-0A0P-01RXP95B39RXN95A39RXP94D38RXN94C38RXP93B37RXN93A37RXP92D36RXN92C36RXP91B35RXN91A35RXP90D34RXN90C34RXP89B33RXN89A33RXP88D32RXN88C32RXP87B31RXN87A31RXP86D30RXN86C30RXP85B29RXN85A29RXP84D28RXN84C28RXP83B27RXN83A27RXP82D26RXN82C26RXP81B25RXN81A25RXP80D24RXN80C24TXP95G39TXN95F39TXP94J38TXN94H38TXP93G37TXN93F37TXP92J36TXN92H36TXP91G35TXN91F35TXP90J34TXN90H34TXP89G33TXN89F33TXP88J32TXN88H32TXP87G31TXN87F31TXP86J30TXN86H30TXP85G29TXN85F29TXP84J28TXN84H28TXP83G27TXN83F27TXP82J26TXN82H26TXP81G25TXN81F25TXP80J24TXN80H24
C2532 DIFF BUS_0.22UFC2519 DIFF BUS_0.22UFC2541 DIFF BUS_0.22UFC2528 DIFF BUS_0.22UFC2515 DIFF BUS_0.22UFC2537 DIFF BUS_0.22UFC2524 DIFF BUS_0.22UF
C2271 DIFF BUS_0.22UF
C2533 DIFF BUS_0.22UFC2267 DIFF BUS_0.22UFC2263 DIFF BUS_0.22UFC2259 DIFF BUS_0.22UFC2255 DIFF BUS_0.22UFC2251 DIFF BUS_0.22UFC2247 DIFF BUS_0.22UFC2520 DIFF BUS_0.22UFC2243 DIFF BUS_0.22UFC2542 DIFF BUS_0.22UFC2529 DIFF BUS_0.22UFC2516 DIFF BUS_0.22UFC2538 DIFF BUS_0.22UFC2525 DIFF BUS_0.22UF
C2272 DIFF BUS_0.22UFC2268 DIFF BUS_0.22UFC2264 DIFF BUS_0.22UF
C2512 DIFF BUS_0.22UF
C2260 DIFF BUS_0.22UFC2534 DIFF BUS_0.22UFC2256 DIFF BUS_0.22UFC2252 DIFF BUS_0.22UFC2521 DIFF BUS_0.22UFC2543 DIFF BUS_0.22UFC2248 DIFF BUS_0.22UFC2244 DIFF BUS_0.22UF5/26PEX1ESS26-0A0P-01RXP79D40RXN79C40RXP78B41RXN78A41RXP77D42RXN77C42RXP76B43RXN76A43RXP75D44RXN75C44RXP74B45RXN74A45RXP73D46RXN73C46RXP72B47RXN72A47RXP71C48RXN71C49RXP70K48RXN70K49RXP69L46RXN69L47RXP68M48RXN68M49RXP67N46RXN67N47RXP66P48RXN66P49RXP65R46RXN65R47RXP64T48RXN64T49TXP79J40TXN79H40TXP78G41TXN78F41TXP77J42TXN77H42TXP76G43TXN76F43TXP75J44TXN75H44TXP74G45TXN74F45TXP73J46TXN73H46TXP72G47TXN72F47TXP71E48TXN71E49TXP70H48TXN70H49TXP69L43TXN69L44TXP68M41TXN68M42TXP67N43TXN67N44TXP66P41TXN66P42TXP65R43TXN65R44TXP64T41TXN64T42C2530 DIFF BUS_0.22UFC2517 DIFF BUS_0.22UFC2539 DIFF BUS_0.22UFP5E_PEX1_STN5_RX_DP<95>P5E_PEX1_STN5_TX_DP<95>P5E_PEX1_STN5_TX_C_DP<95>P5E_PEX1_STN5_RX_DN<95>P5E_PEX1_STN5_TX_DN<95>P5E_PEX1_STN5_TX_C_DN<95>P5E_PEX1_STN5_RX_DP<94>P5E_PEX1_STN5_TX_DP<94>P5E_PEX1_STN5_TX_C_DP<94>P5E_PEX1_STN5_RX_DN<94>P5E_PEX1_STN5_TX_DN<94>P5E_PEX1_STN5_TX_C_DN<94>P5E_PEX1_STN5_RX_DP<93>P5E_PEX1_STN5_TX_DP<93>P5E_PEX1_STN5_TX_C_DP<93>P5E_PEX1_STN5_RX_DN<93>P5E_PEX1_STN5_TX_DN<93>P5E_PEX1_STN5_TX_C_DN<93>P5E_PEX1_STN5_RX_DP<92>P5E_PEX1_STN5_TX_DP<92>P5E_PEX1_STN5_TX_C_DP<92>P5E_PEX1_STN5_RX_DN<92>P5E_PEX1_STN5_TX_DN<92>P5E_PEX1_STN5_TX_C_DN<92>P5E_PEX1_STN5_RX_DP<91>P5E_PEX1_STN5_TX_DP<91>P5E_PEX1_STN5_TX_C_DP<91>P5E_PEX1_STN5_RX_DN<91>P5E_PEX1_STN5_TX_DN<91>P5E_PEX1_STN5_TX_C_DN<91>P5E_PEX1_STN5_RX_DP<90>P5E_PEX1_STN5_TX_DP<90>P5E_PEX1_STN5_TX_C_DP<90>P5E_PEX1_STN5_RX_DN<90>P5E_PEX1_STN5_TX_DN<90>P5E_PEX1_STN5_TX_C_DN<90>P5E_PEX1_STN5_RX_DP<89>P5E_PEX1_STN5_TX_DP<89>P5E_PEX1_STN5_TX_C_DP<89>P5E_PEX1_STN5_RX_DN<89>P5E_PEX1_STN5_TX_DN<89>P5E_PEX1_STN5_TX_C_DN<89>P5E_PEX1_STN5_RX_DP<88>P5E_PEX1_STN5_TX_DP<88>P5E_PEX1_STN5_TX_C_DP<88>P5E_PEX1_STN5_RX_DN<88>P5E_PEX1_STN5_TX_DN<88>P5E_PEX1_STN5_TX_C_DN<88>P5E_PEX1_STN5_RX_DP<87>P5E_PEX1_STN5_TX_DP<87>P5E_PEX1_STN5_TX_C_DP<87>P5E_PEX1_STN5_RX_DN<87>P5E_PEX1_STN5_TX_DN<87>P5E_PEX1_STN5_TX_C_DN<87>P5E_PEX1_STN5_RX_DP<86>P5E_PEX1_STN5_TX_DP<86>P5E_PEX1_STN5_TX_C_DP<86>P5E_PEX1_STN5_RX_DN<86>P5E_PEX1_STN5_TX_DN<86>P5E_PEX1_STN5_TX_C_DN<86>P5E_PEX1_STN5_RX_DP<85>P5E_PEX1_STN5_TX_DP<85>P5E_PEX1_STN5_TX_C_DP<85>P5E_PEX1_STN5_RX_DN<85>P5E_PEX1_STN5_TX_DN<85>P5E_PEX1_STN5_TX_C_DN<85>P5E_PEX1_STN5_RX_DP<84>P5E_PEX1_STN5_TX_DP<84>P5E_PEX1_STN5_TX_C_DP<84>P5E_PEX1_STN5_RX_DN<84>P5E_PEX1_STN5_TX_DN<84>P5E_PEX1_STN5_TX_C_DN<84>P5E_PEX1_STN5_RX_DP<83>P5E_PEX1_STN5_TX_DP<83>P5E_PEX1_STN5_TX_C_DP<83>P5E_PEX1_STN5_RX_DN<83>P5E_PEX1_STN5_TX_DN<83>P5E_PEX1_STN5_TX_C_DN<83>P5E_PEX1_STN5_RX_DP<82>P5E_PEX1_STN5_TX_DP<82>P5E_PEX1_STN5_TX_C_DP<82>P5E_PEX1_STN5_RX_DN<82>P5E_PEX1_STN5_TX_DN<82>P5E_PEX1_STN5_TX_C_DN<82>P5E_PEX1_STN5_RX_DP<81>P5E_PEX1_STN5_TX_DP<81>P5E_PEX1_STN5_TX_C_DP<81>P5E_PEX1_STN5_RX_DN<81>P5E_PEX1_STN5_TX_DN<81>P5E_PEX1_STN5_TX_C_DN<81>P5E_PEX1_STN5_RX_DP<80>P5E_PEX1_STN5_TX_DP<80>P5E_PEX1_STN5_TX_C_DP<80>P5E_PEX1_STN5_RX_DN<80>P5E_PEX1_STN5_TX_DN<80>P5E_PEX1_STN5_TX_C_DN<80>
P5E_PEX1_STN4_RX_DP<79>P5E_PEX1_STN4_TX_DP<79>P5E_PEX1_STN4_TX_C_DP<79>P5E_PEX1_STN4_RX_DN<79>P5E_PEX1_STN4_TX_DN<79>P5E_PEX1_STN4_TX_C_DN<79>P5E_PEX1_STN4_RX_DP<78>P5E_PEX1_STN4_TX_DP<78>P5E_PEX1_STN4_TX_C_DP<78>P5E_PEX1_STN4_RX_DN<78>P5E_PEX1_STN4_TX_DN<78>P5E_PEX1_STN4_TX_C_DN<78>P5E_PEX1_STN4_RX_DP<77>P5E_PEX1_STN4_TX_DP<77>P5E_PEX1_STN4_TX_C_DP<77>P5E_PEX1_STN4_RX_DN<77>P5E_PEX1_STN4_TX_DN<77>P5E_PEX1_STN4_TX_C_DN<77>P5E_PEX1_STN4_RX_DP<76>P5E_PEX1_STN4_TX_DP<76>P5E_PEX1_STN4_TX_C_DP<76>P5E_PEX1_STN4_RX_DN<76>P5E_PEX1_STN4_TX_DN<76>P5E_PEX1_STN4_TX_C_DN<76>P5E_PEX1_STN4_RX_DP<75>P5E_PEX1_STN4_TX_DP<75>P5E_PEX1_STN4_TX_C_DP<75>P5E_PEX1_STN4_RX_DN<75>P5E_PEX1_STN4_TX_DN<75>P5E_PEX1_STN4_TX_C_DN<75>P5E_PEX1_STN4_RX_DP<74>P5E_PEX1_STN4_TX_DP<74>P5E_PEX1_STN4_TX_C_DP<74>P5E_PEX1_STN4_RX_DN<74>P5E_PEX1_STN4_TX_DN<74>P5E_PEX1_STN4_TX_C_DN<74>P5E_PEX1_STN4_RX_DP<73>P5E_PEX1_STN4_TX_DP<73>P5E_PEX1_STN4_TX_C_DP<73>P5E_PEX1_STN4_RX_DN<73>P5E_PEX1_STN4_TX_DN<73>P5E_PEX1_STN4_TX_C_DN<73>P5E_PEX1_STN4_RX_DP<72>P5E_PEX1_STN4_TX_DP<72>P5E_PEX1_STN4_TX_C_DP<72>P5E_PEX1_STN4_RX_DN<72>P5E_PEX1_STN4_TX_DN<72>P5E_PEX1_STN4_TX_C_DN<72>P5E_PEX1_STN4_RX_DP<71>P5E_PEX1_STN4_TX_DP<71>P5E_PEX1_STN4_TX_C_DP<71>P5E_PEX1_STN4_RX_DN<71>P5E_PEX1_STN4_TX_DN<71>P5E_PEX1_STN4_TX_C_DN<71>P5E_PEX1_STN4_RX_DP<70>P5E_PEX1_STN4_TX_DP<70>P5E_PEX1_STN4_TX_C_DP<70>P5E_PEX1_STN4_RX_DN<70>P5E_PEX1_STN4_TX_DN<70>P5E_PEX1_STN4_TX_C_DN<70>P5E_PEX1_STN4_RX_DP<69>P5E_PEX1_STN4_TX_DP<69>P5E_PEX1_STN4_TX_C_DP<69>P5E_PEX1_STN4_RX_DN<69>P5E_PEX1_STN4_TX_DN<69>P5E_PEX1_STN4_TX_C_DN<69>P5E_PEX1_STN4_RX_DP<68>P5E_PEX1_STN4_TX_DP<68>P5E_PEX1_STN4_TX_C_DP<68>P5E_PEX1_STN4_RX_DN<68>P5E_PEX1_STN4_TX_DN<68>P5E_PEX1_STN4_TX_C_DN<68>P5E_PEX1_STN4_RX_DP<67>P5E_PEX1_STN4_TX_DP<67>P5E_PEX1_STN4_TX_C_DP<67>P5E_PEX1_STN4_RX_DN<67>P5E_PEX1_STN4_TX_DN<67>P5E_PEX1_STN4_TX_C_DN<67>P5E_PEX1_STN4_RX_DP<66>P5E_PEX1_STN4_TX_DP<66>P5E_PEX1_STN4_TX_C_DP<66>P5E_PEX1_STN4_RX_DN<66>P5E_PEX1_STN4_TX_DN<66>P5E_PEX1_STN4_TX_C_DN<66>P5E_PEX1_STN4_RX_DP<65>P5E_PEX1_STN4_TX_DP<65>P5E_PEX1_STN4_TX_C_DP<65>P5E_PEX1_STN4_RX_DN<65>P5E_PEX1_STN4_TX_DN<65>P5E_PEX1_STN4_TX_C_DN<65>P5E_PEX1_STN4_RX_DP<64>P5E_PEX1_STN4_TX_DP<64>P5E_PEX1_STN4_TX_C_DP<64>P5E_PEX1_STN4_RX_DN<64>P5E_PEX1_STN4_TX_DN<64>P5E_PEX1_STN4_TX_C_DN<64>



5
5
4
4
3
3
2
2
1
1
D D
C C
B B
A A
PEX_1_STN_67(4/11)
P5E_PEX1_STN7_TX_C_DP<112> [139]P5E_PEX1_STN7_TX_C_DN<112> [139]P5E_PEX1_STN7_TX_C_DP<113> [139]P5E_PEX1_STN7_TX_C_DN<113> [139]P5E_PEX1_STN7_TX_C_DP<115> [140]P5E_PEX1_STN7_TX_C_DN<115> [140]P5E_PEX1_STN7_TX_C_DP<114> [140]P5E_PEX1_STN7_TX_C_DN<114> [140]P5E_PEX1_STN7_TX_C_DP<119> [142]P5E_PEX1_STN7_TX_C_DN<119> [142]P5E_PEX1_STN7_TX_C_DP<118> [142]P5E_PEX1_STN7_TX_C_DN<118> [142]P5E_PEX1_STN7_TX_C_DP<117> [141]P5E_PEX1_STN7_TX_C_DN<117> [141]P5E_PEX1_STN7_TX_C_DP<116> [141]P5E_PEX1_STN7_TX_C_DN<116> [141]P5E_PEX1_STN7_TX_C_DP<120> [139]P5E_PEX1_STN7_TX_C_DN<120> [139]P5E_PEX1_STN7_TX_C_DP<121> [139]P5E_PEX1_STN7_TX_C_DN<121> [139]P5E_PEX1_STN7_TX_C_DP<123> [140]P5E_PEX1_STN7_TX_C_DN<123> [140]P5E_PEX1_STN7_TX_C_DP<122> [140]P5E_PEX1_STN7_TX_C_DN<122> [140]P5E_PEX1_STN7_TX_C_DP<127> [142]P5E_PEX1_STN7_TX_C_DN<127> [142]P5E_PEX1_STN7_TX_C_DP<126> [142]P5E_PEX1_STN7_TX_C_DN<126> [142]P5E_PEX1_STN7_TX_C_DP<125> [141]P5E_PEX1_STN7_TX_C_DN<125> [141]P5E_PEX1_STN7_TX_C_DP<124> [141]P5E_PEX1_STN7_TX_C_DN<124> [141]P5E_PEX1_STN7_RX_DP<127>[142]P5E_PEX1_STN7_RX_DN<127>[142]P5E_PEX1_STN7_RX_DP<126>[142]P5E_PEX1_STN7_RX_DN<126>[142]P5E_PEX1_STN7_RX_DP<125>[141]P5E_PEX1_STN7_RX_DN<125>[141]P5E_PEX1_STN7_RX_DP<124>[141]P5E_PEX1_STN7_RX_DN<124>[141]P5E_PEX1_STN7_RX_DP<123>[140]P5E_PEX1_STN7_RX_DN<123>[140]P5E_PEX1_STN7_RX_DP<122>[140]P5E_PEX1_STN7_RX_DN<122>[140]P5E_PEX1_STN7_RX_DP<121>[139]P5E_PEX1_STN7_RX_DN<121>[139]P5E_PEX1_STN7_RX_DP<120>[139]P5E_PEX1_STN7_RX_DN<120>[139]P5E_PEX1_STN7_RX_DP<119>[142]P5E_PEX1_STN7_RX_DN<119>[142]P5E_PEX1_STN7_RX_DP<118>[142]P5E_PEX1_STN7_RX_DN<118>[142]P5E_PEX1_STN7_RX_DP<117>[141]P5E_PEX1_STN7_RX_DN<117>[141]P5E_PEX1_STN7_RX_DP<116>[141]P5E_PEX1_STN7_RX_DN<116>[141]P5E_PEX1_STN7_RX_DP<115>[140]P5E_PEX1_STN7_RX_DN<115>[140]P5E_PEX1_STN7_RX_DP<114>[140]P5E_PEX1_STN7_RX_DN<114>[140]P5E_PEX1_STN7_RX_DP<113>[139]P5E_PEX1_STN7_RX_DN<113>[139]P5E_PEX1_STN7_RX_DP<112>[139]P5E_PEX1_STN7_RX_DN<112>[139]
P5E_PEX1_STN6_RX_DP<111>[134]P5E_PEX1_STN6_TX_C_DP<111> [134]P5E_PEX1_STN6_RX_DN<111>[134]P5E_PEX1_STN6_TX_C_DN<111> [134]P5E_PEX1_STN6_RX_DP<110>[134]P5E_PEX1_STN6_TX_C_DP<110> [134]P5E_PEX1_STN6_RX_DN<110>[134]P5E_PEX1_STN6_TX_C_DN<110> [134]P5E_PEX1_STN6_RX_DP<109>[135]P5E_PEX1_STN6_TX_C_DP<109> [135]P5E_PEX1_STN6_RX_DN<109>[135]P5E_PEX1_STN6_TX_C_DN<109> [135]P5E_PEX1_STN6_RX_DP<108>[135]P5E_PEX1_STN6_TX_C_DP<108> [135]P5E_PEX1_STN6_RX_DN<108>[135]P5E_PEX1_STN6_TX_C_DN<108> [135]P5E_PEX1_STN6_RX_DP<107>[136]P5E_PEX1_STN6_TX_C_DP<107> [136]P5E_PEX1_STN6_RX_DN<107>[136]P5E_PEX1_STN6_TX_C_DN<107> [136]P5E_PEX1_STN6_RX_DP<106>[136]P5E_PEX1_STN6_TX_C_DP<106> [136]P5E_PEX1_STN6_RX_DN<106>[136]P5E_PEX1_STN6_TX_C_DN<106> [136]P5E_PEX1_STN6_RX_DP<105>[137]P5E_PEX1_STN6_TX_C_DP<105> [137]P5E_PEX1_STN6_RX_DN<105>[137]P5E_PEX1_STN6_TX_C_DN<105> [137]P5E_PEX1_STN6_RX_DP<104>[137]P5E_PEX1_STN6_TX_C_DP<104> [137]P5E_PEX1_STN6_RX_DN<104>[137]P5E_PEX1_STN6_TX_C_DN<104> [137]P5E_PEX1_STN6_RX_DP<103>[134]P5E_PEX1_STN6_TX_C_DP<103> [134]P5E_PEX1_STN6_RX_DN<103>[134]P5E_PEX1_STN6_TX_C_DN<103> [134]P5E_PEX1_STN6_RX_DP<102>[134]P5E_PEX1_STN6_TX_C_DP<102> [134]P5E_PEX1_STN6_RX_DN<102>[134]P5E_PEX1_STN6_TX_C_DN<102> [134]P5E_PEX1_STN6_RX_DP<101>[135]P5E_PEX1_STN6_TX_C_DP<101> [135]P5E_PEX1_STN6_RX_DN<101>[135]P5E_PEX1_STN6_TX_C_DN<101> [135]P5E_PEX1_STN6_RX_DP<100>[135]P5E_PEX1_STN6_TX_C_DP<100> [135]P5E_PEX1_STN6_RX_DN<100>[135]P5E_PEX1_STN6_TX_C_DN<100> [135]P5E_PEX1_STN6_RX_DP<99>[136]P5E_PEX1_STN6_TX_C_DP<99> [136]P5E_PEX1_STN6_RX_DN<99>[136]P5E_PEX1_STN6_TX_C_DN<99> [136]P5E_PEX1_STN6_RX_DP<98>[136]P5E_PEX1_STN6_TX_C_DP<98> [136]P5E_PEX1_STN6_RX_DN<98>[136]P5E_PEX1_STN6_TX_C_DN<98> [136]P5E_PEX1_STN6_RX_DP<97>[137]P5E_PEX1_STN6_TX_C_DP<97> [137]P5E_PEX1_STN6_RX_DN<97>[137]P5E_PEX1_STN6_TX_C_DN<97> [137]P5E_PEX1_STN6_RX_DP<96>[137]P5E_PEX1_STN6_TX_C_DP<96> [137]P5E_PEX1_STN6_RX_DN<96>[137]P5E_PEX1_STN6_TX_C_DN<96> [137]
SizeDoc NumberRevDate: SheetofReviewerDesignerDepartmentProject
Page TitleCCBU D26 257Tuesday, August 29, 2023<project_name><Designer> GRANDTETON_SWB_20230829026 PEX_1_STN_67(4/11)<Reviewer>SizeDoc NumberRevDate: SheetofReviewerDesignerDepartmentProject
Page TitleCCBU D26 257Tuesday, August 29, 2023<project_name><Designer> GRANDTETON_SWB_20230829026 PEX_1_STN_67(4/11)<Reviewer>SizeDoc NumberRevDate: SheetofReviewerDesignerDepartmentProject
Page TitleCCBU D26 257Tuesday, August 29, 2023<project_name><Designer> GRANDTETON_SWB_20230829026 PEX_1_STN_67(4/11)<Reviewer>
C371 DIFF BUS_0.22UFC346 DIFF BUS_0.22UF
C384 DIFF BUS_0.22UFC359 DIFF BUS_0.22UF
C397 DIFF BUS_0.22UFC372 DIFF BUS_0.22UFC347 DIFF BUS_0.22UF
C385 DIFF BUS_0.22UFC360 DIFF BUS_0.22UF
C398 DIFF BUS_0.22UFC373 DIFF BUS_0.22UFC348 DIFF BUS_0.22UF
C386 DIFF BUS_0.22UFC361 DIFF BUS_0.22UF
C399 DIFF BUS_0.22UFC374 DIFF BUS_0.22UFC349 DIFF BUS_0.22UF
C387 DIFF BUS_0.22UFC362 DIFF BUS_0.22UF
C400 DIFF BUS_0.22UFC375 DIFF BUS_0.22UFC350 DIFF BUS_0.22UF
C388 DIFF BUS_0.22UFC363 DIFF BUS_0.22UF
C401 DIFF BUS_0.22UFC376 DIFF BUS_0.22UFC351 DIFF BUS_0.22UF
C389 DIFF BUS_0.22UFC364 DIFF BUS_0.22UF
C402 DIFF BUS_0.22UFC377 DIFF BUS_0.22UF8/26PEX1HSS26-0A0P-01RXP127B7RXN127A7RXP126D6RXN126C6RXP125B5RXN125A5RXP124D4RXN124C4RXP123B3RXN123A3RXP122C2RXN122C1RXP121K2RXN121K1RXP120L4RXN120L3RXP119M2RXN119M1RXP118N4RXN118N3RXP117P2RXN117P1RXP116R4RXN116R3RXP115T2RXN115T1RXP114U4RXN114U3RXP113V2RXN113V1RXP112W4RXN112W3TXP127G7TXN127F7TXP126J6TXN126H6TXP125G5TXN125F5TXP124J4TXN124H4TXP123G3TXN123F3TXP122E2TXN122E1TXP121H2TXN121H1TXP120L7TXN120L6TXP119M9TXN119M8TXP118N7TXN118N6TXP117P9TXN117P8TXP116R7TXN116R6TXP115T9TXN115T8TXP114U7TXN114U6TXP113V9TXN113V8TXP112W7TXN112W6
C352 DIFF BUS_0.22UF
C390 DIFF BUS_0.22UFC365 DIFF BUS_0.22UF
C403 DIFF BUS_0.22UF
C340 DIFF BUS_0.22UF
C378 DIFF BUS_0.22UFC353 DIFF BUS_0.22UF
C391 DIFF BUS_0.22UFC366 DIFF BUS_0.22UFC341 DIFF BUS_0.22UF
C379 DIFF BUS_0.22UFC354 DIFF BUS_0.22UF
C392 DIFF BUS_0.22UFC367 DIFF BUS_0.22UFC342 DIFF BUS_0.22UF
C380 DIFF BUS_0.22UFC355 DIFF BUS_0.22UF
C393 DIFF BUS_0.22UFC368 DIFF BUS_0.22UFC343 DIFF BUS_0.22UF
C381 DIFF BUS_0.22UFC356 DIFF BUS_0.22UF
C394 DIFF BUS_0.22UFC369 DIFF BUS_0.22UFC344 DIFF BUS_0.22UF
C382 DIFF BUS_0.22UFC357 DIFF BUS_0.22UF
C395 DIFF BUS_0.22UFC370 DIFF BUS_0.22UFC345 DIFF BUS_0.22UF
C383 DIFF BUS_0.22UF
7/26PEX1GSS26-0A0P-01RXP111D8RXN111C8RXP110B9RXN110A9RXP109D10RXN109C10RXP108B11RXN108A11RXP107D12RXN107C12RXP106B13RXN106A13RXP105D14RXN105C14RXP104B15RXN104A15RXP103D16RXN103C16RXP102B17RXN102A17RXP101D18RXN101C18RXP100B19RXN100A19RXP99D20RXN99C20RXP98B21RXN98A21RXP97D22RXN97C22RXP96B23RXN96A23TXP111J8TXN111H8TXP110G9TXN110F9TXP109J10TXN109H10TXP108G11TXN108F11TXP107J12TXN107H12TXP106G13TXN106F13TXP105J14TXN105H14TXP104G15TXN104F15TXP103J16TXN103H16TXP102G17TXN102F17TXP101J18TXN101H18TXP100G19TXN100F19TXP99J20TXN99H20TXP98G21TXN98F21TXP97J22TXN97H22TXP96G23TXN96F23C358 DIFF BUS_0.22UF
C396 DIFF BUS_0.22UFP5E_PEX1_STN7_TX_DP<112>P5E_PEX1_STN7_TX_C_DP<112>P5E_PEX1_STN7_TX_DN<112>P5E_PEX1_STN7_TX_C_DN<112>P5E_PEX1_STN7_TX_DP<113>P5E_PEX1_STN7_TX_DN<113>P5E_PEX1_STN7_TX_DP<115>P5E_PEX1_STN7_TX_DN<115>P5E_PEX1_STN7_TX_DP<114>P5E_PEX1_STN7_TX_DN<114>P5E_PEX1_STN7_TX_DP<119>P5E_PEX1_STN7_TX_DN<119>P5E_PEX1_STN7_TX_DP<118>P5E_PEX1_STN7_TX_DN<118>P5E_PEX1_STN7_TX_DP<117>P5E_PEX1_STN7_TX_DN<117>P5E_PEX1_STN7_TX_DP<116>P5E_PEX1_STN7_TX_DN<116>P5E_PEX1_STN7_TX_C_DP<113>P5E_PEX1_STN7_TX_C_DN<113>P5E_PEX1_STN7_TX_C_DP<115>P5E_PEX1_STN7_TX_C_DN<115>P5E_PEX1_STN7_TX_C_DP<114>P5E_PEX1_STN7_TX_C_DN<114>P5E_PEX1_STN7_TX_C_DP<119>P5E_PEX1_STN7_TX_C_DN<119>P5E_PEX1_STN7_TX_C_DP<118>P5E_PEX1_STN7_TX_C_DN<118>P5E_PEX1_STN7_TX_C_DP<117>P5E_PEX1_STN7_TX_C_DN<117P5E_PEX1_STN7_TX_C_DP<116>P5E_PEX1_STN7_TX_C_DN<116>P5E_PEX1_STN7_TX_DP<120>P5E_PEX1_STN7_TX_DN<120>P5E_PEX1_STN7_TX_DP<121>P5E_PEX1_STN7_TX_DN<121>P5E_PEX1_STN7_TX_DP<122>P5E_PEX1_STN7_TX_DN<122>P5E_PEX1_STN7_TX_DP<123>P5E_PEX1_STN7_TX_DN<123>P5E_PEX1_STN7_TX_DP<124>P5E_PEX1_STN7_TX_DN<124>P5E_PEX1_STN7_TX_DP<125>P5E_PEX1_STN7_TX_DN<125>P5E_PEX1_STN7_TX_DP<126>P5E_PEX1_STN7_TX_DN<126>P5E_PEX1_STN7_TX_DP<127>P5E_PEX1_STN7_TX_DN<127>P5E_PEX1_STN7_TX_C_DP<120>P5E_PEX1_STN7_TX_C_DN<120>P5E_PEX1_STN7_TX_C_DP<121>P5E_PEX1_STN7_TX_C_DN<121>P5E_PEX1_STN7_TX_C_DP<123>P5E_PEX1_STN7_TX_C_DN<123>P5E_PEX1_STN7_TX_C_DP<122>P5E_PEX1_STN7_TX_C_DN<122>P5E_PEX1_STN7_TX_C_DP<127>P5E_PEX1_STN7_TX_C_DN<127>P5E_PEX1_STN7_TX_C_DP<126>P5E_PEX1_STN7_TX_C_DN<126>P5E_PEX1_STN7_TX_C_DP<125>P5E_PEX1_STN7_TX_C_DN<125>P5E_PEX1_STN7_TX_C_DP<124>P5E_PEX1_STN7_TX_C_DN<124>P5E_PEX1_STN7_RX_DP<127>P5E_PEX1_STN7_RX_DN<127>P5E_PEX1_STN7_RX_DP<126>P5E_PEX1_STN7_RX_DN<126>P5E_PEX1_STN7_RX_DP<125>P5E_PEX1_STN7_RX_DN<125>P5E_PEX1_STN7_RX_DP<124>P5E_PEX1_STN7_RX_DN<124>P5E_PEX1_STN7_RX_DP<123>P5E_PEX1_STN7_RX_DN<123>P5E_PEX1_STN7_RX_DP<122>P5E_PEX1_STN7_RX_DN<122>P5E_PEX1_STN7_RX_DP<121>P5E_PEX1_STN7_RX_DN<121>P5E_PEX1_STN7_RX_DP<120>P5E_PEX1_STN7_RX_DN<120>P5E_PEX1_STN7_RX_DP<119>P5E_PEX1_STN7_RX_DN<119>P5E_PEX1_STN7_RX_DP<118>P5E_PEX1_STN7_RX_DN<118>P5E_PEX1_STN7_RX_DP<117>P5E_PEX1_STN7_RX_DN<117>P5E_PEX1_STN7_RX_DP<116>P5E_PEX1_STN7_RX_DN<116>P5E_PEX1_STN7_RX_DP<115>P5E_PEX1_STN7_RX_DN<115>P5E_PEX1_STN7_RX_DP<114>P5E_PEX1_STN7_RX_DN<114>P5E_PEX1_STN7_RX_DP<113>P5E_PEX1_STN7_RX_DN<113>P5E_PEX1_STN7_RX_DP<112>P5E_PEX1_STN7_RX_DN<112>
P5E_PEX1_STN6_RX_DP<111>P5E_PEX1_STN6_TX_DP<111>P5E_PEX1_STN6_TX_C_DP<111>P5E_PEX1_STN6_RX_DN<111>P5E_PEX1_STN6_TX_DN<111>P5E_PEX1_STN6_TX_C_DN<111>P5E_PEX1_STN6_RX_DP<110>P5E_PEX1_STN6_TX_DP<110>P5E_PEX1_STN6_TX_C_DP<110>P5E_PEX1_STN6_RX_DN<110>P5E_PEX1_STN6_TX_DN<110>P5E_PEX1_STN6_TX_C_DN<110>P5E_PEX1_STN6_RX_DP<109>P5E_PEX1_STN6_TX_DP<109>P5E_PEX1_STN6_TX_C_DP<109>P5E_PEX1_STN6_RX_DN<109>P5E_PEX1_STN6_TX_DN<109>P5E_PEX1_STN6_TX_C_DN<109>P5E_PEX1_STN6_RX_DP<108>P5E_PEX1_STN6_TX_DP<108>P5E_PEX1_STN6_TX_C_DP<108>P5E_PEX1_STN6_RX_DN<108>P5E_PEX1_STN6_TX_DN<108>P5E_PEX1_STN6_TX_C_DN<108>P5E_PEX1_STN6_RX_DP<107>P5E_PEX1_STN6_TX_DP<107>P5E_PEX1_STN6_TX_C_DP<107>P5E_PEX1_STN6_RX_DN<107>P5E_PEX1_STN6_TX_DN<107>P5E_PEX1_STN6_TX_C_DN<107>P5E_PEX1_STN6_RX_DP<106>P5E_PEX1_STN6_TX_DP<106>P5E_PEX1_STN6_TX_C_DP<106>P5E_PEX1_STN6_RX_DN<106>P5E_PEX1_STN6_TX_DN<106>P5E_PEX1_STN6_TX_C_DN<106>P5E_PEX1_STN6_RX_DP<105>P5E_PEX1_STN6_TX_DP<105>P5E_PEX1_STN6_TX_C_DP<105>P5E_PEX1_STN6_RX_DN<105>P5E_PEX1_STN6_TX_DN<105>P5E_PEX1_STN6_TX_C_DN<105>P5E_PEX1_STN6_RX_DP<104>P5E_PEX1_STN6_TX_DP<104>P5E_PEX1_STN6_TX_C_DP<104>P5E_PEX1_STN6_RX_DN<104>P5E_PEX1_STN6_TX_DN<104>P5E_PEX1_STN6_TX_C_DN<104>P5E_PEX1_STN6_RX_DP<103>P5E_PEX1_STN6_TX_DP<103>P5E_PEX1_STN6_TX_C_DP<103>P5E_PEX1_STN6_RX_DN<103>P5E_PEX1_STN6_TX_DN<103>P5E_PEX1_STN6_TX_C_DN<103>P5E_PEX1_STN6_RX_DP<102>P5E_PEX1_STN6_TX_DP<102>P5E_PEX1_STN6_TX_C_DP<102>P5E_PEX1_STN6_RX_DN<102>P5E_PEX1_STN6_TX_DN<102>P5E_PEX1_STN6_TX_C_DN<102>P5E_PEX1_STN6_RX_DP<101>P5E_PEX1_STN6_TX_DP<101>P5E_PEX1_STN6_TX_C_DP<101>P5E_PEX1_STN6_RX_DN<101>P5E_PEX1_STN6_TX_DN<101>P5E_PEX1_STN6_TX_C_DN<101>P5E_PEX1_STN6_RX_DP<100>P5E_PEX1_STN6_TX_DP<100>P5E_PEX1_STN6_TX_C_DP<100>P5E_PEX1_STN6_RX_DN<100>P5E_PEX1_STN6_TX_DN<100>P5E_PEX1_STN6_TX_C_DN<100>P5E_PEX1_STN6_RX_DP<99>P5E_PEX1_STN6_TX_DP<99>P5E_PEX1_STN6_TX_C_DP<99>P5E_PEX1_STN6_RX_DN<99>P5E_PEX1_STN6_TX_DN<99>P5E_PEX1_STN6_TX_C_DN<99>P5E_PEX1_STN6_RX_DP<98>P5E_PEX1_STN6_TX_DP<98>P5E_PEX1_STN6_TX_C_DP<98>P5E_PEX1_STN6_RX_DN<98>P5E_PEX1_STN6_TX_DN<98>P5E_PEX1_STN6_TX_C_DN<98>P5E_PEX1_STN6_RX_DP<97>P5E_PEX1_STN6_TX_DP<97>P5E_PEX1_STN6_TX_C_DP<97>P5E_PEX1_STN6_RX_DN<97>P5E_PEX1_STN6_TX_DN<97>P5E_PEX1_STN6_TX_C_DN<97>P5E_PEX1_STN6_RX_DP<96>P5E_PEX1_STN6_TX_DP<96>P5E_PEX1_STN6_TX_C_DP<96>P5E_PEX1_STN6_RX_DN<96>P5E_PEX1_STN6_TX_DN<96>P5E_PEX1_STN6_TX_C_DN<96>



5
5
4
4
3
3
2
2
1
1
D D
C C
B B
A A
PEX_1_STN_8(5/11)
CLK_100M_DB2000QL_PEX1_S1_R_DP [79]CLK_100M_DB2000QL_PEX1_S1_R_DN [79]CLK_100M_DB800ZL_PEX1_S0_R_DP [83]CLK_100M_DB800ZL_PEX1_S0_R_DN [83]CLK_100M_PEX1_REF_R_DP[82]CLK_100M_PEX1_REF_R_DN[82]RST_PEX1_PERST_R_N[118]RST_PEX1_S3_PERST_R_N [27]RST_PEX1_S1_PERST_R_N [27]RST_PEX1_S0_PERST_R_N [27]RST_PEX1_S0_PERST_R_N[27]RST_PEX1_S1_PERST_R_N[27]RST_PEX1_S3_PERST_R_N[27]CLK_100M_DB800ZL_PEX1_S3_R_DP [84]CLK_100M_DB800ZL_PEX1_S3_R_DN [84]P1V8_PEXP1V8_PEXSizeDoc NumberRevDate: SheetofReviewerDesignerDepartmentProject
Page TitleCCBU D27 257Tuesday, August 29, 2023<project_name><Designer> GRANDTETON_SWB_20230829027 PEX_1_STN_8(5/11)<Reviewer>SizeDoc NumberRevDate: SheetofReviewerDesignerDepartmentProject
Page TitleCCBU D27 257Tuesday, August 29, 2023<project_name><Designer> GRANDTETON_SWB_20230829027 PEX_1_STN_8(5/11)<Reviewer>SizeDoc NumberRevDate: SheetofReviewerDesignerDepartmentProject
Page TitleCCBU D27 257Tuesday, August 29, 2023<project_name><Designer> GRANDTETON_SWB_20230829027 PEX_1_STN_8(5/11)<Reviewer>R63914.7KR0402-02015%
9/26PEX1ISS26-0A0P-01RXP143AM48RXN143AM49RXP142AL46RXN142AL47RXP141AK48RXN141AK49RXP140AJ46RXN140AJ47RXP139AH48RXN139AH49RXP138AG46RXN138AG47RXP137AF48RXN137AF49RXP136AE46RXN136AE47RXP135AD48RXN135AD49RXP134AC46RXN134AC47RXP133AB48RXN133AB49RXP132AA46RXN132AA47RXP131Y48RXN131Y49RXP130W46RXN130W47RXP129V48RXN129V49RXP128U46RXN128U47TXP143AM41TXN143AM42TXP142AL43TXN142AL44TXP141AK41TXN141AK42TXP140AJ43TXN140AJ44TXP139AH41TXN139AH42TXP138AG43TXN138AG44TXP137AF41TXN137AF42TXP136AE43TXN136AE44TXP135AD41TXN135AD42TXP134AC43TXN134AC44TXP133AB41TXN133AB42TXP132AA43TXN132AA44TXP131Y41TXN131Y42TXP130W43TXN130W44TXP129V41TXN129V42TXP128U43TXN128U4410/26PEX1JSS26-0A0P-01S7_PCE_PERST_NU38S6_PCE_PERST_NR38S5_PCE_PERST_NU39S4_PCE_PERST_NR39S3_PCE_PERST_NP38S2_PCE_PERST_NT39S1_PCE_PERST_NP39S0_PCE_PERST_NT38SYS_REF_CLK_PAA2SYS_REF_CLK_NAA1S7_PCE_REF_CLK_PAJ2S7_PCE_REF_CLK_NAJ1S6_PCE_REF_CLK_PAH5S6_PCE_REF_CLK_NAH4S5_PCE_REF_CLK_PAG2S5_PCE_REF_CLK_NAG1S4_PCE_REF_CLK_PAF5S4_PCE_REF_CLK_NAF4S3_PCE_REF_CLK_PAE2S3_PCE_REF_CLK_NAE1S2_PCE_REF_CLK_PAD5S2_PCE_REF_CLK_NAD4S1_PCE_REF_CLK_PAC2S1_PCE_REF_CLK_NAC1S0_PCE_REF_CLK_PAB5S0_PCE_REF_CLK_NAB4CLKREQ_INIT_NM13R436110K1% R0402-0201<Part Number>NIU426BSN74LVC3G34DCTR3584R6392 33 R0402-0201C41860.1UF10%16VC0402-0201U426ASN74LVC3G34DCTR1784U426CSN74LVC3G34DCTR6284R6390 33 R0402-0201R6393 33 R0402-0201CLK_100M_DB2000QL_PEX1_S1_R_DPCLK_100M_DB2000QL_PEX1_S1_R_DNCLK_100M_DB800ZL_PEX1_S0_R_DPCLK_100M_DB800ZL_PEX1_S0_R_DNCLK_100M_PEX1_REF_R_DPCLK_100M_PEX1_REF_R_DNIRQ_PEX1_CLKREQ_INT_NRST_PEX1_PERST_R_NRST_PEX1_S3_PERST_NRST_PEX1_S3_PERST_R_NRST_PEX1_S1_PERST_NRST_PEX1_S1_PERST_R_NRST_PEX1_S0_PERST_NRST_PEX1_S0_PERST_R_NRST_PEX1_S0_PERST_R_NRST_PEX1_S1_PERST_R_NRST_PEX1_S3_PERST_R_NCLK_100M_DB800ZL_PEX1_S3_R_DPCLK_100M_DB800ZL_PEX1_S3_R_DN



5
5
4
4
3
3
2
2
1
1
D D
C C
B B
A A
Add Test Point
PEX_1_GPIO(6/11)
DVT_CHANGEPEX1_DBG_MODE4 [28]PEX1_DBG_MODE3 [28]PEX1_MODE_SEL12 [28]PEX1_DBG_MODE2 [28]PEX1_MODE_SEL11 [28]PEX1_DBG_MODE1 [28]PEX1_MODE_SEL10 [28]PEX1_DBG_MODE0 [28]PEX1_MODE_SEL9 [28]PEX1_DBG_SEL1 [28]PEX1_MODE_SEL8 [28]PEX1_DBG_SEL0 [28]PEX1_MODE_SEL7 [28]PEX1_MODE_SEL6 [28]PEX1_MODE_SEL5 [28]PEX1_MODE_SEL4 [28]PEX1_MODE_SEL3 [28]PEX1_MODE_SEL2 [28,121]PEX1_MODE_SEL1 [28,121]PEX1_MODE_SEL0 [28]PEX1_DBG_MODE4[28]PEX1_DBG_MODE3[28]PEX1_DBG_MODE2[28]PEX1_DBG_MODE1[28]PEX1_DBG_MODE0[28]PEX1_DBG_SEL1[28]PEX1_DBG_SEL0[28]PEX1_MODE_SEL12[28]PEX1_MODE_SEL11[28]PEX1_MODE_SEL10[28]PEX1_MODE_SEL9[28]PEX1_MODE_SEL8[28]PEX1_MODE_SEL7[28]PEX1_MODE_SEL6[28]PEX1_MODE_SEL5[28]PEX1_MODE_SEL4[28]PEX1_MODE_SEL3[28]PEX1_MODE_SEL2[28,121]PEX1_MODE_SEL1[28,121]PEX1_MODE_SEL0[28]PEX1_SYS_ERR_R_N [28]RST_PEX1_SYS_N [118]UART_PEX1_SDB_TX [67]UART_PEX1_SDB_BUF_RX [67]UART_PEX1_CLI_TX [68]UART_PEX1_CLI_BUF_RX [68]PEX1_SYS_ERR_R_N[28]PEX1_PCA9555_INT_R_N [73]PEX1_SYS_ERR_FPGA [118]
P1V8_PEXP1V8_PEXP1V8_PEXP1V8_PEXP3V3_AUXP1V8_PEX
P1V8_PEXP3V3_LEDP1V8_PEXSizeDoc NumberRevDate: SheetofReviewerDesignerDepartmentProject
Page TitleCCBU D28 257Tuesday, August 29, 2023<project_name><Designer> GRANDTETON_SWB_20230829028 PEX_1_GPIO(6/11)<Reviewer>SizeDoc NumberRevDate: SheetofReviewerDesignerDepartmentProject
Page TitleCCBU D28 257Tuesday, August 29, 2023<project_name><Designer> GRANDTETON_SWB_20230829028 PEX_1_GPIO(6/11)<Reviewer>SizeDoc NumberRevDate: SheetofReviewerDesignerDepartmentProject
Page TitleCCBU D28 257Tuesday, August 29, 2023<project_name><Designer> GRANDTETON_SWB_20230829028 PEX_1_GPIO(6/11)<Reviewer>
R12911KR0402-02011%NIR13011KR0402-02011%R12741KR0402-02011%NIR12651KR0402-02011%NIR12821KR0402-02011%
12/26PEX1LSS26-0A0P-01GPIO31AV13GPIO30AV12GPIO29AW12GPIO28AW16GPIO27AV17GPIO26AV16GPIO25AW13GPIO24AW17GPIO23AV14GPIO21AW14GPIO20AW18GPIO19AV19GPIO18AV15GPIO17AW15GPIO16AW19GPIO15AV36GPIO14AU39GPIO13AW35GPIO12AJ39GPIO11AN39GPIO10AM38GPIO9AR39GPIO8AP39GPIO7AR38GPIO6AP38GPIO5AM39GPIO4AU38GPIO3AV39GPIO2AT39GPIO1AV34GPIO0AW39GPIO63M24GPIO62L23GPIO61M23GPIO60M22GPIO59L22GPIO58L24GPIO57AV23GPIO56AW22GPIO55AV22GPIO54AV21GPIO53M32GPIO52L31GPIO51M34GPIO50N39GPIO49L29GPIO48M33GPIO47AW21GPIO46AW23GPIO45L33GPIO44M31GPIO43M30GPIO42L35GPIO41AN38GPIO40AL38GPIO39AW37GPIO38AV37GPIO37AV38GPIO36AV35GPIO35AW36GPIO34AV33GPIO33AT38GPIO32AW33EXT_GPIO_LATCH_NL37GPIO22AV18R13284.7KR0402-02011%  R1322 0 R0402-02015%R12921KR0402-02011%R13081KR0402-02011%NIR12751KR0402-02011%NIR12661KR0402-02011%NIR12831KR0402-02011%R131310KR0402-02015%R396110KR0402-02015%Q14BBSS138BKS<Part Number>D23G25S24
R12931KR0402-02011%R13091KR0402-02011%R132410K R0402-02015%
R12761KR0402-02011%NIR131110K 1%R0402-0201R12671KR0402-02011%NIR12841KR0402-02011%NI R131410KR0402-02015%R12941KR0402-02011%R13101KR0402-02011%NIR12771KR0402-02011%NIR13021KR0402-02011%NIR131510KR0402-02015%Q14ABSS138BKS<Part Number>S11G12D16
R12681KR0402-02011%NIR12851KR0402-02011%R131210K 1%R0402-0201<Part Number>R12951KR0402-02011%R13254.75K R0402-02011%
R12781KR0402-02011%R12691KR0402-02011%NIR12861KR0402-02011%R131610KR0402-02015%R13031KR0402-02011%NIR61544.7KR0402-02011%  
R12961KR0402-02011%R132310K R0402-02015%R12791KR0402-02011%NIR131710KR0402-02015%R12871KR0402-02011%R12701KR0402-02011%R13041KR0402-02011%NIR12971KR0402-02011%R12801KR0402-02011%R12881KR0402-02011%R131810KR0402-02015%R417710KR0402-02015%NI
R12711KR0402-02011%R13051KR0402-02011%NIR12981KR0402-02011%NIR13264.75K R0402-02011% R132749.9<Part Number>R0402-02011%1/16W
R12621KR0402-02011%NI R131910KR0402-02015%R12811KR0402-02011%NI11/26PEX1KSS26-0A0P-01DBG_MODE4AW34DBG_MODE3AW26DBG_MODE2AW30DBG_MODE1L13DBG_MODE0L12DBG_SEL1M19DBG_SEL0L18MODE_SEL12AW32MODE_SEL11AW31MODE_SEL10AV32MODE_SEL9AV28MODE_SEL8AW29MODE_SEL7AV26MODE_SEL6AV31MODE_SEL5AW25MODE_SEL4AW28MODE_SEL3AV27MODE_SEL2AV25MODE_SEL1AW38MODE_SEL0AW27AVG_TRST_LM18AVG_TCKM15AVG_TDIL17AVG_TDOL19AVG_TMSM20AVG_PAD_TRI_LL16AVG_TR_TCKL20AVG_ATPG_MODE_LL15SHPC_INT_NAV29SPARE7M27SPARE6L28SPARE5L25SPARE4M25SPARE3L32SPARE2L27SPARE1L30SPARE0M26DFT_IDDTM16ADCTEMP_VINP0Y39ADCTEMP_VINP1AA39SYS_ERROR_NAV30SYS_PWR_ON_RST_NM17SDB_TXAL39SDB_RXAK39UART_TXAJ38UART_RXAK38R5800 33 R0402-02011%
R12721KR0402-02011%NIR12991KR0402-02011%R13061KR0402-02011%NI
R4178 1K R0402-02011%NI
R12891KR0402-02011%R12631KR0402-02011%NI R132010KR0402-02015%NID2LED_BLUEAC
R12731KR0402-02011%NIR13001KR0402-02011%NIR12901KR0402-02011%NIR13071KR0402-02011%NIR12641KR0402-02011% R132110KR0402-02015%PEX1_DBG_MODE4PEX1_DBG_MODE3PEX1_MODE_SEL12PEX1_DBG_MODE2PEX1_MODE_SEL11PEX1_DBG_MODE1PEX1_MODE_SEL10PEX1_DBG_MODE0PEX1_MODE_SEL9PEX1_DBG_SEL1PEX1_MODE_SEL8PEX1_DBG_SEL0PEX1_MODE_SEL7PEX1_MODE_SEL6PEX1_MODE_SEL5PEX1_MODE_SEL4PEX1_MODE_SEL3PEX1_MODE_SEL2PEX1_MODE_SEL1PEX1_MODE_SEL0PEX1_DBG_MODE4PEX1_DBG_MODE3PEX1_DBG_MODE2PEX1_DBG_MODE1PEX1_DBG_MODE0PEX1_SPARE7PEX1_DBG_SEL1PEX1_SPARE6PEX1_DBG_SEL0PEX1_SPARE5PEX1_SPARE4PEX1_MODE_SEL12PEX1_SPARE3PEX1_MODE_SEL11PEX1_SPARE2PEX1_MODE_SEL10PEX1_SPARE1PEX1_MODE_SEL9PEX1_SPARE0PEX1_MODE_SEL8PEX1_MODE_SEL7PEX1_DFT_IDDTPEX1_MODE_SEL6PEX1_MODE_SEL5PEX1_MODE_SEL4PEX1_MODE_SEL3PEX1_MODE_SEL2PEX1_MODE_SEL1PEX1_MODE_SEL0PEX1_SYS_ERR_NRST_PEX1_SYS_NTP_PEX1_TRST_LTP_PEX1_TCKTP_PEX1_TDIUART_PEX1_SDB_TXTP_PEX1_TDOUART_PEX1_SDB_BUF_RXTP_PEX1_TMSPU_PEX1_PAD_TRI_LUART_PEX1_CLI_TXPU_PEX1_TR_TCKUART_PEX1_CLI_BUF_RXPU_PEX1_ATPG_MODE_LPEX1_SYS_ERR_3V3_NLED_PEX1_SYS_ERR_NPEX1_SYS_ERR_N_GPEX1_ADCTEMP_VINP0PEX1_ADCTEMP_VINP1
PEX1_EXT_GPIO_LATCH_N



5
5
4
4
3
3
2
2
1
1
D D
C C
B B
A A
FLASH SOCKET
To FPGA
PEX VER. B0
PCA9555 3.3V Port PEX 1.8V Port
PEX VER. A0
Pull UP 3V3
CO-LAYOUT
PEX_1_FLASH(7/11)
SEL_FLASH_PEX1_BUF_R[63,88]SPI_PEX1_CS_MUX_N[29]SPI_PEX1_CLK_MUX[29]SPI_PEX1_CLK_R [29]SPI_BIC1_CLK_LS01_R2 [63]SPI_PEX1_CS_R_N [29]SPI_BIC1_CS0_LS01_R2_N [63]SPI_PEX1_CS_MUX_N[29]SPI_PEX1_CLK_MUX[29]SPI_BIC1_MISO_LS01_R2 [63]SPI_BIC1_MOSI_LS01_R2 [63]SPI_PEX1_SDIO1_MUX[29]SPI_PEX1_SDIO0_MUX[29]SPI_PEX1_SDIO0_MUX[29]SPI_PEX1_SDIO1_MUX [29]SPI_PEX1_SDIO1_R [29]SPI_PEX1_SDIO0_R [29]SPI_PEX1_SDIO2_R[29]SPI_PEX1_SDIO3_R[29]
I2C_PEX1_HOST_R_SDA [29]I2C_PEX1_HOST_R_SCL [29]SMB_PEX1_SDA [95]SMB_PEX1_SCL [95]
SMB_PEX1_PCA9555_SCL[73]I2C_PEX1_HOST_R_SCL [29]SMB_PEX1_PCA9555_SDA[73]I2C_PEX1_HOST_R_SDA [29]SMB_PEX1_FPGA_SCL[115]SMB_PEX1_FPGA_SDA[115]
SPI_PEX1_CS_R_N[29]SPI_PEX1_CLK_R[29]SPI_PEX1_SDIO3_R[29]SPI_PEX1_SDIO2_R[29]SPI_PEX1_SDIO1_R[29]SPI_PEX1_SDIO0_R[29]
PWRGD_P1V8_PEX_R[16,42,55,95,118,233]
SPI_PEX1_RST_R_N[29]
SPI_PEX1_RST_R_N [29]P3V3_AUX
P1V8_PEXP1V8_PEXP3V3_AUXP1V8_PEX
P1V8_PEXP1V8_PEX
P1V8_PEX
SizeDoc NumberRevDate: SheetofReviewerDesignerDepartmentProject
Page TitleCCBU D29 257Tuesday, August 29, 2023<project_name><Designer> GRANDTETON_SWB_20230829029 PEX_1_FLASH(7/11)<Reviewer>SizeDoc NumberRevDate: SheetofReviewerDesignerDepartmentProject
Page TitleCCBU D29 257Tuesday, August 29, 2023<project_name><Designer> GRANDTETON_SWB_20230829029 PEX_1_FLASH(7/11)<Reviewer>SizeDoc NumberRevDate: SheetofReviewerDesignerDepartmentProject
Page TitleCCBU D29 257Tuesday, August 29, 2023<project_name><Designer> GRANDTETON_SWB_20230829029 PEX_1_FLASH(7/11)<Reviewer>U314PCA9617ADP<Part Number>EN5VCCA1VCCB8SCLA2SDAA3SDAB6SCLB7GND4U320W25Q256JWFIQNI<Part Number>HOLD#||RESET_IO3#1VCC2RESET#3NC14NC25NC36CS#7DO_IO18CLK16DI_IO015NC714NC613NC512NC411GND10WP_N_IO29
R3451 0 R0402-02015%R6165 0 R0402-02015%
R61674.75K1%R0402-0201<Part Number>
C23070.1UF10%16VC0402-0201R3463 0 R0402-02015%JPEX1SCONN16_ACASPI006P07<Part Number>VCC2HOLD_N1CS_N7WP_N9SI15SCK16VSS10SO8NC3PO24PO15PO06PO311PO412PO513PO614
R3929 33 R0402-02011%
R34671K<Part Number>R0402-02011%
R3452 0 R0402-02015%R3459 4.7K R0402-02011%R3464 0 R0402-02015%R39334.7KR0402-02015%R3937 33 R0402-02011%
R6807 33 R0402-02011%R3930 0 R0402-02015%
R3939 33 R0402-02011%
R3453 0 R0402-02015%
R39344.7KR0402-02015%R34661K<Part Number>R0402-02011%
R3925 0 R0402-02015%NI
R3461 0 R0402-02015%C27560.1UF10%16VC0402-0201R3940 0 R0402-02015%JPEX1_FW1<Part Number>1R3931 0 R0402-02015%R3926 0 R0402-02015%
R3460 0 R0402-02015%R3454 0 R0402-02015%C23080.1UF10%16VC0402-0201R6808 33 R0402-02011%
C27570.1UF10%16VC0402-0201R3465 0 R0402-02015%R3941 0 R0402-02015%NI
R3932 0 R0402-02015%U66PI3CH480QEXS1E#15YA4YB7D113YC9YD12D014C110C011B16B05A13A02VCC16GND8 R34681K<Part Number>R0402-02011%NI
R6717 33 R0402-02011%C27830.1UF10%16VC0402-0201
R3927 0 R0402-02015%NI
R3938 0 R0402-02015%R34691K<Part Number>R0402-02011%NI
R394410K1% R0402-0201<Part Number>R3455 0 R0402-02015%R6718 0 R0402-02015%
R40152K1/16W1%R0402-0201R3942 0 R0402-02015%NIR61661KR0402-02011%NI<Part Number>R3462 0 R0402-02015%14/26PEX1NSS26-0A0P-01MXSTEST_0_TST1AN36MXSTEST_0_TST0AP36MXSTEST_1_TST1AT36MXSTEST_1_TST0AR36MXSTEST_2_TST1AP14MXSTEST_2_TST0AN14MXSTEST_3_TST1U36MXSTEST_3_TST0P36MXSTEST_4_TST1T36MXSTEST_4_TST0R36MXSTEST_5_TST1T14MXSTEST_5_TST0U14MXSTEST_6_TST1AA35MXSTEST_6_TST0AB35CLKOBSAK5CLKOBS_NAK413/26PEX1MSS26-0A0P-01SPI0_CS_N1AJ8SPI0_CS_N0AK7SPI0_FLASH_CS_NAJ7SPI0_RST_NAG7SPI0_CLKAH7SPI0_SDIO3AH8SPI0_SDIO2AG8SPI0_SDIO1AF8SPI0_SDIO0AF7SPI1_CS_N1AB7SPI1_CS_N0AB8SPI1_RST_NAD7SPI1_CLKAE7SPI1_SDIO3AE8SPI1_SDIO2AC8SPI1_SDIO1AD8SPI1_SDIO0AC7SIO_BLINKL26I2C0_SDAM39I2C0_SCLM35I2C1_SDAM37I2C1_SCLL38I2C2_SDAL36I2C2_SCLM36I2C3_SDAM38I2C3_SCLL34I2C_S_SDAL39I2C_S_SCLN38SHPC_SDAM28SHPC_SCLM29
R40162K1/16W1%<Part Number>R0402-0201R3948 0 R0402-02015%
R3928 0 R0402-02015%R61581KR0402-02011%R3456 0 R0402-02015%SPI_PEX1_CS_MUX_NSPI_PEX1_SDIO1_MUXSPI_PEX1_SDIO1_RSPI_BIC1_MISO_LS01_R2SPI_PEX1_CS_R_NSPI_BIC1_CS0_LS01_R2_NSEL_FLASH_PEX1_BUF_RSPI_PEX1_SDIO0_MUXSPI_PEX1_CLK_MUXSPI_PEX1_SDIO0_RSPI_BIC1_MOSI_LS01_R2SPI_PEX1_CLK_RSPI_BIC1_CLK_LS01_R2SPI_MUX_PEX1_EN_NSPI_PEX1_SDIO1_MUX_RSPI_PEX1_SDIO1_MUXSPI_PEX1_SDIO3_RSPI_PEX1_SDIO3_R1SPI_PEX1_CS_MUX_NSPI_PEX1_CS_MUX_R_NSPI_PEX1_SDIO2_RSPI_PEX1_SDIO2_R1SPI_PEX1_SDIO0_MUXSPI_PEX1_SDIO0_MUX_RSPI_PEX1_CLK_MUXSPI_PEX1_CLK_MUX_RSPI_PEX1_CS_MUX_R_NSPI_PEX1_SDIO3_R1SPI_PEX1_SDIO2_R1
I2C0_PEX1_SDAI2C_PEX1_HOST_SDAI2C0_PEX1_SCLI2C_PEX1_HOST_SCLSMB_PEX1_SLAVE_SDASMB_PEX1_SLAVE_SCLI2C0_PEX1_SHPC_SDAI2C0_PEX1_SHPC_SCL
SMB_PEX1_HOST_LS_SCLSMB_PEX1_HOST_LS_SDA
SPI_PEX1_CS_R_NSPI_PEX1_CS_NSPI_PEX1_CLK_RSPI_PEX1_CLKSPI_PEX1_SDIO3_RSPI_PEX1_SDIO3SPI_PEX1_SDIO2_RSPI_PEX1_SDIO2SPI_PEX1_SDIO1_RSPI_PEX1_SDIO1SPI_PEX1_SDIO0_RSPI_PEX1_SDIO0PU_PEX1_SIO_BLINK
PWRGD_P1V8_PEX1_RSPI_PEX1_CLK_MUX_RSPI_PEX1_CS_MUX_R_NSPI_PEX1_SDIO3_R1SPI_PEX1_SDIO2_R1SPI_PEX1_SDIO1_MUX_RSPI_PEX1_SDIO0_MUX_R
SPI_PEX1_RST_R_NSPI_PEX1_RST_N
SPI_PEX1_RST_R_NSPI_PEX1_RST_R_NSPI_PEX1_RST_R_N
SMB_PEX1_SLAVE1_SCLSMB_PEX1_SLAVE1_SDASMB_PEX1_R_SDASMB_PEX1_R_SCL



5
5
4
4
3
3
2
2
1
1
D D
C C
B B
A A
PEX0 P1V25_SERDES_VDDHTXDECOUPLING INFO.
Item QTY.
BGA BALLs 41
1000pF(0201) Caps
0.1uF(0201) Caps
1uF(0201) Caps
10uF(0603) Caps
11
25
5
2
PEX0 P1V25_SERDES_VDDHPLLDECOUPLING INFO.
Item QTY.
41BGA BALLs
1000pF(0201) Caps 11
0.1uF(0201) Caps 25
1uF(0201) Caps 5
10uF(0603) Caps 2
1
1
8
4
QTY.
13
PEX0 P1V8_SWDECOUPLING INFO.
10uF(0603) Caps
1uF(0201) Caps
0.1uF(0201) Caps
1000pF(0201) Caps
BGA BALLs
Item
1
1
8
4
QTY.
9
PEX0 P1V8_VDDADECOUPLING INFO.
10uF(0603) Caps
1uF(0201) Caps
0.1uF(0201) Caps
1000pF(0201) Caps
BGA BALLs
Item
Add Test Point
PEX_1_PWR_Cap_1(8/11)
VSENSE_P0V8_PEX1_SKT_VRTN[223]VSENSE_P0V8_PEX1_SKT_VSEN[223]
P1V25_PEX1P1V25_SERDES_VDDPLL_PEX1P1V8_VDDA_PEX1P0V8_PEX1P0V8_PEX1P1V25_PEX1P1V25_SERDES_VDDPLL_PEX1
P0V8_SERDES_VDDA_PEX1P0V8_SERDES_VDDA_PEX1P1V8_PEXP1V8_VDDA_PEX1P1V8_PEXPCEPLL7_VDDA18_PEX1PCEPLL6_VDDA18_PEX1PCEPLL5_VDDA18_PEX1PCEPLL4_VDDA18_PEX1PCEPLL3_VDDA18_PEX1PCEPLL2_VDDA18_PEX1PCEPLL1_VDDA18_PEX1PCEPLL0_VDDA18_PEX1SYSPLL_VDDA18_PEX1
SizeDoc NumberRevDate: SheetofReviewerDesignerDepartmentProject
Page TitleCCBU D30 257Tuesday, August 29, 2023<project_name><Designer> GRANDTETON_SWB_20230829030 PEX_1_PWR_Cap_1(8/11)<Reviewer>SizeDoc NumberRevDate: SheetofReviewerDesignerDepartmentProject
Page TitleCCBU D30 257Tuesday, August 29, 2023<project_name><Designer> GRANDTETON_SWB_20230829030 PEX_1_PWR_Cap_1(8/11)<Reviewer>SizeDoc NumberRevDate: SheetofReviewerDesignerDepartmentProject
Page TitleCCBU D30 257Tuesday, August 29, 2023<project_name><Designer> GRANDTETON_SWB_20230829030 PEX_1_PWR_Cap_1(8/11)<Reviewer>
C31261000PFC02015%16VC30901000PFC02015%16V
C31750.1UFC020110%6.3VC316310UFC060320%6.3VC31760.1UFC020110%6.3V
C31140.1UFC020110%6.3VC31410.1UFC020110%6.3VC31500.1UFC020110%6.3VC31030.1UFC020110%6.3VC30881000PFC02015%16VC31540.1UFC020110%6.3VC31770.1UFC020110%6.3VC31820.1UFC020110%6.3VC31641UFC020120%4V
C30851UFC020120%4VC308210UFC060320%6.3VC31331000PFC02015%16VC31351000PFC02015%16VC31850.1UFC020110%6.3V
C30950.1UFC020110%6.3VC31251000PFC02015%16VC30831UFC020120%4V
C31490.1UFC020110%6.3VC31241UFC020120%4VC30930.1UFC020110%6.3VC30841UFC020120%4VC31390.1UFC020110%6.3VC31321000PFC02015%16VC31440.1UFC020110%6.3VC30960.1UFC020110%6.3VC30980.1UFC020110%6.3VC31010.1UFC020110%6.3V
C31721000PFC02015%16V
C31160.1UFC020110%6.3VC31271000PFC02015%16VC31150.1UFC020110%6.3VC31341000PFC02015%16VC30891000PFC02015%16VC30861UFC020120%4VC31050.1UFC020110%6.3VC31020.1UFC020110%6.3VC31430.1UFC020110%6.3VC31170.1UFC020110%6.3V
C31870.1UFC020110%6.3VC31830.1UFC020110%6.3V
16/26PEX1PSS26-0A0P-01PCEPLL7_VDDA18AJ13PCEPLL6_VDDA18AH12PCEPLL5_VDDA18AG13PCEPLL4_VDDA18AF12PCEPLL3_VDDA18AE13PCEPLL2_VDDA18AD12PCEPLL1_VDDA18AB12PCEPLL0_VDDA18AA13SYSPLL_VDDA18AC13EDM_VDDW38VDDQ_EFUSEAM12VDD18_V35V35VDD18_W35W35VDD18_Y12Y12VDD18_Y35Y35VDD18_AE10AE10VDD18_AF10AF10VDD18_AH10AH10VDD18_AJ10AJ10VDD18_AK10AK10VDD18_AK12AK12VDD18_AK35AK35VDD18_AL35AL35VDD18_AM35AM35VDDA18_T35T35VDDA18_V14V14VDDA18_AA10AA10VDDA18_AA34AA34VDDA18_AA37AA37VDDA18_AB10AB10VDDA18_AC10AC10VDDA18_AM14AM14VDDA18_AP35AP35VDDA_SENSEAL15VSSA_SENSEAL14VDD_SENSEV39VSS_SENSEW39C30921000PFC02015%16V
C31740.1UFC020110%6.3VC31711000PFC02015%16VC31681000PFC02015%16VC31291000PFC02015%16VC31000.1UFC020110%6.3VC30871000PFC02015%16V
C31621UFC020120%4V
C31040.1UFC020110%6.3VC31110.1UFC020110%6.3VC31380.1UFC020110%6.3VC31231UFC020120%4VC30911000PFC02015%16VC31060.1UFC020110%6.3V15/26PEX1O
SS26-0A0P-01
VDD125_V16V16VDD125_V17V17VDD125_V18V18VDD125_V19V19VDD125_V20V20VDD125_V21V21VDD125_V22V22VDD125_V23V23VDD125_V24V24VDD125_V25V25VDD125_V26V26VDD125_V27V27VDD125_V28V28VDD125_V29V29VDD125_V30V30VDD125_V31V31VDD125_V32V32VDD125_V33V33VDD125_AC36AC36VDD125_AD36AD36VDD125_AE36AE36VDD125_AF36AF36VDD125_AG36AG36VDD125_AM16AM16VDD125_AM17AM17VDD125_AM18AM18VDD125_AM19AM19VDD125_AM20AM20VDD125_AM21AM21VDD125_AM22AM22VDD125_AM23AM23VDD125_AM24AM24VDD125_AM25AM25VDD125_AM26AM26VDD125_AM27AM27VDD125_AM28AM28VDD125_AM29AM29VDD125_AM30AM30VDD125_AM31AM31VDD125_AM32AM32VDD125_AM33AM33VDD_Y14Y14VDD_AA15AA15VDD_AB14AB14VDD_AC15AC15VDD_AC17AC17VDD_AC19AC19VDD_AC21AC21VDD_AC23AC23VDD_AC25AC25VDD_AC27AC27VDD_AC29AC29VDD_AC31AC31VDD_AC33AC33VDD_AD14AD14VDD_AD16AD16VDD_AD18AD18VDD_AD20AD20VDD_AD22AD22VDD_AD24AD24VDD_AD26AD26VDD_AD28AD28VDD_AD30AD30VDD_AE15AE15VDD_AE17AE17VDD_AE19AE19VDD_AE21AE21VDD_AE23AE23
VDDA125_T16T16VDDA125_T17T17VDDA125_T18T18VDDA125_T19T19VDDA125_T20T20VDDA125_T21T21VDDA125_T22T22VDDA125_T23T23VDDA125_T24T24VDDA125_T25T25VDDA125_T26T26VDDA125_T27T27VDDA125_T28T28VDDA125_T29T29VDDA125_T30T30VDDA125_T31T31VDDA125_T32T32VDDA125_T33T33VDDA125_AC38AC38VDDA125_AD38AD38VDDA125_AE38AE38VDDA125_AF38AF38VDDA125_AG38AG38VDDA125_AP16AP16VDDA125_AP17AP17VDDA125_AP18AP18VDDA125_AP19AP19VDDA125_AP20AP20VDDA125_AP21AP21VDDA125_AP22AP22VDDA125_AP23AP23VDDA125_AP24AP24VDDA125_AP25AP25VDDA125_AP26AP26VDDA125_AP28AP28VDDA125_AP29AP29VDDA125_AP30AP30VDDA125_AP31AP31VDDA125_AP32AP32VDDA125_AP33AP33VDD_AE25AE25VDD_AE27AE27VDD_AE29AE29VDD_AE31AE31VDD_AF14AF14VDD_AF16AF16VDD_AF18AF18VDD_AF20AF20VDD_AF22AF22VDD_AF24AF24VDD_AF26AF26VDD_AF28AF28VDD_AF30AF30VDD_AG15AG15VDD_AG17AG17VDD_AG19AG19VDD_AG21AG21VDD_AG23AG23VDD_AG25AG25VDD_AG27AG27VDD_AG29AG29VDD_AG31AG31VDD_AG33AG33VDD_AH14AH14VDD_AJ15AJ15VDD_AK14AK14VDDA125_AP27AP27C31550.1UFC020110%6.3VC31701000PFC02015%16VC31860.1UFC020110%6.3VC31201UFC020120%4VC31780.1UFC020110%6.3VC31651000PFC02015%16V
C31090.1UFC020110%6.3VC31460.1UFC020110%6.3VC31480.1UFC020110%6.3VC31671000PFC02015%16VC31370.1UFC020110%6.3VC31130.1UFC020110%6.3VC31661000PFC02015%16VC31470.1UFC020110%6.3VC31120.1UFC020110%6.3VC31450.1UFC020110%6.3VC31810.1UFC020110%6.3VC31560.1UFC020110%6.3VC31590.1UFC020110%6.3VC31520.1UFC020110%6.3VC31070.1UFC020110%6.3V
C31790.1UFC020110%6.3VC31281000PFC02015%16VC31880.1UFC020110%6.3V
C30940.1UFC020110%6.3VC30781000PFC02015%16VC30771000PFC02015%16V
C31800.1UFC020110%6.3V
C30801000PFC02015%16VC31600.1UFC020110%6.3VC31221UFC020120%4VC31840.1UFC020110%6.3VC31301000PFC02015%16VC31100.1UFC020110%6.3VC31311000PFC02015%16VC31211UFC020120%4VC31400.1UFC020110%6.3VC31570.1UFC020110%6.3VC31691000PFC02015%16V
C30761UFC020120%4VC311810UFC060320%6.3VC30990.1UFC020110%6.3VC30791000PFC02015%16VC30970.1UFC020110%6.3VC307510UFC060320%6.3V
C316110UFC060320%6.3VC311910UFC060320%6.3VC31080.1UFC020110%6.3VC31530.1UFC020110%6.3VC31510.1UFC020110%6.3VC31580.1UFC020110%6.3V17/26PEX1QSS26-0A0P-01VDDA_Y16Y16VDDA_Y17Y17VDDA_Y18Y18VDDA_Y19Y19VDDA_Y20Y20VDDA_Y21Y21VDDA_Y22Y22VDDA_Y23Y23VDDA_Y24Y24VDDA_Y25Y25VDDA_Y26Y26VDDA_Y27Y27VDDA_Y28Y28VDDA_Y29Y29VDDA_Y30Y30VDDA_Y31Y31VDDA_Y32Y32VDDA_Y33Y33VDDA_AB16AB16VDDA_AB17AB17VDDA_AB18AB18VDDA_AB19AB19VDDA_AB20AB20VDDA_AB21AB21VDDA_AB22AB22VDDA_AB23AB23VDDA_AB24AB24VDDA_AB25AB25VDDA_AB26AB26VDDA_AB27AB27VDDA_AB28AB28VDDA_AB29AB29VDDA_AB30AB30VDDA_AB31AB31VDDA_AB32AB32VDDA_AB33AB33VDDA_AD32AD32VDDA_AD33AD33VDDA_AD34AD34VDDA_AE33AE33VDDA_AE34AE34VDDA_AF32AF32VDDA_AF33AF33VDDA_AF34AF34VDDA_AH16AH16VDDA_AH17AH17VDDA_AH18AH18VDDA_AH19AH19VDDA_AH20AH20VDDA_AH21AH21VDDA_AH22AH22VDDA_AH23AH23VDDA_AH24AH24VDDA_AH25AH25VDDA_AH26AH26VDDA_AH27AH27VDDA_AH28AH28VDDA_AH29AH29VDDA_AH30AH30VDDA_AH31AH31VDDA_AH32AH32VDDA_AH33AH33VDDA_AK16AK16VDDA_AK17AK17VDDA_AK18AK18VDDA_AK19AK19VDDA_AK20AK20VDDA_AK21AK21VDDA_AK22AK22VDDA_AK23AK23VDDA_AK24AK24VDDA_AK25AK25VDDA_AK26AK26VDDA_AK27AK27VDDA_AK28AK28VDDA_AK29AK29VDDA_AK30AK30VDDA_AK31AK31VDDA_AK32AK32VDDA_AK33AK33C31420.1UFC020110%6.3VC31360.1UFC020110%6.3VC30811000PFC02015%16V
C31730.1UFC020110%6.3VTP_PEX1_VDDQ_EFUSE



5
5
4
4
3
3
2
2
1
1
D D
C C
B B
A A
10uF(0603) Caps
BGA BALLs
1uF(0201) Caps
1uF(0201) Caps
0.1uF(0201) Caps
80
1000pF(0201) Caps
44
BGA BALLs
Item
Item
0.1uF(0201) Caps
3
PEX1 P0V8_SERDES_VDDADECOUPLING INFO.
4
33
30
4
17
1000pF(0201) Caps
QTY.
10uF(0603) Caps
QTY.
53
PEX1 P0V8DECOUPLING INFO.
6
PEX_1_PWR_Cap_2(9/11)
P0V8_PEX1P0V8_SERDES_VDDA_PEX1
SizeDoc NumberRevDate: SheetofReviewerDesignerDepartmentProject
Page TitleCCBU D31 257Tuesday, August 29, 2023<project_name><Designer> GRANDTETON_SWB_20230829031 PEX_1_PWR_Cap_2(9/11)<Reviewer>SizeDoc NumberRevDate: SheetofReviewerDesignerDepartmentProject
Page TitleCCBU D31 257Tuesday, August 29, 2023<project_name><Designer> GRANDTETON_SWB_20230829031 PEX_1_PWR_Cap_2(9/11)<Reviewer>SizeDoc NumberRevDate: SheetofReviewerDesignerDepartmentProject
Page TitleCCBU D31 257Tuesday, August 29, 2023<project_name><Designer> GRANDTETON_SWB_20230829031 PEX_1_PWR_Cap_2(9/11)<Reviewer>
C13890.1UFC020110%6.3VC14700.1UFC020110%6.3VC14461000PFC02015%16VC14301000PFC02015%16VC13960.1UFC020110%6.3VC14610.1UFC020110%6.3VC141510UFC060320%6.3VC13931000PFC02015%16V
C14520.1UFC020110%6.3VC14910.1UFC020110%6.3V
C13651000PFC02015%16V
C14820.1UFC020110%6.3V
C13581UFC020120%4VC14030.1UFC020110%6.3VC14730.1UFC020110%6.3VC14710.1UFC020110%6.3VC14471000PFC02015%16VC13980.1UFC020110%6.3VC14311000PFC02015%16VC13820.1UFC020110%6.3VC14620.1UFC020110%6.3VC14221000PFC02015%16VC13940.1UFC020110%6.3VC13721000PFC02015%16V
C14530.1UFC020110%6.3VC14161UFC020120%4VC14920.1UFC020110%6.3V
C13911000PFC02015%16V
C14830.1UFC020110%6.3V
C13591UFC020120%4VC14040.1UFC020110%6.3VC14740.1UFC020110%6.3V
C13900.1UFC020110%6.3VC14720.1UFC020110%6.3VC14481000PFC02015%16VC14321000PFC02015%16VC14391000PFC02015%16VC13830.1UFC020110%6.3VC14630.1UFC020110%6.3VC14231000PFC02015%16VC13731000PFC02015%16V
C14540.1UFC020110%6.3VC14171UFC020120%4VC13760.1UFC020110%6.3V
C14930.1UFC020110%6.3V
C13661000PFC02015%16V
C14840.1UFC020110%6.3V
C13601UFC020120%4VC14050.1UFC020110%6.3VC14750.1UFC020110%6.3V
C13990.1UFC020110%6.3VC14491000PFC02015%16VC14331000PFC02015%16VC13840.1UFC020110%6.3VC14640.1UFC020110%6.3VC14401000PFC02015%16VC14241000PFC02015%16VC14181UFC020120%4VC13770.1UFC020110%6.3VC13741000PFC02015%16V
C14550.1UFC020110%6.3VC14940.1UFC020110%6.3V
C13671000PFC02015%16V
C14850.1UFC020110%6.3V
C13611UFC020120%4VC14060.1UFC020110%6.3VC14760.1UFC020110%6.3VC14501000PFC02015%16VC14341000PFC02015%16VC13850.1UFC020110%6.3VC14650.1UFC020110%6.3VC14411000PFC02015%16V
18/26PEX1R
SS26-0A0P-01
VSS_A2A2VSS_A4A4VSS_A6A6VSS_A8A8VSS_A10A10VSS_A12A12VSS_A14A14VSS_A16A16VSS_A18A18VSS_A20A20VSS_A22A22VSS_A24A24VSS_A26A26VSS_A28A28VSS_A30A30VSS_A32A32VSS_A34A34VSS_A36A36VSS_A38A38VSS_A40A40VSS_A42A42VSS_A44A44VSS_A46A46VSS_A48A48VSS_B1B1VSS_B2B2VSS_B4B4VSS_B6B6VSS_B8B8VSS_B10B10VSS_B12B12VSS_B14B14VSS_B16B16VSS_B18B18VSS_B20B20VSS_B22B22VSS_B24B24VSS_B26B26VSS_B28B28VSS_B30B30VSS_B32B32VSS_B34B34VSS_B36B36VSS_B38B38VSS_B40B40VSS_B42B42VSS_B44B44VSS_B46B46VSS_B48B48VSS_B49B49VSS_C3C3VSS_C5C5VSS_C7C7VSS_C9C9VSS_C11C11VSS_C13C13VSS_C15C15VSS_C17C17VSS_C19C19VSS_C21C21VSS_C23C23VSS_C25C25VSS_C27C27VSS_C29C29VSS_C31C31VSS_C33C33VSS_C35C35VSS_C37C37VSS_C39C39VSS_C41C41VSS_C43C43VSS_C45C45VSS_C47C47VSS_D1D1VSS_D2D2VSS_D3D3VSS_D5D5VSS_D7D7VSS_D9D9VSS_D11D11
VSS_D13D13VSS_D15D15VSS_D17D17VSS_D19D19VSS_D21D21VSS_D23D23VSS_D25D25VSS_D27D27VSS_D29D29VSS_D31D31VSS_D33D33VSS_D35D35VSS_D37D37VSS_D39D39VSS_D41D41VSS_D43D43VSS_D45D45VSS_D47D47VSS_D48D48VSS_D49D49VSS_E3E3VSS_E4E4VSS_E6E6VSS_E7E7VSS_E8E8VSS_E9E9VSS_E10E10VSS_E11E11VSS_E12E12VSS_E13E13VSS_E14E14VSS_E15E15VSS_E16E16VSS_E17E17VSS_E18E18VSS_E19E19VSS_E20E20VSS_E21E21VSS_E22E22VSS_E23E23VSS_E24E24VSS_E25E25VSS_E26E26VSS_E27E27VSS_E28E28VSS_E29E29VSS_E30E30VSS_E31E31VSS_E32E32VSS_E33E33VSS_E34E34VSS_E35E35VSS_E36E36VSS_E37E37VSS_E38E38VSS_E40E40VSS_E41E41VSS_E42E42VSS_E43E43VSS_E44E44VSS_E45E45VSS_E46E46VSS_E47E47VSS_F1F1VSS_F2F2VSS_F4F4VSS_F6F6VSS_F8F8VSS_F10F10VSS_F12F12VSS_F14F14VSS_F16F16VSS_F18F18VSS_F20F20VSS_F22F22VSS_F24F24VSS_F26F26VSS_F28F28VSS_E39E39VSS_E5E519/26PEX1S
SS26-0A0P-01
VSS_F30F30VSS_F32F32VSS_F34F34VSS_F38F38VSS_F40F40VSS_F42F42VSS_F44F44VSS_F46F46VSS_F48F48VSS_F49F49VSS_G1G1VSS_G2G2VSS_G4G4VSS_G6G6VSS_G8G8VSS_G10G10VSS_G12G12VSS_G14G14VSS_G16G16VSS_G18G18VSS_G20G20VSS_G22G22VSS_G24G24VSS_G26G26VSS_G28G28VSS_G30G30VSS_G32G32VSS_G34G34VSS_G36G36VSS_G38G38VSS_G40G40VSS_G42G42VSS_G44G44VSS_G46G46VSS_G48G48VSS_G49G49VSS_H3H3VSS_H5H5VSS_H7H7VSS_H9H9VSS_H11H11VSS_H13H13VSS_H15H15VSS_H17H17VSS_H19H19VSS_H21H21VSS_H23H23VSS_H25H25VSS_H27H27VSS_H29H29VSS_H31H31VSS_H33H33VSS_H35H35VSS_H37H37VSS_H39H39VSS_H41H41VSS_H43H43VSS_H45H45VSS_H47H47VSS_J1J1VSS_J2J2VSS_J3J3VSS_J5J5VSS_J7J7VSS_J9J9VSS_J11J11VSS_J13J13VSS_J15J15VSS_J17J17VSS_J19J19VSS_J21J21VSS_J23J23VSS_J25J25VSS_J27J27VSS_J29J29VSS_J31J31VSS_J33J33VSS_J35J35VSS_J37J37
VSS_J39J39VSS_J41J41VSS_J43J43VSS_J45J45VSS_J47J47VSS_J48J48VSS_J49J49VSS_K3K3VSS_K4K4VSS_K5K5VSS_K6K6VSS_K7K7VSS_K8K8VSS_K9K9VSS_K10K10VSS_K11K11VSS_K12K12VSS_K13K13VSS_K14K14VSS_K15K15VSS_K16K16VSS_K17K17VSS_K18K18VSS_K19K19VSS_K20K20VSS_K21K21VSS_K22K22VSS_K23K23VSS_K24K24VSS_K25K25VSS_K26K26VSS_K27K27VSS_K28K28VSS_K29K29VSS_K30K30VSS_K31K31VSS_K32K32VSS_K33K33VSS_K34K34VSS_K35K35VSS_K36K36VSS_K37K37VSS_K38K38VSS_K39K39VSS_K40K40VSS_K41K41VSS_K42K42VSS_K43K43VSS_K44K44VSS_K45K45VSS_K46K46VSS_K47K47VSS_L1L1VSS_L2L2VSS_L5L5VSS_L8L8VSS_L9L9VSS_L10L10VSS_L11L11VSS_L14L14VSS_L21L21VSS_L40L40VSS_L41L41VSS_L42L42VSS_L45L45VSS_L48L48VSS_L49L49VSS_M3M3VSS_M4M4VSS_M5M5VSS_M6M6VSS_M7M7VSS_M10M10VSS_M11M11VSS_M12M12VSS_M14M14VSS_M21M21VSS_M40M40VSS_M43M43VSS_M44M44
VSS_F36F36C14251000PFC02015%16VC13780.1UFC020110%6.3VC13751000PFC02015%16V
C14560.1UFC020110%6.3VC14191UFC020120%4VC14950.1UFC020110%6.3V
C13681000PFC02015%16V
C14860.1UFC020110%6.3V
C14070.1UFC020110%6.3VC14770.1UFC020110%6.3VC14511000PFC02015%16VC14351000PFC02015%16VC14421000PFC02015%16VC13970.1UFC020110%6.3VC14660.1UFC020110%6.3VC14261000PFC02015%16VC14570.1UFC020110%6.3VC14201UFC020120%4VC13950.1UFC020110%6.3VC13691000PFC02015%16V
C14870.1UFC020110%6.3VC14780.1UFC020110%6.3V
C14080.1UFC020110%6.3VC14361000PFC02015%16VC13860.1UFC020110%6.3VC14670.1UFC020110%6.3VC14431000PFC02015%16VC14271000PFC02015%16VC14211UFC020120%4VC13790.1UFC020110%6.3VC14580.1UFC020110%6.3VC141210UFC060320%6.3VC13921000PFC02015%16V
C14880.1UFC020110%6.3V
C13621000PFC02015%16VC14090.1UFC020110%6.3VC14790.1UFC020110%6.3V
C135510UFC060320%6.3VC14000.1UFC020110%6.3VC14371000PFC02015%16VC13870.1UFC020110%6.3VC14680.1UFC020110%6.3VC14441000PFC02015%16VC14281000PFC02015%16VC13800.1UFC020110%6.3VC14590.1UFC020110%6.3V
C13701000PFC02015%16VC141310UFC060320%6.3VC14890.1UFC020110%6.3V
C13631000PFC02015%16VC14100.1UFC020110%6.3VC14800.1UFC020110%6.3V
C135610UFC060320%6.3VC14010.1UFC020110%6.3VC14381000PFC02015%16VC14451000PFC02015%16VC13880.1UFC020110%6.3VC14690.1UFC020110%6.3VC14291000PFC02015%16VC13810.1UFC020110%6.3VC14600.1UFC020110%6.3V
C13711000PFC02015%16VC141410UFC060320%6.3VC14900.1UFC020110%6.3V
C13641000PFC02015%16V
C14810.1UFC020110%6.3V
C14110.1UFC020110%6.3VC135710UFC060320%6.3VC14020.1UFC020110%6.3V



5
5
4
4
3
3
2
2
1
1
D D
C C
B B
A A
PEX_1_PWR_Cap_3(10/11)
Imax: 0.04A
Imax: 0.04A Imax: 0.04A Imax: 0.04A
Imax: 0.04A Imax: 0.04A Imax: 0.04A
Imax: 0.04A
Imax: 0.2A Imax: 0.1A
PCEPLL0_VDDA18_PEX1P1V8_PLL0_PEX1P1V8_PLL0_PEX1PCEPLL1_VDDA18_PEX1P1V8_PLL0_PEX1PCEPLL2_VDDA18_PEX1P1V8_PLL0_PEX1PCEPLL3_VDDA18_PEX1P1V8_PLL0_PEX1PCEPLL4_VDDA18_PEX1P1V8_PLL0_PEX1PCEPLL5_VDDA18_PEX1P1V8_PLL0_PEX1PCEPLL6_VDDA18_PEX1P1V8_PLL0_PEX1PCEPLL7_VDDA18_PEX1P1V8_PLL0_PEX1SYSPLL_VDDA18_PEX1P1V8_PLL0_PEX1P1V8_VDDA_PEX1
PCEPLL0_VDDA18_PEX1_RPCEPLL1_VDDA18_PEX1_RPCEPLL2_VDDA18_PEX1_RPCEPLL3_VDDA18_PEX1_RPCEPLL4_VDDA18_PEX1_RPCEPLL5_VDDA18_PEX1_RPCEPLL6_VDDA18_PEX1_RPCEPLL7_VDDA18_PEX1_RSYSPLL_VDDA18_PEX1_RP1V8_VDDA_PEX1_RSizeDoc NumberRevDate: SheetofReviewerDesignerDepartmentProject
Page TitleCCBU D32 257Tuesday, August 29, 2023<project_name><Designer> GRANDTETON_SWB_20230829032 PEX_1_PWR_Cap_3(10/11)<Reviewer>SizeDoc NumberRevDate: SheetofReviewerDesignerDepartmentProject
Page TitleCCBU D32 257Tuesday, August 29, 2023<project_name><Designer> GRANDTETON_SWB_20230829032 PEX_1_PWR_Cap_3(10/11)<Reviewer>SizeDoc NumberRevDate: SheetofReviewerDesignerDepartmentProject
Page TitleCCBU D32 257Tuesday, August 29, 2023<project_name><Designer> GRANDTETON_SWB_20230829032 PEX_1_PWR_Cap_3(10/11)<Reviewer>
R45750.51C318922UFC0603_H4020%6.3VC320110UFC060320%6.3VR45710.51L105HCB2012KF-601T20<Part Number>21
C323210UFC060320%6.3VC321122UFC0603_H4020%6.3VC322910UFC060320%6.3VC32281UFC020120%4VC31961UFC020120%4VC32101UFC020120%4VC31921UFC020120%4VC320922UFC0603_H4020%6.3VC322347UFC32451UFC020120%4V
C32121UFC020120%4VC322522UFC0603_H4020%6.3VC321610UFC060320%6.3VC32331UFC020120%4V
R45680.51C32081UFC020120%4VC319122UFC0603_H4020%6.3VC31941UFC020120%4V
C32460.1UFC020110%6.3VL110HCB2012KF-601T20<Part Number>21 C32171UFC020120%4VC32261UFC020120%4VL113HCB2012KF-601T20<Part Number>21
L109HCB2012KF-601T20<Part Number>21C322447UFC32141UFC020120%4VC319810UFC060320%6.3V
C32430.1UFC020110%6.3VC322722UFC0603_H4020%6.3VL111HCB2012KF-601T20<Part Number>21C321910UFC060320%6.3VL104HCB2012KF-601T20<Part Number>21 C32000.1UFC020110%6.3VR45740.51C320447UFL106HCB2012KF-601T20<Part Number>21
L112HCB2012KF-601T20<Part Number>21C323722UFC0603_H4020%6.3VC323922UFC0603_H4020%6.3V
C32021UFC020120%4VC321310UFC060320%6.3VC31991UFC020120%4V
C32381UFC020120%4V
C31901UFC020120%4VC32030.1UFC020110%6.3V
R45760.51C324410UFC060320%6.3V
C32150.1UFC020110%6.3VC31970.1UFC020110%6.3VC32201UFC020120%4VR45720.51R45700.51
C32401UFC020120%4V
C319322UFC0603_H4020%6.3VC320722UFC0603_H4020%6.3VC322247UFL107HCB2012KF-601T20<Part Number>21 C320647UFC32210.1UFC020110%6.3VC323647UF
R45690.51
C32301UFC020120%4VC320547UFC32340.1UFC020110%6.3VR45770.51C324110UFC060320%6.3VC324747UFC32421UFC020120%4V
L108HCB2012KF-601T20<Part Number>21C319510UFC060320%6.3VC323547UFR45730.51C32310.1UFC020110%6.3VC32180.1UFC020110%6.3V
C324847UF



5
5
4
4
3
3
2
2
1
1
D D
C C
B B
A A
PEX_1_GND(11/11) SizeDoc NumberRevDate: SheetofReviewerDesignerDepartmentProject
Page TitleCCBU D33 257Tuesday, August 29, 2023<project_name><Designer> GRANDTETON_SWB_20230829033 PEX_1_GND(11/11)<Reviewer>SizeDoc NumberRevDate: SheetofReviewerDesignerDepartmentProject
Page TitleCCBU D33 257Tuesday, August 29, 2023<project_name><Designer> GRANDTETON_SWB_20230829033 PEX_1_GND(11/11)<Reviewer>SizeDoc NumberRevDate: SheetofReviewerDesignerDepartmentProject
Page TitleCCBU D33 257Tuesday, August 29, 2023<project_name><Designer> GRANDTETON_SWB_20230829033 PEX_1_GND(11/11)<Reviewer>
23/26PEX1W
SS26-0A0P-01
VSS_AJ36AJ36VSS_AJ37AJ37VSS_AJ40AJ40VSS_AJ41AJ41VSS_AJ42AJ42VSS_AJ45AJ45VSS_AJ48AJ48VSS_AJ49AJ49VSS_AK1AK1VSS_AK2AK2VSS_AK3AK3VSS_AK6AK6VSS_AK8AK8VSS_AK9AK9VSS_AK11AK11VSS_AK13AK13VSS_AK15AK15VSS_AK34AK34VSS_AK36AK36VSS_AK37AK37VSS_AK40AK40VSS_AK43AK43VSS_AK44AK44VSS_AK45AK45VSS_AK46AK46VSS_AK47AK47VSS_AL1AL1VSS_AL2AL2VSS_AL3AL3VSS_AL4AL4VSS_AL5AL5VSS_AL6AL6VSS_AL7AL7VSS_AL8AL8VSS_AL9AL9VSS_AL10AL10VSS_AL11AL11VSS_AL12AL12VSS_AL13AL13VSS_AL16AL16VSS_AL17AL17VSS_AL18AL18VSS_AL19AL19VSS_AL20AL20VSS_AL21AL21VSS_AL22AL22VSS_AL23AL23VSS_AL24AL24VSS_AL25AL25VSS_AL26AL26VSS_AL27AL27VSS_AL28AL28VSS_AL29AL29VSS_AL30AL30VSS_AL31AL31VSS_AL32AL32VSS_AL33AL33VSS_AL34AL34VSS_AL36AL36VSS_AL37AL37VSS_AL40AL40VSS_AL41AL41VSS_AL42AL42VSS_AL45AL45VSS_AL48AL48VSS_AL49AL49VSS_AM3AM3VSS_AM4AM4VSS_AM5AM5VSS_AM6AM6VSS_AM7AM7VSS_AM10AM10VSS_AM11AM11VSS_AM13AM13VSS_AM15AM15VSS_AM34AM34VSS_AM36AM36VSS_AM37AM37VSS_AM40AM40VSS_AM43AM43
VSS_AM44AM44VSS_AM45AM45VSS_AM46AM46VSS_AM47AM47VSS_AN1AN1VSS_AN2AN2VSS_AN5AN5VSS_AN8AN8VSS_AN9AN9VSS_AN10AN10VSS_AN11AN11VSS_AN12AN12VSS_AN13AN13VSS_AN15AN15VSS_AN16AN16VSS_AN17AN17VSS_AN18AN18VSS_AN19AN19VSS_AN20AN20VSS_AN21AN21VSS_AN22AN22VSS_AN23AN23VSS_AN24AN24VSS_AN25AN25VSS_AN26AN26VSS_AN27AN27VSS_AN28AN28VSS_AN29AN29VSS_AN30AN30VSS_AN31AN31VSS_AN32AN32VSS_AN33AN33VSS_AN34AN34VSS_AN35AN35VSS_AN37AN37VSS_AN40AN40VSS_AN41AN41VSS_AN42AN42VSS_AN45AN45VSS_AN48AN48VSS_AN49AN49VSS_AP3AP3VSS_AP4AP4VSS_AP5AP5VSS_AP6AP6VSS_AP7AP7VSS_AP10AP10VSS_AP11AP11VSS_AP12AP12VSS_AP13AP13VSS_AP15AP15VSS_AP34AP34VSS_AP37AP37VSS_AP40AP40VSS_AP43AP43VSS_AP44AP44VSS_AP45AP45VSS_AP46AP46VSS_AP47AP47VSS_AR1AR1VSS_AR2AR2VSS_AR5AR5VSS_AR8AR8VSS_AR9AR9VSS_AR10AR10VSS_AR11AR11VSS_AR12AR12VSS_AR13AR13VSS_AR14AR14VSS_AR15AR15VSS_AR16AR16VSS_AR17AR17VSS_AR18AR18VSS_AR19AR19VSS_AR20AR20VSS_AR21AR21VSS_AR22AR22VSS_AR23AR23VSS_AR24AR24VSS_AR25AR25
22/26PEX1V
SS26-0A0P-01
VSS_AC28AC28VSS_AC30AC30VSS_AC32AC32VSS_AC34AC34VSS_AC35AC35VSS_AC37AC37VSS_AC39AC39VSS_AC40AC40VSS_AC41AC41VSS_AC42AC42VSS_AC45AC45VSS_AC48AC48VSS_AC49AC49VSS_AD1AD1VSS_AD2AD2VSS_AD3AD3VSS_AD6AD6VSS_AD9AD9VSS_AD10AD10VSS_AD11AD11VSS_AD15AD15VSS_AD17AD17VSS_AD19AD19VSS_AD21AD21VSS_AD23AD23VSS_AD25AD25VSS_AD27AD27VSS_AD29AD29VSS_AD31AD31VSS_AD35AD35VSS_AD37AD37VSS_AD39AD39VSS_AD40AD40VSS_AD43AD43VSS_AD44AD44VSS_AD45AD45VSS_AD46AD46VSS_AD47AD47VSS_AE3AE3VSS_AE4AE4VSS_AE5AE5VSS_AE6AE6VSS_AE9AE9VSS_AE11AE11VSS_AE14AE14VSS_AE16AE16VSS_AE18AE18VSS_AE20AE20VSS_AE22AE22VSS_AE24AE24VSS_AE26AE26VSS_AE28AE28VSS_AE30AE30VSS_AE32AE32VSS_AE35AE35VSS_AE37AE37VSS_AE39AE39VSS_AE40AE40VSS_AE41AE41VSS_AE42AE42VSS_AE45AE45VSS_AE48AE48VSS_AE49AE49VSS_AF1AF1VSS_AF2AF2VSS_AF3AF3VSS_AF6AF6VSS_AF9AF9VSS_AF11AF11VSS_AF15AF15VSS_AF17AF17VSS_AF19AF19VSS_AF21AF21VSS_AF23AF23VSS_AF25AF25VSS_AF27AF27VSS_AF29AF29VSS_AF31AF31VSS_AF35AF35VSS_AF37AF37
VSS_AF39AF39VSS_AF40AF40VSS_AF43AF43VSS_AF44AF44VSS_AF45AF45VSS_AF46AF46VSS_AF47AF47VSS_AG3AG3VSS_AG4AG4VSS_AG5AG5VSS_AG6AG6VSS_AG9AG9VSS_AG10AG10VSS_AG11AG11VSS_AG14AG14VSS_AG16AG16VSS_AG18AG18VSS_AG20AG20VSS_AG22AG22VSS_AG24AG24VSS_AG26AG26VSS_AG28AG28VSS_AG30AG30VSS_AG32AG32VSS_AG34AG34VSS_AG35AG35VSS_AG37AG37VSS_AG39AG39VSS_AG40AG40VSS_AG41AG41VSS_AG42AG42VSS_AG45AG45VSS_AG48AG48VSS_AG49AG49VSS_AH1AH1VSS_AH2AH2VSS_AH3AH3VSS_AH6AH6VSS_AH9AH9VSS_AH11AH11VSS_AH15AH15VSS_AH34AH34VSS_AH35AH35VSS_AH36AH36VSS_AH37AH37VSS_AH38AH38VSS_AH39AH39VSS_AH40AH40VSS_AH43AH43VSS_AH44AH44VSS_AH45AH45VSS_AH46AH46VSS_AH47AH47VSS_AJ3AJ3VSS_AJ4AJ4VSS_AJ5AJ5VSS_AJ6AJ6VSS_AJ9AJ9VSS_AJ11AJ11VSS_AJ14AJ14VSS_AJ16AJ16VSS_AJ17AJ17VSS_AJ18AJ18VSS_AJ19AJ19VSS_AJ20AJ20VSS_AJ21AJ21VSS_AJ22AJ22VSS_AJ23AJ23VSS_AJ24AJ24VSS_AJ25AJ25VSS_AJ26AJ26VSS_AJ27AJ27VSS_AJ28AJ28VSS_AJ29AJ29VSS_AJ30AJ30VSS_AJ31AJ31VSS_AJ32AJ32VSS_AJ33AJ33VSS_AJ34AJ34VSS_AJ35AJ35
26/26PEX1ZSS26-0A0P-01VSS_BF7BF7VSS_BF9BF9VSS_BF11BF11VSS_BF13BF13VSS_BF15BF15VSS_BF17BF17VSS_BF19BF19VSS_BF21BF21VSS_BF23BF23VSS_BF25BF25VSS_BF27BF27VSS_BF29BF29VSS_BF31BF31VSS_BF33BF33VSS_BF35BF35VSS_BF37BF37VSS_BF39BF39VSS_BF41BF41VSS_BF43BF43VSS_BF45BF45VSS_BF47BF47VSS_BF48BF48VSS_BF49BF49VSS_BG3BG3VSS_BG5BG5VSS_BG7BG7VSS_BG9BG9VSS_BG11BG11VSS_BG13BG13VSS_BG15BG15VSS_BG17BG17VSS_BG19BG19VSS_BG21BG21VSS_BG23BG23VSS_BG25BG25VSS_BG27BG27VSS_BG29BG29VSS_BG31BG31VSS_BG33BG33VSS_BG35BG35VSS_BG37BG37VSS_BG39BG39VSS_BG41BG41VSS_BG43BG43VSS_BG45BG45VSS_BG47BG47VSS_BH1BH1VSS_BH2BH2VSS_BH4BH4VSS_BH6BH6VSS_BH8BH8VSS_BH10BH10VSS_BH12BH12VSS_BH14BH14VSS_BH16BH16VSS_BH18BH18VSS_BH20BH20VSS_BH22BH22VSS_BH24BH24VSS_BH26BH26VSS_BH28BH28VSS_BH30BH30VSS_BH32BH32VSS_BH34BH34VSS_BH36BH36VSS_BH38BH38VSS_BH40BH40VSS_BH42BH42VSS_BH44BH44VSS_BH46BH46VSS_BH48BH48VSS_BH49BH49VSS_BJ2BJ2VSS_BJ4BJ4VSS_BJ6BJ6VSS_BJ8BJ8VSS_BJ10BJ10VSS_BJ12BJ12VSS_BJ14BJ14VSS_BJ16BJ16VSS_BJ18BJ18VSS_BJ20BJ20VSS_BJ22BJ22VSS_BJ24BJ24VSS_BJ26BJ26VSS_BJ28BJ28VSS_BJ30BJ30VSS_BJ32BJ32VSS_BJ34BJ34VSS_BJ36BJ36VSS_BJ38BJ38VSS_BJ40BJ40VSS_BJ42BJ42VSS_BJ44BJ44VSS_BJ46BJ46VSS_BJ48BJ48PLL_VSSA_AA12AA12PLL_VSSA_AB13AB13PLL_VSSA_AC12AC12PLL_VSSA_AD13AD13PLL_VSSA_AE12AE12PLL_VSSA_AF13AF13PLL_VSSA_AG12AG12PLL_VSSA_AH13AH13PLL_VSSA_AJ12AJ1225/26PEX1Y
SS26-0A0P-01
VSS_AY39AY39VSS_AY40AY40VSS_AY41AY41VSS_AY42AY42VSS_AY43AY43VSS_AY44AY44VSS_AY45AY45VSS_AY46AY46VSS_AY47AY47VSS_BA1BA1VSS_BA2BA2VSS_BA3BA3VSS_BA5BA5VSS_BA7BA7VSS_BA9BA9VSS_BA11BA11VSS_BA13BA13VSS_BA15BA15VSS_BA17BA17VSS_BA19BA19VSS_BA21BA21VSS_BA23BA23VSS_BA25BA25VSS_BA27BA27VSS_BA29BA29VSS_BA31BA31VSS_BA33BA33VSS_BA35BA35VSS_BA37BA37VSS_BA39BA39VSS_BA41BA41VSS_BA43BA43VSS_BA45BA45VSS_BA47BA47VSS_BA48BA48VSS_BA49BA49VSS_BB3BB3VSS_BB5BB5VSS_BB7BB7VSS_BB9BB9VSS_BB11BB11VSS_BB13BB13VSS_BB15BB15VSS_BB17BB17VSS_BB19BB19VSS_BB21BB21VSS_BB23BB23VSS_BB25BB25VSS_BB27BB27VSS_BB29BB29VSS_BB31BB31VSS_BB33BB33VSS_BB35BB35VSS_BB37BB37VSS_BB39BB39VSS_BB41BB41VSS_BB43BB43VSS_BB45BB45VSS_BB47BB47VSS_BC1BC1VSS_BC2BC2VSS_BC4BC4VSS_BC6BC6VSS_BC8BC8VSS_BC10BC10VSS_BC12BC12VSS_BC14BC14VSS_BC16BC16VSS_BC18BC18VSS_BC20BC20VSS_BC22BC22VSS_BC24BC24VSS_BC26BC26VSS_BC28BC28VSS_BC30BC30VSS_BC32BC32VSS_BC34BC34VSS_BC36BC36VSS_BC38BC38VSS_BC40BC40
VSS_BC42BC42VSS_BC44BC44VSS_BC46BC46VSS_BC48BC48VSS_BC49BC49VSS_BD1BD1VSS_BD2BD2VSS_BD4BD4VSS_BD6BD6VSS_BD8BD8VSS_BD10BD10VSS_BD12BD12VSS_BD14BD14VSS_BD16BD16VSS_BD18BD18VSS_BD20BD20VSS_BD22BD22VSS_BD24BD24VSS_BD26BD26VSS_BD28BD28VSS_BD30BD30VSS_BD32BD32VSS_BD34BD34VSS_BD36BD36VSS_BD38BD38VSS_BD40BD40VSS_BD42BD42VSS_BD44BD44VSS_BD46BD46VSS_BD48BD48VSS_BD49BD49VSS_BE3BE3VSS_BE4BE4VSS_BE5BE5VSS_BE6BE6VSS_BE7BE7VSS_BE8BE8VSS_BE9BE9VSS_BE10BE10VSS_BE11BE11VSS_BE12BE12VSS_BE13BE13VSS_BE14BE14VSS_BE15BE15VSS_BE16BE16VSS_BE17BE17VSS_BE18BE18VSS_BE19BE19VSS_BE20BE20VSS_BE21BE21VSS_BE22BE22VSS_BE23BE23VSS_BE24BE24VSS_BE25BE25VSS_BE26BE26VSS_BE27BE27VSS_BE28BE28VSS_BE29BE29VSS_BE30BE30VSS_BE31BE31VSS_BE32BE32VSS_BE33BE33VSS_BE34BE34VSS_BE35BE35VSS_BE36BE36VSS_BE37BE37VSS_BE38BE38VSS_BE39BE39VSS_BE40BE40VSS_BE41BE41VSS_BE42BE42VSS_BE43BE43VSS_BE44BE44VSS_BE45BE45VSS_BE46BE46VSS_BE47BE47VSS_BF1BF1VSS_BF2BF2VSS_BF3BF3VSS_BF5BF5
20/26PEX1T
SS26-0A0P-01
VSS_M45M45VSS_M46M46VSS_M47M47VSS_N1N1VSS_N2N2VSS_N5N5VSS_N8N8VSS_N9N9VSS_N10N10VSS_N11N11VSS_N12N12VSS_N13N13VSS_N14N14VSS_N15N15VSS_N16N16VSS_N17N17VSS_N18N18VSS_N19N19VSS_N20N20VSS_N21N21VSS_N22N22VSS_N23N23VSS_N24N24VSS_N25N25VSS_N26N26VSS_N27N27VSS_N28N28VSS_N29N29VSS_N30N30VSS_N31N31VSS_N32N32VSS_N33N33VSS_N34N34VSS_N35N35VSS_N36N36VSS_N37N37VSS_N40N40VSS_N41N41VSS_N42N42VSS_N45N45VSS_N48N48VSS_N49N49VSS_P3P3VSS_P4P4VSS_P5P5VSS_P6P6VSS_P7P7VSS_P10P10VSS_P11P11VSS_P12P12VSS_P13P13VSS_P14P14VSS_P15P15VSS_P16P16VSS_P17P17VSS_P18P18VSS_P19P19VSS_P20P20VSS_P21P21VSS_P22P22VSS_P23P23VSS_P24P24VSS_P25P25VSS_P26P26VSS_P27P27VSS_P28P28VSS_P29P29VSS_P30P30VSS_P31P31VSS_P32P32VSS_P33P33VSS_P34P34VSS_P35P35VSS_P37P37VSS_P40P40VSS_P43P43VSS_P44P44VSS_P45P45VSS_P46P46VSS_P47P47
VSS_R1R1VSS_R2R2VSS_R5R5VSS_R8R8VSS_R9R9VSS_R10R10VSS_R11R11VSS_R12R12VSS_R13R13VSS_R14R14VSS_R15R15VSS_R16R16VSS_R17R17VSS_R18R18VSS_R19R19VSS_R20R20VSS_R21R21VSS_R22R22VSS_R23R23VSS_R24R24VSS_R25R25VSS_R26R26VSS_R27R27VSS_R28R28VSS_R29R29VSS_R30R30VSS_R31R31VSS_R32R32VSS_R33R33VSS_R34R34VSS_R35R35VSS_R37R37VSS_R40R40VSS_R41R41VSS_R42R42VSS_R45R45VSS_R48R48VSS_R49R49VSS_T3T3VSS_T4T4VSS_T5T5VSS_T6T6VSS_T7T7VSS_T10T10VSS_T11T11VSS_T12T12VSS_T13T13VSS_T15T15VSS_T34T34VSS_T37T37VSS_T40T40VSS_T43T43VSS_T44T44VSS_T45T45VSS_T46T46VSS_T47T47VSS_U1U1VSS_U2U2VSS_U5U5VSS_U8U8VSS_U9U9VSS_U10U10VSS_U11U11VSS_U12U12VSS_U13U13VSS_U15U15VSS_U16U16VSS_U17U17VSS_U18U18VSS_U19U19VSS_U20U20VSS_U21U21VSS_U22U22VSS_U23U23VSS_U24U24VSS_U25U25VSS_U26U26VSS_U27U27VSS_U28U28VSS_U29U29
21/26PEX1U
SS26-0A0P-01
VSS_U30U30VSS_U31U31VSS_U32U32VSS_U33U33VSS_U34U34VSS_U35U35VSS_U37U37VSS_U40U40VSS_U41U41VSS_U42U42VSS_U45U45VSS_U48U48VSS_U49U49VSS_V3V3VSS_V4V4VSS_V5V5VSS_V6V6VSS_V7V7VSS_V10V10VSS_V11V11VSS_V12V12VSS_V13V13VSS_V15V15VSS_V34V34VSS_V36V36VSS_V37V37VSS_V38V38VSS_V40V40VSS_V43V43VSS_V44V44VSS_V45V45VSS_V46V46VSS_V47V47VSS_W1W1VSS_W2W2VSS_W5W5VSS_W8W8VSS_W9W9VSS_W10W10VSS_W11W11VSS_W12W12VSS_W13W13VSS_W14W14VSS_W15W15VSS_W16W16VSS_W17W17VSS_W18W18VSS_W19W19VSS_W20W20VSS_W21W21VSS_W22W22VSS_W23W23VSS_W24W24VSS_W25W25VSS_W26W26VSS_W27W27VSS_W28W28VSS_W29W29VSS_W30W30VSS_W31W31VSS_W32W32VSS_W33W33VSS_W34W34VSS_W36W36VSS_W37W37VSS_W40W40VSS_W41W41VSS_W42W42VSS_W45W45VSS_W48W48VSS_W49W49VSS_Y1Y1VSS_Y2Y2VSS_Y3Y3VSS_Y4Y4VSS_Y5Y5VSS_Y6Y6VSS_Y7Y7VSS_Y8Y8VSS_Y9Y9
VSS_Y10Y10VSS_Y11Y11VSS_Y13Y13VSS_Y15Y15VSS_Y34Y34VSS_Y36Y36VSS_Y37Y37VSS_Y38Y38VSS_Y40Y40VSS_Y44Y44VSS_Y45Y45VSS_Y46Y46VSS_Y47Y47VSS_AA3AA3VSS_AA4AA4VSS_AA5AA5VSS_AA6AA6VSS_AA7AA7VSS_AA8AA8VSS_AA9AA9VSS_AA11AA11VSS_AA14AA14VSS_AA16AA16VSS_AA17AA17VSS_AA18AA18VSS_AA19AA19VSS_AA20AA20VSS_AA21AA21VSS_AA22AA22VSS_AA23AA23VSS_AA24AA24VSS_AA25AA25VSS_AA26AA26VSS_AA27AA27VSS_AA28AA28VSS_AA29AA29VSS_AA30AA30VSS_AA31AA31VSS_AA32AA32VSS_AA33AA33VSS_AA36AA36VSS_AA38AA38VSS_AA40AA40VSS_AA41AA41VSS_AA42AA42VSS_AA45AA45VSS_AA48AA48VSS_AA49AA49VSS_AB1AB1VSS_AB2AB2VSS_AB3AB3VSS_AB6AB6VSS_AB9AB9VSS_AB11AB11VSS_AB15AB15VSS_AB34AB34VSS_AB36AB36VSS_AB37AB37VSS_AB38AB38VSS_AB39AB39VSS_AB40AB40VSS_AB43AB43VSS_AB44AB44VSS_AB45AB45VSS_AB46AB46VSS_AB47AB47VSS_AC3AC3VSS_AC4AC4VSS_AC5AC5VSS_AC6AC6VSS_AC9AC9VSS_AC11AC11VSS_AC14AC14VSS_AC16AC16VSS_AC18AC18VSS_AC20AC20VSS_AC22AC22VSS_AC24AC24VSS_AC26AC26
VSS_Y43Y4324/26PEX1X
SS26-0A0P-01
VSS_AR26AR26VSS_AR27AR27VSS_AR28AR28VSS_AR29AR29VSS_AR30AR30VSS_AR31AR31VSS_AR32AR32VSS_AR33AR33VSS_AR34AR34VSS_AR35AR35VSS_AR37AR37VSS_AR40AR40VSS_AR41AR41VSS_AR42AR42VSS_AR45AR45VSS_AR48AR48VSS_AR49AR49VSS_AT3AT3VSS_AT4AT4VSS_AT5AT5VSS_AT6AT6VSS_AT7AT7VSS_AT10AT10VSS_AT11AT11VSS_AT12AT12VSS_AT13AT13VSS_AT14AT14VSS_AT15AT15VSS_AT16AT16VSS_AT17AT17VSS_AT18AT18VSS_AT19AT19VSS_AT20AT20VSS_AT21AT21VSS_AT22AT22VSS_AT23AT23VSS_AT24AT24VSS_AT25AT25VSS_AT26AT26VSS_AT27AT27VSS_AT28AT28VSS_AT29AT29VSS_AT30AT30VSS_AT31AT31VSS_AT32AT32VSS_AT33AT33VSS_AT34AT34VSS_AT35AT35VSS_AT37AT37VSS_AT40AT40VSS_AT43AT43VSS_AT44AT44VSS_AT45AT45VSS_AT46AT46VSS_AT47AT47VSS_AU1AU1VSS_AU2AU2VSS_AU5AU5VSS_AU8AU8VSS_AU9AU9VSS_AU10AU10VSS_AU11AU11VSS_AU12AU12VSS_AU13AU13VSS_AU14AU14VSS_AU15AU15VSS_AU16AU16VSS_AU17AU17VSS_AU18AU18VSS_AU19AU19VSS_AU20AU20VSS_AU21AU21VSS_AU22AU22VSS_AU23AU23VSS_AU24AU24VSS_AU25AU25VSS_AU26AU26VSS_AU27AU27VSS_AU28AU28VSS_AU29AU29
VSS_AU30AU30VSS_AU31AU31VSS_AU32AU32VSS_AU33AU33VSS_AU34AU34VSS_AU35AU35VSS_AU36AU36VSS_AU37AU37VSS_AU40AU40VSS_AU41AU41VSS_AU42AU42VSS_AU45AU45VSS_AU48AU48VSS_AU49AU49VSS_AV3AV3VSS_AV4AV4VSS_AV5AV5VSS_AV6AV6VSS_AV7AV7VSS_AV10AV10VSS_AV11AV11VSS_AV20AV20VSS_AV24AV24VSS_AV40AV40VSS_AV43AV43VSS_AV44AV44VSS_AV45AV45VSS_AV46AV46VSS_AV47AV47VSS_AW1AW1VSS_AW2AW2VSS_AW5AW5VSS_AW8AW8VSS_AW9AW9VSS_AW10AW10VSS_AW11AW11VSS_AW20AW20VSS_AW24AW24VSS_AW40AW40VSS_AW41AW41VSS_AW42AW42VSS_AW45AW45VSS_AW48AW48VSS_AW49AW49VSS_AY3AY3VSS_AY4AY4VSS_AY5AY5VSS_AY6AY6VSS_AY7AY7VSS_AY8AY8VSS_AY9AY9VSS_AY10AY10VSS_AY11AY11VSS_AY12AY12VSS_AY13AY13VSS_AY14AY14VSS_AY15AY15VSS_AY16AY16VSS_AY17AY17VSS_AY18AY18VSS_AY19AY19VSS_AY20AY20VSS_AY21AY21VSS_AY22AY22VSS_AY23AY23VSS_AY24AY24VSS_AY25AY25VSS_AY26AY26VSS_AY27AY27VSS_AY28AY28VSS_AY29AY29VSS_AY30AY30VSS_AY31AY31VSS_AY32AY32VSS_AY33AY33VSS_AY34AY34VSS_AY35AY35VSS_AY36AY36VSS_AY37AY37VSS_AY38AY38



5
5
4
4
3
3
2
2
1
1
D D
C C
B B
A A
Co-Layout CAD NOTE:BUCK CAP NEAR FILTER CAD NOTE:NEAR PACKAGE EDGE
PEX_1_PWR_FILTER
Co-Layout CAD NOTE:BUCK CAP NEAR FILTER CAD NOTE:NEAR PACKAGE EDGE
DCR : 0.0021 ohm
P0V8_SERDES_VDDA_PEX1P0V8_PEX1P0V8_PEX1P1V25_SERDES_VDDPLL_PEX1P1V25_PEX1P1V25_PEX1SizeDoc NumberRevDate: SheetofReviewerDesignerDepartmentProject
Page TitleCCBU D34 257Tuesday, August 29, 2023<project_name><Designer> GRANDTETON_SWB_20230829034 PEX_1_PWR_FILTER<Reviewer>SizeDoc NumberRevDate: SheetofReviewerDesignerDepartmentProject
Page TitleCCBU D34 257Tuesday, August 29, 2023<project_name><Designer> GRANDTETON_SWB_20230829034 PEX_1_PWR_FILTER<Reviewer>SizeDoc NumberRevDate: SheetofReviewerDesignerDepartmentProject
Page TitleCCBU D34 257Tuesday, August 29, 2023<project_name><Designer> GRANDTETON_SWB_20230829034 PEX_1_PWR_FILTER<Reviewer>
C425922UFC0603_H4020%6.3VC42651UFC020120%4V
C429847UFC428547UFC427647UFL99BLM31SN500SN1L21C428947UF
C42511UFC020120%4VL29BLM31SN500SN1L21
C429947UFC4286100UFC0805_H61_SEL20%4VC429047UFC427747UFR64830.51C42661UFC020120%4VL30BLM31SN500SN1L21R64750.51
0.01R6132NI2B1B2A1AC4300100UFC0805_H61_SEL20%4VC42781UFC020120%4V
C42521UFC020120%4V
C429147UFC4287100UF20%4VR64840.51R64760.51C42671UFC020120%4VC42921UFC020120%4V0.01R6133NI2B1B2A1AC4301100UF20%4V
R64850.51C42531UFC020120%4VC42791UFC020120%4V
R64770.51
0.01R6130NI2B1B2A1AR64860.51C42931UFC020120%4VR64910.51
R64780.51L27BLM31SN500SN1L210.01R5789NI2B1B2A1AC42801UFC020120%4VR64870.510.01R6131NI2B1B2A1A
R64790.51
R64990.51R64920.51
L28BLM31SN500SN1L21C426847UFC42941UFC020120%4V
R64880.510.01R5790NI2B1B2A1AC42811UFC020120%4VC425447UF
R65000.51R64930.51
R64800.51C426947UFC426047UF
C42951UFC020120%4V
C425547UFC424647UF
R65010.51R64940.51C427047UFC426147UFC425647UFC424747UFR64950.51L100BLM31SN500SN1L21R65020.51C427147UFC426247UF0.01R5787NI2B1B2A1A
C428247UF
C425747UFC424847UF
R65030.51R64960.51L101BLM31SN500SN1L21C427222UFC0603_H4020%6.3VC426347UFC425822UFC0603_H4020%6.3V
C429647UFC428347UFC427447UF
C424947UF0.01R5788NI2B1B2A1A
R65040.51
C42641UFC020120%4VC427322UFC0603_H4020%6.3VC429747UFC428447UFL98BLM31SN500SN1L21C42501UFC020120%4V
C428847UFC427547UF



5
5
4
4
3
3
2
2
1
1
D D
C C
B B
A A
BLANK SizeDoc NumberRevDate: SheetofReviewerDesignerDepartmentProject
Page TitleCCBU D35 257Tuesday, August 29, 2023<project_name><Designer> GRANDTETON_SWB_20230829035 BLANK<Reviewer>SizeDoc NumberRevDate: SheetofReviewerDesignerDepartmentProject
Page TitleCCBU D35 257Tuesday, August 29, 2023<project_name><Designer> GRANDTETON_SWB_20230829035 BLANK<Reviewer>SizeDoc NumberRevDate: SheetofReviewerDesignerDepartmentProject
Page TitleCCBU D35 257Tuesday, August 29, 2023<project_name><Designer> GRANDTETON_SWB_20230829035 BLANK<Reviewer>



5
5
4
4
3
3
2
2
1
1
D D
C C
B B
A A
PEX_2_STN_01(1/11)
P5E_PEX2_STN0_TX_C_DP<15> [183]P5E_PEX2_STN0_TX_C_DN<15> [183]P5E_PEX2_STN0_TX_C_DN<14> [183]P5E_PEX2_STN0_TX_C_DP<14> [183]P5E_PEX2_STN0_TX_C_DP<13> [183]P5E_PEX2_STN0_TX_C_DN<13> [183]P5E_PEX2_STN0_TX_C_DN<12> [183]P5E_PEX2_STN0_TX_C_DP<12> [183]P5E_PEX2_STN0_TX_C_DP<11> [183]P5E_PEX2_STN0_TX_C_DN<11> [183]P5E_PEX2_STN0_TX_C_DP<10> [183]P5E_PEX2_STN0_TX_C_DN<10> [183]P5E_PEX2_STN0_TX_C_DP<9> [183]P5E_PEX2_STN0_TX_C_DN<9> [183]P5E_PEX2_STN0_TX_C_DP<8> [183]P5E_PEX2_STN0_TX_C_DN<8> [183]P5E_PEX2_STN0_TX_C_DP<7> [183]P5E_PEX2_STN0_TX_C_DN<7> [183]P5E_PEX2_STN0_TX_C_DP<6> [183]P5E_PEX2_STN0_TX_C_DN<6> [183]P5E_PEX2_STN0_TX_C_DP<5> [183]P5E_PEX2_STN0_TX_C_DN<5> [183]P5E_PEX2_STN0_TX_C_DP<4> [183]P5E_PEX2_STN0_TX_C_DN<4> [183]P5E_PEX2_STN0_TX_C_DP<3> [183]P5E_PEX2_STN0_TX_C_DN<3> [183]P5E_PEX2_STN0_TX_C_DP<2> [183]P5E_PEX2_STN0_TX_C_DN<2> [183]P5E_PEX2_STN0_TX_C_DP<1> [183]P5E_PEX2_STN0_TX_C_DN<1> [183]P5E_PEX2_STN0_TX_C_DP<0> [183]P5E_PEX2_STN0_TX_C_DN<0> [183]P5E_PEX2_STN1_TX_C_DP<16> [180]P5E_PEX2_STN1_TX_C_DN<16> [180]P5E_PEX2_STN1_TX_C_DN<17> [180]P5E_PEX2_STN1_TX_C_DP<17> [180]P5E_PEX2_STN1_TX_C_DN<19> [180]P5E_PEX2_STN1_TX_C_DP<19> [180]P5E_PEX2_STN1_TX_C_DP<18> [180]P5E_PEX2_STN1_TX_C_DN<18> [180]P5E_PEX2_STN1_TX_C_DN<23> [180]P5E_PEX2_STN1_TX_C_DP<23> [180]P5E_PEX2_STN1_TX_C_DP<22> [180]P5E_PEX2_STN1_TX_C_DN<22> [180]P5E_PEX2_STN1_TX_C_DN<21> [180]P5E_PEX2_STN1_TX_C_DP<21> [180]P5E_PEX2_STN1_TX_C_DP<20> [180]P5E_PEX2_STN1_TX_C_DN<20> [180]P5E_PEX2_STN1_TX_C_DP<24> [180]P5E_PEX2_STN1_TX_C_DN<24> [180]P5E_PEX2_STN1_TX_C_DN<25> [180]P5E_PEX2_STN1_TX_C_DP<25> [180]P5E_PEX2_STN1_TX_C_DN<27> [180]P5E_PEX2_STN1_TX_C_DP<27> [180]P5E_PEX2_STN1_TX_C_DP<26> [180]P5E_PEX2_STN1_TX_C_DN<26> [180]P5E_PEX2_STN1_TX_C_DN<31> [180]P5E_PEX2_STN1_TX_C_DP<31> [180]P5E_PEX2_STN1_TX_C_DP<30> [180]P5E_PEX2_STN1_TX_C_DN<30> [180]P5E_PEX2_STN1_TX_C_DN<29> [180]P5E_PEX2_STN1_TX_C_DP<29> [180]P5E_PEX2_STN1_TX_C_DP<28> [180]P5E_PEX2_STN1_TX_C_DN<28> [180]
P5E_PEX2_STN0_RX_DP<15>[183]P5E_PEX2_STN0_RX_DN<15>[183]P5E_PEX2_STN0_RX_DP<14>[183]P5E_PEX2_STN0_RX_DN<14>[183]P5E_PEX2_STN0_RX_DP<13>[183]P5E_PEX2_STN0_RX_DN<13>[183]P5E_PEX2_STN0_RX_DP<12>[183]P5E_PEX2_STN0_RX_DN<12>[183]P5E_PEX2_STN0_RX_DP<11>[183]P5E_PEX2_STN0_RX_DN<11>[183]P5E_PEX2_STN0_RX_DP<10>[183]P5E_PEX2_STN0_RX_DN<10>[183]P5E_PEX2_STN0_RX_DP<9>[183]P5E_PEX2_STN0_RX_DN<9>[183]P5E_PEX2_STN0_RX_DP<8>[183]P5E_PEX2_STN0_RX_DN<8>[183]P5E_PEX2_STN0_RX_DP<7>[183]P5E_PEX2_STN0_RX_DN<7>[183]P5E_PEX2_STN0_RX_DP<6>[183]P5E_PEX2_STN0_RX_DN<6>[183]P5E_PEX2_STN0_RX_DP<5>[183]P5E_PEX2_STN0_RX_DN<5>[183]P5E_PEX2_STN0_RX_DP<4>[183]P5E_PEX2_STN0_RX_DN<4>[183]P5E_PEX2_STN0_RX_DP<3>[183]P5E_PEX2_STN0_RX_DN<3>[183]P5E_PEX2_STN0_RX_DP<2>[183]P5E_PEX2_STN0_RX_DN<2>[183]P5E_PEX2_STN0_RX_DP<1>[183]P5E_PEX2_STN0_RX_DN<1>[183]P5E_PEX2_STN0_RX_DP<0>[183]P5E_PEX2_STN0_RX_DN<0>[183]P5E_PEX2_STN1_RX_DP<31>[180]P5E_PEX2_STN1_RX_DN<31>[180]P5E_PEX2_STN1_RX_DP<30>[180]P5E_PEX2_STN1_RX_DN<30>[180]P5E_PEX2_STN1_RX_DP<29>[180]P5E_PEX2_STN1_RX_DN<29>[180]P5E_PEX2_STN1_RX_DP<28>[180]P5E_PEX2_STN1_RX_DN<28>[180]P5E_PEX2_STN1_RX_DP<27>[180]P5E_PEX2_STN1_RX_DN<27>[180]P5E_PEX2_STN1_RX_DP<26>[180]P5E_PEX2_STN1_RX_DN<26>[180]P5E_PEX2_STN1_RX_DP<25>[180]P5E_PEX2_STN1_RX_DN<25>[180]P5E_PEX2_STN1_RX_DP<24>[180]P5E_PEX2_STN1_RX_DN<24>[180]P5E_PEX2_STN1_RX_DP<23>[180]P5E_PEX2_STN1_RX_DN<23>[180]P5E_PEX2_STN1_RX_DP<22>[180]P5E_PEX2_STN1_RX_DN<22>[180]P5E_PEX2_STN1_RX_DP<21>[180]P5E_PEX2_STN1_RX_DN<21>[180]P5E_PEX2_STN1_RX_DP<20>[180]P5E_PEX2_STN1_RX_DN<20>[180]P5E_PEX2_STN1_RX_DP<19>[180]P5E_PEX2_STN1_RX_DN<19>[180]P5E_PEX2_STN1_RX_DP<18>[180]P5E_PEX2_STN1_RX_DN<18>[180]P5E_PEX2_STN1_RX_DP<17>[180]P5E_PEX2_STN1_RX_DN<17>[180]P5E_PEX2_STN1_RX_DP<16>[180]P5E_PEX2_STN1_RX_DN<16>[180]SizeDoc NumberRevDate: SheetofReviewerDesignerDepartmentProject
Page TitleCCBU D36 257Tuesday, August 29, 2023<project_name><Designer> GRANDTETON_SWB_20230829036 PEX_2_STN_01(1/11)<Reviewer>SizeDoc NumberRevDate: SheetofReviewerDesignerDepartmentProject
Page TitleCCBU D36 257Tuesday, August 29, 2023<project_name><Designer> GRANDTETON_SWB_20230829036 PEX_2_STN_01(1/11)<Reviewer>SizeDoc NumberRevDate: SheetofReviewerDesignerDepartmentProject
Page TitleCCBU D36 257Tuesday, August 29, 2023<project_name><Designer> GRANDTETON_SWB_20230829036 PEX_2_STN_01(1/11)<Reviewer>
C456 DIFF BUS_0.22UFC431 DIFF BUS_0.22UF
C469 DIFF BUS_0.22UFC444 DIFF BUS_0.22UF
C482 DIFF BUS_0.22UFC457 DIFF BUS_0.22UFC432 DIFF BUS_0.22UF
C470 DIFF BUS_0.22UFC445 DIFF BUS_0.22UF
C483 DIFF BUS_0.22UFC458 DIFF BUS_0.22UFC433 DIFF BUS_0.22UF
C471 DIFF BUS_0.22UFC446 DIFF BUS_0.22UF
C484 DIFF BUS_0.22UFC459 DIFF BUS_0.22UFC434 DIFF BUS_0.22UF
C472 DIFF BUS_0.22UFC447 DIFF BUS_0.22UF
C485 DIFF BUS_0.22UFC460 DIFF BUS_0.22UFC435 DIFF BUS_0.22UF
C473 DIFF BUS_0.22UFC448 DIFF BUS_0.22UF
C486 DIFF BUS_0.22UF
C423 DIFF BUS_0.22UF
C461 DIFF BUS_0.22UFC436 DIFF BUS_0.22UF
C474 DIFF BUS_0.22UFC449 DIFF BUS_0.22UFC424 DIFF BUS_0.22UF
C462 DIFF BUS_0.22UF2/26PEX2BSS26-0A0P-01RXP31BF40RXN31BG40RXP30BH39RXN30BJ39RXP29BF38RXN29BG38RXP28BH37RXN28BJ37RXP27BF36RXN27BG36RXP26BH35RXN26BJ35RXP25BF34RXN25BG34RXP24BH33RXN24BJ33RXP23BF32RXN23BG32RXP22BH31RXN22BJ31RXP21BF30RXN21BG30RXP20BH29RXN20BJ29RXP19BF28RXN19BG28RXP18BH27RXN18BJ27RXP17BF26RXN17BG26RXP16BH25RXN16BJ25TXP31BA40TXN31BB40TXP30BC39TXN30BD39TXP29BA38TXN29BB38TXP28BC37TXN28BD37TXP27BA36TXN27BB36TXP26BC35TXN26BD35TXP25BA34TXN25BB34TXP24BC33TXN24BD33TXP23BA32TXN23BB32TXP22BC31TXN22BD31TXP21BA30TXN21BB30TXP20BC29TXN20BD29TXP19BA28TXN19BB28TXP18BC27TXN18BD27TXP17BA26TXP16BC25TXN16BD25TXN17BB26
C437 DIFF BUS_0.22UF
C475 DIFF BUS_0.22UFC450 DIFF BUS_0.22UFC425 DIFF BUS_0.22UF
1/26
PEX2ASS26-0A0P-01RXP15BH41RXN15BJ41RXP14BF42RXN14BG42RXP13BH43RXN13BJ43RXP12BF44RXN12BG44RXP11BH45RXN11BJ45RXP10BF46RXN10BG46RXP9BH47RXN9BJ47RXP8BG48RXN8BG49RXP7AY48RXN7AY49RXP6AW46RXN6AW47RXP5AV48RXN5AV49RXP4AU46RXN4AU47RXP3AT48RXN3AT49RXP2AR46RXN2AR47RXP1AP48RXN1AP49RXP0AN46RXN0AN47TXP15BC41TXN15BD41TXP14BA42TXN14BB42TXP13BC43TXN13BD43TXP12BA44TXN12BB44TXP11BC45TXN11BD45TXP10BA46TXN10BB46TXP9BC47TXN9BD47TXP8BE48TXN8BE49TXP7BB48TXN7BB49TXP6AW43TXN6AW44TXP5AV41TXN5AV42TXP4AU43TXN4AU44TXP3AT41TXN3AT42TXP2AR43TXN2AR44TXP1AP41TXN1AP42TXP0AN43TXN0AN44C463 DIFF BUS_0.22UFC438 DIFF BUS_0.22UF
C476 DIFF BUS_0.22UFC451 DIFF BUS_0.22UFC426 DIFF BUS_0.22UF
C464 DIFF BUS_0.22UFC439 DIFF BUS_0.22UF
C477 DIFF BUS_0.22UFC452 DIFF BUS_0.22UFC427 DIFF BUS_0.22UF
C465 DIFF BUS_0.22UFC440 DIFF BUS_0.22UF
C478 DIFF BUS_0.22UFC453 DIFF BUS_0.22UFC428 DIFF BUS_0.22UF
C466 DIFF BUS_0.22UFC441 DIFF BUS_0.22UF
C479 DIFF BUS_0.22UFC454 DIFF BUS_0.22UFC429 DIFF BUS_0.22UF
C467 DIFF BUS_0.22UFC442 DIFF BUS_0.22UF
C480 DIFF BUS_0.22UFC455 DIFF BUS_0.22UFC430 DIFF BUS_0.22UF
C468 DIFF BUS_0.22UFC443 DIFF BUS_0.22UF
C481 DIFF BUS_0.22UFP5E_PEX2_STN0_TX_DP<0>P5E_PEX2_STN0_TX_DN<0>P5E_PEX2_STN1_TX_DN<31>P5E_PEX2_STN1_TX_DP<31>P5E_PEX2_STN0_TX_DP<1>P5E_PEX2_STN0_TX_DN<1>P5E_PEX2_STN0_TX_DP<3>P5E_PEX2_STN0_TX_DN<3>P5E_PEX2_STN0_TX_DP<2>P5E_PEX2_STN0_TX_DN<2>P5E_PEX2_STN0_TX_DP<7>P5E_PEX2_STN0_TX_DN<7>P5E_PEX2_STN0_TX_DP<6>P5E_PEX2_STN0_TX_DN<6>P5E_PEX2_STN0_TX_DP<5>P5E_PEX2_STN0_TX_DN<5>P5E_PEX2_STN0_TX_DP<4>P5E_PEX2_STN0_TX_DN<4>P5E_PEX2_STN0_TX_DP<15>P5E_PEX2_STN0_TX_DN<15>P5E_PEX2_STN0_TX_DN<14>P5E_PEX2_STN0_TX_DP<14>P5E_PEX2_STN0_TX_DP<13>P5E_PEX2_STN0_TX_DN<13>P5E_PEX2_STN0_TX_DN<12>P5E_PEX2_STN0_TX_DP<12>P5E_PEX2_STN0_TX_DP<11>P5E_PEX2_STN0_TX_DN<11>P5E_PEX2_STN0_TX_DP<10>P5E_PEX2_STN0_TX_DN<10>P5E_PEX2_STN0_TX_DP<9>P5E_PEX2_STN0_TX_DN<9>P5E_PEX2_STN0_TX_DP<8>P5E_PEX2_STN0_TX_DN<8>P5E_PEX2_STN1_TX_DP<30>P5E_PEX2_STN1_TX_DN<30>P5E_PEX2_STN1_TX_DN<29>P5E_PEX2_STN1_TX_DP<29>P5E_PEX2_STN1_TX_DP<28>P5E_PEX2_STN1_TX_DN<28>P5E_PEX2_STN1_TX_DN<27>P5E_PEX2_STN1_TX_DP<27>P5E_PEX2_STN1_TX_DP<26>P5E_PEX2_STN1_TX_DN<26>P5E_PEX2_STN1_TX_DN<25>P5E_PEX2_STN1_TX_DP<25>P5E_PEX2_STN1_TX_DP<24>P5E_PEX2_STN1_TX_DN<24>P5E_PEX2_STN1_TX_DN<23>P5E_PEX2_STN1_TX_DP<23>P5E_PEX2_STN1_TX_DP<22>P5E_PEX2_STN1_TX_DN<22>P5E_PEX2_STN1_TX_DN<21>P5E_PEX2_STN1_TX_DP<21>P5E_PEX2_STN1_TX_DP<20>P5E_PEX2_STN1_TX_DN<20>P5E_PEX2_STN1_TX_DN<19>P5E_PEX2_STN1_TX_DP<19>P5E_PEX2_STN1_TX_DP<18>P5E_PEX2_STN1_TX_DN<18>P5E_PEX2_STN1_TX_DN<17>P5E_PEX2_STN1_TX_DP<17>P5E_PEX2_STN1_TX_DP<16>P5E_PEX2_STN1_TX_DN<16>
P5E_PEX2_STN0_TX_C_DP<15>P5E_PEX2_STN0_TX_C_DN<15>P5E_PEX2_STN0_TX_C_DN<14>P5E_PEX2_STN0_TX_C_DP<14>P5E_PEX2_STN0_TX_C_DP<13>P5E_PEX2_STN0_TX_C_DN<13>P5E_PEX2_STN0_TX_C_DN<12>P5E_PEX2_STN0_TX_C_DP<12>P5E_PEX2_STN0_TX_C_DP<11>P5E_PEX2_STN0_TX_C_DN<11>P5E_PEX2_STN0_TX_C_DP<10>P5E_PEX2_STN0_TX_C_DN<10>P5E_PEX2_STN0_TX_C_DP<9>P5E_PEX2_STN0_TX_C_DN<9>P5E_PEX2_STN0_TX_C_DP<8>P5E_PEX2_STN0_TX_C_DN<8>P5E_PEX2_STN0_TX_C_DP<7>P5E_PEX2_STN0_TX_C_DN<7>P5E_PEX2_STN0_TX_C_DP<6>P5E_PEX2_STN0_TX_C_DN<6>P5E_PEX2_STN0_TX_C_DP<5>P5E_PEX2_STN0_TX_C_DN<5>P5E_PEX2_STN0_TX_C_DP<4>P5E_PEX2_STN0_TX_C_DN<4>P5E_PEX2_STN0_TX_C_DP<3>P5E_PEX2_STN0_TX_C_DN<3>P5E_PEX2_STN0_TX_C_DP<2>P5E_PEX2_STN0_TX_C_DN<2>P5E_PEX2_STN0_TX_C_DP<1>P5E_PEX2_STN0_TX_C_DN<1>P5E_PEX2_STN0_TX_C_DP<0>P5E_PEX2_STN0_TX_C_DN<0>P5E_PEX2_STN1_TX_C_DP<16>P5E_PEX2_STN1_TX_C_DN<16>P5E_PEX2_STN1_TX_C_DN<17>P5E_PEX2_STN1_TX_C_DP<17>P5E_PEX2_STN1_TX_C_DN<19>P5E_PEX2_STN1_TX_C_DP<19>P5E_PEX2_STN1_TX_C_DP<18>P5E_PEX2_STN1_TX_C_DN<18>P5E_PEX2_STN1_TX_C_DN<23>P5E_PEX2_STN1_TX_C_DP<23>P5E_PEX2_STN1_TX_C_DP<22>P5E_PEX2_STN1_TX_C_DN<22>P5E_PEX2_STN1_TX_C_DN<21>P5E_PEX2_STN1_TX_C_DP<21>P5E_PEX2_STN1_TX_C_DP<20>P5E_PEX2_STN1_TX_C_DN<20>P5E_PEX2_STN1_TX_C_DP<24>P5E_PEX2_STN1_TX_C_DN<24>P5E_PEX2_STN1_TX_C_DN<25>P5E_PEX2_STN1_TX_C_DP<25>P5E_PEX2_STN1_TX_C_DN<27>P5E_PEX2_STN1_TX_C_DP<27>P5E_PEX2_STN1_TX_C_DP<26>P5E_PEX2_STN1_TX_C_DN<26>P5E_PEX2_STN1_TX_C_DN<31>P5E_PEX2_STN1_TX_C_DP<31>P5E_PEX2_STN1_TX_C_DP<30>P5E_PEX2_STN1_TX_C_DN<30>P5E_PEX2_STN1_TX_C_DN<29>P5E_PEX2_STN1_TX_C_DP<29>P5E_PEX2_STN1_TX_C_DP<28>P5E_PEX2_STN1_TX_C_DN<28>
P5E_PEX2_STN0_RX_DP<15>P5E_PEX2_STN0_RX_DN<15>P5E_PEX2_STN0_RX_DP<14>P5E_PEX2_STN0_RX_DN<14>P5E_PEX2_STN0_RX_DP<13>P5E_PEX2_STN0_RX_DN<13>P5E_PEX2_STN0_RX_DP<12>P5E_PEX2_STN0_RX_DN<12>P5E_PEX2_STN0_RX_DP<11>P5E_PEX2_STN0_RX_DN<11>P5E_PEX2_STN0_RX_DP<10>P5E_PEX2_STN0_RX_DN<10>P5E_PEX2_STN0_RX_DP<9>P5E_PEX2_STN0_RX_DN<9>P5E_PEX2_STN0_RX_DP<8>P5E_PEX2_STN0_RX_DN<8>P5E_PEX2_STN0_RX_DP<7>P5E_PEX2_STN0_RX_DN<7>P5E_PEX2_STN0_RX_DP<6>P5E_PEX2_STN0_RX_DN<6>P5E_PEX2_STN0_RX_DP<5>P5E_PEX2_STN0_RX_DN<5>P5E_PEX2_STN0_RX_DP<4>P5E_PEX2_STN0_RX_DN<4>P5E_PEX2_STN0_RX_DP<3>P5E_PEX2_STN0_RX_DN<3>P5E_PEX2_STN0_RX_DP<2>P5E_PEX2_STN0_RX_DN<2>P5E_PEX2_STN0_RX_DP<1>P5E_PEX2_STN0_RX_DN<1>P5E_PEX2_STN0_RX_DP<0>P5E_PEX2_STN0_RX_DN<0>P5E_PEX2_STN1_RX_DP<31>P5E_PEX2_STN1_RX_DN<31>P5E_PEX2_STN1_RX_DP<30>P5E_PEX2_STN1_RX_DN<30>P5E_PEX2_STN1_RX_DP<29>P5E_PEX2_STN1_RX_DN<29>P5E_PEX2_STN1_RX_DP<28>P5E_PEX2_STN1_RX_DN<28>P5E_PEX2_STN1_RX_DP<27>P5E_PEX2_STN1_RX_DN<27>P5E_PEX2_STN1_RX_DP<26>P5E_PEX2_STN1_RX_DN<26>P5E_PEX2_STN1_RX_DP<25>P5E_PEX2_STN1_RX_DN<25>P5E_PEX2_STN1_RX_DP<24>P5E_PEX2_STN1_RX_DN<24>P5E_PEX2_STN1_RX_DP<23>P5E_PEX2_STN1_RX_DN<23>P5E_PEX2_STN1_RX_DP<22>P5E_PEX2_STN1_RX_DN<22>P5E_PEX2_STN1_RX_DP<21>P5E_PEX2_STN1_RX_DN<21>P5E_PEX2_STN1_RX_DP<20>P5E_PEX2_STN1_RX_DN<20>P5E_PEX2_STN1_RX_DP<19>P5E_PEX2_STN1_RX_DN<19>P5E_PEX2_STN1_RX_DP<18>P5E_PEX2_STN1_RX_DN<18>P5E_PEX2_STN1_RX_DP<17>P5E_PEX2_STN1_RX_DN<17>P5E_PEX2_STN1_RX_DP<16>P5E_PEX2_STN1_RX_DN<16>



5
5
4
4
3
3
2
2
1
1
D D
C C
B B
A A
PEX_2_STN_23(2/11)
P5E_PEX2_STN2_TX_C_DP<47> [198]P5E_PEX2_STN2_TX_C_DN<47> [198]P5E_PEX2_STN2_TX_C_DP<46> [198]P5E_PEX2_STN2_TX_C_DN<46> [198]P5E_PEX2_STN2_TX_C_DP<45> [198]P5E_PEX2_STN2_TX_C_DN<45> [198]P5E_PEX2_STN2_TX_C_DP<44> [198]P5E_PEX2_STN2_TX_C_DN<44> [198]P5E_PEX2_STN2_TX_C_DP<43> [198]P5E_PEX2_STN2_TX_C_DN<43> [198]P5E_PEX2_STN2_TX_C_DP<42> [198]P5E_PEX2_STN2_TX_C_DN<42> [198]P5E_PEX2_STN2_TX_C_DP<41> [198]P5E_PEX2_STN2_TX_C_DN<41> [198]P5E_PEX2_STN2_TX_C_DP<40> [198]P5E_PEX2_STN2_TX_C_DN<40> [198]P5E_PEX2_STN2_TX_C_DP<39> [199]P5E_PEX2_STN2_TX_C_DN<39> [199]P5E_PEX2_STN2_TX_C_DP<38> [199]P5E_PEX2_STN2_TX_C_DN<38> [199]P5E_PEX2_STN2_TX_C_DP<37> [199]P5E_PEX2_STN2_TX_C_DN<37> [199]P5E_PEX2_STN2_TX_C_DP<36> [199]P5E_PEX2_STN2_TX_C_DN<36> [199]P5E_PEX2_STN2_TX_C_DP<35> [199]P5E_PEX2_STN2_TX_C_DN<35> [199]P5E_PEX2_STN2_TX_C_DP<34> [199]P5E_PEX2_STN2_TX_C_DN<34> [199]P5E_PEX2_STN2_TX_C_DP<33> [199]P5E_PEX2_STN2_TX_C_DN<33> [199]P5E_PEX2_STN2_TX_C_DP<32> [199]P5E_PEX2_STN2_TX_C_DN<32> [199]P5E_PEX2_STN2_RX_DP<47>[198]P5E_PEX2_STN2_RX_DN<47>[198]P5E_PEX2_STN2_RX_DP<46>[198]P5E_PEX2_STN2_RX_DN<46>[198]P5E_PEX2_STN2_RX_DP<45>[198]P5E_PEX2_STN2_RX_DN<45>[198]P5E_PEX2_STN2_RX_DP<44>[198]P5E_PEX2_STN2_RX_DN<44>[198]P5E_PEX2_STN2_RX_DP<43>[198]P5E_PEX2_STN2_RX_DN<43>[198]P5E_PEX2_STN2_RX_DP<42>[198]P5E_PEX2_STN2_RX_DN<42>[198]P5E_PEX2_STN2_RX_DP<41>[198]P5E_PEX2_STN2_RX_DN<41>[198]P5E_PEX2_STN2_RX_DP<40>[198]P5E_PEX2_STN2_RX_DN<40>[198]P5E_PEX2_STN2_RX_DP<39>[199]P5E_PEX2_STN2_RX_DN<39>[199]P5E_PEX2_STN2_RX_DP<38>[199]P5E_PEX2_STN2_RX_DN<38>[199]P5E_PEX2_STN2_RX_DP<37>[199]P5E_PEX2_STN2_RX_DN<37>[199]P5E_PEX2_STN2_RX_DP<36>[199]P5E_PEX2_STN2_RX_DN<36>[199]P5E_PEX2_STN2_RX_DP<35>[199]P5E_PEX2_STN2_RX_DN<35>[199]P5E_PEX2_STN2_RX_DP<34>[199]P5E_PEX2_STN2_RX_DN<34>[199]P5E_PEX2_STN2_RX_DP<33>[199]P5E_PEX2_STN2_RX_DN<33>[199]P5E_PEX2_STN2_RX_DP<32>[199]P5E_PEX2_STN2_RX_DN<32>[199]
SizeDoc NumberRevDate: SheetofReviewerDesignerDepartmentProject
Page TitleCCBU D37 257Tuesday, August 29, 2023<project_name><Designer> GRANDTETON_SWB_20230829037 PEX_2_STN_23(2/11)<Reviewer>SizeDoc NumberRevDate: SheetofReviewerDesignerDepartmentProject
Page TitleCCBU D37 257Tuesday, August 29, 2023<project_name><Designer> GRANDTETON_SWB_20230829037 PEX_2_STN_23(2/11)<Reviewer>SizeDoc NumberRevDate: SheetofReviewerDesignerDepartmentProject
Page TitleCCBU D37 257Tuesday, August 29, 2023<project_name><Designer> GRANDTETON_SWB_20230829037 PEX_2_STN_23(2/11)<Reviewer>
C507 DIFF BUS_0.22UFC495 DIFF BUS_0.22UFC508 DIFF BUS_0.22UF3/26PEX2CSS26-0A0P-01RXP47BH9RXN47BJ9RXP46BF10RXN46BG10RXP45BH11RXN45BJ11RXP44BF12RXN44BG12RXP43BH13RXN43BJ13RXP42BF14RXN42BG14RXP41BH15RXN41BJ15RXP40BF16RXN40BG16RXP39BH17RXN39BJ17RXP38BF18RXN38BG18RXP37BH19RXN37BJ19RXP36BF20RXN36BG20RXP35BH21RXN35BJ21RXP34BF22RXN34BG22RXP33BH23RXN33BJ23RXP32BF24RXN32BG24TXP47BC9TXN47BD9TXP46BA10TXN46BB10TXP45BC11TXN45BD11TXP44BA12TXN44BB12TXP43BC13TXN43BD13TXP42BA14TXN42BB14TXP41BC15TXN41BD15TXP40BA16TXN40BB16TXP39BC17TXN39BD17TXP38BA18TXN38BB18TXP37BC19TXN37BD19TXP36BA20TXN36BB20TXP35BC21TXN35BD21TXP34BA22TXN34BB22TXP33BC23TXN33BD23TXP32BA24TXN32BB24C496 DIFF BUS_0.22UFC509 DIFF BUS_0.22UFC497 DIFF BUS_0.22UFC510 DIFF BUS_0.22UF4/26PEX2DSS26-0A0P-01RXP63BF8RXN63BG8RXP62BH7RXN62BJ7RXP61BF6RXN61BG6RXP60BH5RXN60BJ5RXP59BF4RXN59BG4RXP58BH3RXN58BJ3RXP57BG2RXN57BG1RXP56AY2RXN56AY1RXP55AW4RXN55AW3RXP54AV2RXN54AV1RXP53AU4RXN53AU3RXP52AT2RXN52AT1RXP51AR4RXN51AR3RXP50AP2RXN50AP1RXP49AN4RXN49AN3RXP48AM2RXN48AM1TXP63BA8TXN63BB8TXP62BC7TXN62BD7TXP61BA6TXN61BB6TXP60BC5TXN60BD5TXP59BA4TXN59BB4TXP58BC3TXN58BD3TXP57BE2TXN57BE1TXP56BB2TXN56BB1TXP55AW7TXN55AW6TXP54AV9TXN54AV8TXP53AU7TXN53AU6TXP52AT9TXN52AT8TXP51AR7TXN51AR6TXP50AP9TXN50AP8TXP49AN7TXN49AN6TXP48AM9TXN48AM8
C498 DIFF BUS_0.22UFC511 DIFF BUS_0.22UFC499 DIFF BUS_0.22UFC512 DIFF BUS_0.22UFC487 DIFF BUS_0.22UFC500 DIFF BUS_0.22UFC513 DIFF BUS_0.22UFC488 DIFF BUS_0.22UFC501 DIFF BUS_0.22UFC514 DIFF BUS_0.22UFC489 DIFF BUS_0.22UFC502 DIFF BUS_0.22UFC515 DIFF BUS_0.22UFC490 DIFF BUS_0.22UFC503 DIFF BUS_0.22UFC516 DIFF BUS_0.22UFC491 DIFF BUS_0.22UFC504 DIFF BUS_0.22UFC517 DIFF BUS_0.22UFC492 DIFF BUS_0.22UFC505 DIFF BUS_0.22UFC518 DIFF BUS_0.22UFC493 DIFF BUS_0.22UFC506 DIFF BUS_0.22UFC494 DIFF BUS_0.22UFP5E_PEX2_STN2_TX_DP<47>P5E_PEX2_STN2_TX_DN<47>P5E_PEX2_STN2_TX_DP<39>P5E_PEX2_STN2_TX_DN<39>P5E_PEX2_STN2_TX_DP<46>P5E_PEX2_STN2_TX_DN<46>P5E_PEX2_STN2_TX_DP<45>P5E_PEX2_STN2_TX_DN<45>P5E_PEX2_STN2_TX_DP<44>P5E_PEX2_STN2_TX_DN<44>P5E_PEX2_STN2_TX_DP<43>P5E_PEX2_STN2_TX_DN<43>P5E_PEX2_STN2_TX_DP<42>P5E_PEX2_STN2_TX_DN<42>P5E_PEX2_STN2_TX_DP<41>P5E_PEX2_STN2_TX_DN<41>P5E_PEX2_STN2_TX_DP<40>P5E_PEX2_STN2_TX_DN<40>P5E_PEX2_STN2_TX_DP<38>P5E_PEX2_STN2_TX_DN<38>P5E_PEX2_STN2_TX_DP<37>P5E_PEX2_STN2_TX_DN<37>P5E_PEX2_STN2_TX_DP<36>P5E_PEX2_STN2_TX_DN<36>P5E_PEX2_STN2_TX_DP<35>P5E_PEX2_STN2_TX_DN<35>P5E_PEX2_STN2_TX_DP<34>P5E_PEX2_STN2_TX_DN<34>P5E_PEX2_STN2_TX_DP<33>P5E_PEX2_STN2_TX_DN<33>P5E_PEX2_STN2_TX_DP<32>P5E_PEX2_STN2_TX_DN<32>P5E_PEX2_STN2_TX_C_DP<47>P5E_PEX2_STN2_TX_C_DN<47>P5E_PEX2_STN2_TX_C_DP<46>P5E_PEX2_STN2_TX_C_DN<46>P5E_PEX2_STN2_TX_C_DP<45>P5E_PEX2_STN2_TX_C_DN<45>P5E_PEX2_STN2_TX_C_DP<44>P5E_PEX2_STN2_TX_C_DN<44>P5E_PEX2_STN2_TX_C_DP<43>P5E_PEX2_STN2_TX_C_DN<43>P5E_PEX2_STN2_TX_C_DP<42>P5E_PEX2_STN2_TX_C_DN<42>P5E_PEX2_STN2_TX_C_DP<41>P5E_PEX2_STN2_TX_C_DN<41>P5E_PEX2_STN2_TX_C_DP<40>P5E_PEX2_STN2_TX_C_DN<40>P5E_PEX2_STN2_TX_C_DP<39>P5E_PEX2_STN2_TX_C_DN<39>P5E_PEX2_STN2_TX_C_DP<38>P5E_PEX2_STN2_TX_C_DN<38>P5E_PEX2_STN2_TX_C_DP<37>P5E_PEX2_STN2_TX_C_DN<37>P5E_PEX2_STN2_TX_C_DP<36>P5E_PEX2_STN2_TX_C_DN<36>P5E_PEX2_STN2_TX_C_DP<35>P5E_PEX2_STN2_TX_C_DN<35>P5E_PEX2_STN2_TX_C_DP<34>P5E_PEX2_STN2_TX_C_DN<34>P5E_PEX2_STN2_TX_C_DP<33>P5E_PEX2_STN2_TX_C_DN<33>P5E_PEX2_STN2_TX_C_DP<32>P5E_PEX2_STN2_TX_C_DN<32>P5E_PEX2_STN2_RX_DP<47>P5E_PEX2_STN2_RX_DN<47>P5E_PEX2_STN2_RX_DP<46>P5E_PEX2_STN2_RX_DN<46>P5E_PEX2_STN2_RX_DP<45>P5E_PEX2_STN2_RX_DN<45>P5E_PEX2_STN2_RX_DP<44>P5E_PEX2_STN2_RX_DN<44>P5E_PEX2_STN2_RX_DP<43>P5E_PEX2_STN2_RX_DN<43>P5E_PEX2_STN2_RX_DP<42>P5E_PEX2_STN2_RX_DN<42>P5E_PEX2_STN2_RX_DP<41>P5E_PEX2_STN2_RX_DN<41>P5E_PEX2_STN2_RX_DP<40>P5E_PEX2_STN2_RX_DN<40>P5E_PEX2_STN2_RX_DP<39>P5E_PEX2_STN2_RX_DN<39>P5E_PEX2_STN2_RX_DP<38>P5E_PEX2_STN2_RX_DN<38>P5E_PEX2_STN2_RX_DP<37>P5E_PEX2_STN2_RX_DN<37>P5E_PEX2_STN2_RX_DP<36>P5E_PEX2_STN2_RX_DN<36>P5E_PEX2_STN2_RX_DP<35>P5E_PEX2_STN2_RX_DN<35>P5E_PEX2_STN2_RX_DP<34>P5E_PEX2_STN2_RX_DN<34>P5E_PEX2_STN2_RX_DP<33>P5E_PEX2_STN2_RX_DN<33>P5E_PEX2_STN2_RX_DP<32>P5E_PEX2_STN2_RX_DN<32>



5
5
4
4
3
3
2
2
1
1
D D
C C
B B
A A
PEX_2_STN_45(3/11)
P5E_PEX2_STN4_RX_DP<79>[144]P5E_PEX2_STN4_TX_C_DP<79> [144]P5E_PEX2_STN4_RX_DN<79>[144]P5E_PEX2_STN4_TX_C_DN<79> [144]P5E_PEX2_STN4_RX_DP<78>[144]P5E_PEX2_STN4_TX_C_DP<78> [144]P5E_PEX2_STN4_RX_DN<78>[144]P5E_PEX2_STN4_TX_C_DN<78> [144]P5E_PEX2_STN4_RX_DP<77>[145]P5E_PEX2_STN4_TX_C_DP<77> [145]P5E_PEX2_STN4_RX_DN<77>[145]P5E_PEX2_STN4_TX_C_DN<77> [145]P5E_PEX2_STN4_RX_DP<76>[145]P5E_PEX2_STN4_TX_C_DP<76> [145]P5E_PEX2_STN4_RX_DN<76>[145]P5E_PEX2_STN4_TX_C_DN<76> [145]P5E_PEX2_STN4_RX_DP<75>[146]P5E_PEX2_STN4_TX_C_DP<75> [146]P5E_PEX2_STN4_RX_DN<75>[146]P5E_PEX2_STN4_TX_C_DN<75> [146]P5E_PEX2_STN4_RX_DP<74>[146]P5E_PEX2_STN4_TX_C_DP<74> [146]P5E_PEX2_STN4_RX_DN<74>[146]P5E_PEX2_STN4_TX_C_DN<74> [146]P5E_PEX2_STN4_RX_DP<73>[147]P5E_PEX2_STN4_TX_C_DP<73> [147]P5E_PEX2_STN4_RX_DN<73>[147]P5E_PEX2_STN4_TX_C_DN<73> [147]P5E_PEX2_STN4_RX_DP<72>[147]P5E_PEX2_STN4_TX_C_DP<72> [147]P5E_PEX2_STN4_RX_DN<72>[147]P5E_PEX2_STN4_TX_C_DN<72> [147]P5E_PEX2_STN4_RX_DP<71>[144]P5E_PEX2_STN4_TX_C_DP<71> [144]P5E_PEX2_STN4_RX_DN<71>[144]P5E_PEX2_STN4_TX_C_DN<71> [144]P5E_PEX2_STN4_RX_DP<70>[144]P5E_PEX2_STN4_TX_C_DP<70> [144]P5E_PEX2_STN4_RX_DN<70>[144]P5E_PEX2_STN4_TX_C_DN<70> [144]P5E_PEX2_STN4_RX_DP<69>[145]P5E_PEX2_STN4_TX_C_DP<69> [145]P5E_PEX2_STN4_RX_DN<69>[145]P5E_PEX2_STN4_TX_C_DN<69> [145]P5E_PEX2_STN4_RX_DP<68>[145]P5E_PEX2_STN4_TX_C_DP<68> [145]P5E_PEX2_STN4_RX_DN<68>[145]P5E_PEX2_STN4_TX_C_DN<68> [145]P5E_PEX2_STN4_RX_DP<67>[146]P5E_PEX2_STN4_TX_C_DP<67> [146]P5E_PEX2_STN4_RX_DN<67>[146]P5E_PEX2_STN4_TX_C_DN<67> [146]P5E_PEX2_STN4_RX_DP<66>[146]P5E_PEX2_STN4_TX_C_DP<66> [146]P5E_PEX2_STN4_RX_DN<66>[146]P5E_PEX2_STN4_TX_C_DN<66> [146]P5E_PEX2_STN4_RX_DP<65>[147]P5E_PEX2_STN4_TX_C_DP<65> [147]P5E_PEX2_STN4_RX_DN<65>[147]P5E_PEX2_STN4_TX_C_DN<65> [147]P5E_PEX2_STN4_RX_DP<64>[147]P5E_PEX2_STN4_TX_C_DP<64> [147]P5E_PEX2_STN4_RX_DN<64>[147]P5E_PEX2_STN4_TX_C_DN<64> [147]P5E_PEX2_STN5_RX_DP<95>[152]P5E_PEX2_STN5_TX_C_DP<95> [152]P5E_PEX2_STN5_RX_DN<95>[152]P5E_PEX2_STN5_TX_C_DN<95> [152]P5E_PEX2_STN5_RX_DP<94>[152]P5E_PEX2_STN5_TX_C_DP<94> [152]P5E_PEX2_STN5_RX_DN<94>[152]P5E_PEX2_STN5_TX_C_DN<94> [152]P5E_PEX2_STN5_RX_DP<93>[151]P5E_PEX2_STN5_TX_C_DP<93> [151]P5E_PEX2_STN5_RX_DN<93>[151]P5E_PEX2_STN5_TX_C_DN<93> [151]P5E_PEX2_STN5_RX_DP<92>[151]P5E_PEX2_STN5_TX_C_DP<92> [151]P5E_PEX2_STN5_RX_DN<92>[151]P5E_PEX2_STN5_TX_C_DN<92> [151]P5E_PEX2_STN5_RX_DP<91>[150]P5E_PEX2_STN5_TX_C_DP<91> [150]P5E_PEX2_STN5_RX_DN<91>[150]P5E_PEX2_STN5_TX_C_DN<91> [150]P5E_PEX2_STN5_RX_DP<90>[150]P5E_PEX2_STN5_TX_C_DP<90> [150]P5E_PEX2_STN5_RX_DN<90>[150]P5E_PEX2_STN5_TX_C_DN<90> [150]P5E_PEX2_STN5_RX_DP<89>[149]P5E_PEX2_STN5_TX_C_DP<89> [149]P5E_PEX2_STN5_RX_DN<89>[149]P5E_PEX2_STN5_TX_C_DN<89> [149]P5E_PEX2_STN5_RX_DP<88>[149]P5E_PEX2_STN5_TX_C_DP<88> [149]P5E_PEX2_STN5_RX_DN<88>[149]P5E_PEX2_STN5_TX_C_DN<88> [149]P5E_PEX2_STN5_RX_DP<87>[152]P5E_PEX2_STN5_TX_C_DP<87> [152]P5E_PEX2_STN5_RX_DN<87>[152]P5E_PEX2_STN5_TX_C_DN<87> [152]P5E_PEX2_STN5_RX_DP<86>[152]P5E_PEX2_STN5_TX_C_DP<86> [152]P5E_PEX2_STN5_RX_DN<86>[152]P5E_PEX2_STN5_TX_C_DN<86> [152]P5E_PEX2_STN5_RX_DP<85>[151]P5E_PEX2_STN5_TX_C_DP<85> [151]P5E_PEX2_STN5_RX_DN<85>[151]P5E_PEX2_STN5_TX_C_DN<85> [151]P5E_PEX2_STN5_RX_DP<84>[151]P5E_PEX2_STN5_TX_C_DP<84> [151]P5E_PEX2_STN5_RX_DN<84>[151]P5E_PEX2_STN5_TX_C_DN<84> [151]P5E_PEX2_STN5_RX_DP<83>[150]P5E_PEX2_STN5_TX_C_DP<83> [150]P5E_PEX2_STN5_RX_DN<83>[150]P5E_PEX2_STN5_TX_C_DN<83> [150]P5E_PEX2_STN5_RX_DP<82>[150]P5E_PEX2_STN5_TX_C_DP<82> [150]P5E_PEX2_STN5_RX_DN<82>[150]P5E_PEX2_STN5_TX_C_DN<82> [150]P5E_PEX2_STN5_RX_DP<81>[149]P5E_PEX2_STN5_TX_C_DP<81> [149]P5E_PEX2_STN5_RX_DN<81>[149]P5E_PEX2_STN5_TX_C_DN<81> [149]P5E_PEX2_STN5_RX_DP<80>[149]P5E_PEX2_STN5_TX_C_DP<80> [149]P5E_PEX2_STN5_RX_DN<80>[149]P5E_PEX2_STN5_TX_C_DN<80> [149]SizeDoc NumberRevDate: SheetofReviewerDesignerDepartmentProject
Page TitleCCBU D38 257Tuesday, August 29, 2023<project_name><Designer> GRANDTETON_SWB_20230829038 PEX_2_STN_45(3/11)<Reviewer>SizeDoc NumberRevDate: SheetofReviewerDesignerDepartmentProject
Page TitleCCBU D38 257Tuesday, August 29, 2023<project_name><Designer> GRANDTETON_SWB_20230829038 PEX_2_STN_45(3/11)<Reviewer>SizeDoc NumberRevDate: SheetofReviewerDesignerDepartmentProject
Page TitleCCBU D38 257Tuesday, August 29, 2023<project_name><Designer> GRANDTETON_SWB_20230829038 PEX_2_STN_45(3/11)<Reviewer>
C2351 DIFF BUS_0.22UFC520 DIFF BUS_0.22UFC2361 DIFF BUS_0.22UFC533 DIFF BUS_0.22UF6/26PEX2FSS26-0A0P-01RXP95B39RXN95A39RXP94D38RXN94C38RXP93B37RXN93A37RXP92D36RXN92C36RXP91B35RXN91A35RXP90D34RXN90C34RXP89B33RXN89A33RXP88D32RXN88C32RXP87B31RXN87A31RXP86D30RXN86C30RXP85B29RXN85A29RXP84D28RXN84C28RXP83B27RXN83A27RXP82D26RXN82C26RXP81B25RXN81A25RXP80D24RXN80C24TXP95G39TXN95F39TXP94J38TXN94H38TXP93G37TXN93F37TXP92J36TXN92H36TXP91G35TXN91F35TXP90J34TXN90H34TXP89G33TXN89F33TXP88J32TXN88H32TXP87G31TXN87F31TXP86J30TXN86H30TXP85G29TXN85F29TXP84J28TXN84H28TXP83G27TXN83F27TXP82J26TXN82H26TXP81G25TXN81F25TXP80J24TXN80H24C546 DIFF BUS_0.22UFC521 DIFF BUS_0.22UFC2353 DIFF BUS_0.22UFC534 DIFF BUS_0.22UFC2357 DIFF BUS_0.22UF
C547 DIFF BUS_0.22UFC522 DIFF BUS_0.22UFC2365 DIFF BUS_0.22UFC2360 DIFF BUS_0.22UFC535 DIFF BUS_0.22UFC548 DIFF BUS_0.22UF
C2342 DIFF BUS_0.22UFC523 DIFF BUS_0.22UFC2346 DIFF BUS_0.22UFC2372 DIFF BUS_0.22UFC536 DIFF BUS_0.22UF
C2352 DIFF BUS_0.22UF
C549 DIFF BUS_0.22UFC524 DIFF BUS_0.22UFC2349 DIFF BUS_0.22UFC2362 DIFF BUS_0.22UFC537 DIFF BUS_0.22UF
C2347 DIFF BUS_0.22UFC2344 DIFF BUS_0.22UF
C550 DIFF BUS_0.22UF
C2350 DIFF BUS_0.22UFC525 DIFF BUS_0.22UFC2367 DIFF BUS_0.22UFC2341 DIFF BUS_0.22UF
C538 DIFF BUS_0.22UFC2358 DIFF BUS_0.22UFC2348 DIFF BUS_0.22UFC526 DIFF BUS_0.22UFC2368 DIFF BUS_0.22UFC539 DIFF BUS_0.22UFC2359 DIFF BUS_0.22UFC2369 DIFF BUS_0.22UFC2354 DIFF BUS_0.22UFC527 DIFF BUS_0.22UF
5/26PEX2ESS26-0A0P-01RXP79D40RXN79C40RXP78B41RXN78A41RXP77D42RXN77C42RXP76B43RXN76A43RXP75D44RXN75C44RXP74B45RXN74A45RXP73D46RXN73C46RXP72B47RXN72A47RXP71C48RXN71C49RXP70K48RXN70K49RXP69L46RXN69L47RXP68M48RXN68M49RXP67N46RXN67N47RXP66P48RXN66P49RXP65R46RXN65R47RXP64T48RXN64T49TXP79J40TXN79H40TXP78G41TXN78F41TXP77J42TXN77H42TXP76G43TXN76F43TXP75J44TXN75H44TXP74G45TXN74F45TXP73J46TXN73H46TXP72G47TXN72F47TXP71E48TXN71E49TXP70H48TXN70H49TXP69L43TXN69L44TXP68M41TXN68M42TXP67N43TXN67N44TXP66P41TXN66P42TXP65R43TXN65R44TXP64T41TXN64T42C540 DIFF BUS_0.22UFC528 DIFF BUS_0.22UFC541 DIFF BUS_0.22UF
C2355 DIFF BUS_0.22UFC2345 DIFF BUS_0.22UF
C529 DIFF BUS_0.22UFC2371 DIFF BUS_0.22UFC542 DIFF BUS_0.22UF
C2356 DIFF BUS_0.22UFC2370 DIFF BUS_0.22UFC530 DIFF BUS_0.22UFC543 DIFF BUS_0.22UFC531 DIFF BUS_0.22UFC2366 DIFF BUS_0.22UFC2343 DIFF BUS_0.22UFC2364 DIFF BUS_0.22UFC544 DIFF BUS_0.22UFC2363 DIFF BUS_0.22UFC519 DIFF BUS_0.22UFC532 DIFF BUS_0.22UFC545 DIFF BUS_0.22UF
P5E_PEX2_STN4_RX_DP<79>P5E_PEX2_STN4_TX_DP<79>P5E_PEX2_STN4_TX_C_DP<79>P5E_PEX2_STN4_RX_DN<79>P5E_PEX2_STN4_TX_DN<79>P5E_PEX2_STN4_TX_C_DN<79>P5E_PEX2_STN4_RX_DP<78>P5E_PEX2_STN4_TX_DP<78>P5E_PEX2_STN4_TX_C_DP<78>P5E_PEX2_STN4_RX_DN<78>P5E_PEX2_STN4_TX_DN<78>P5E_PEX2_STN4_TX_C_DN<78>P5E_PEX2_STN4_RX_DP<77>P5E_PEX2_STN4_TX_DP<77>P5E_PEX2_STN4_TX_C_DP<77>P5E_PEX2_STN4_RX_DN<77>P5E_PEX2_STN4_TX_DN<77>P5E_PEX2_STN4_TX_C_DN<77>P5E_PEX2_STN4_RX_DP<76>P5E_PEX2_STN4_TX_DP<76>P5E_PEX2_STN4_TX_C_DP<76>P5E_PEX2_STN4_RX_DN<76>P5E_PEX2_STN4_TX_DN<76>P5E_PEX2_STN4_TX_C_DN<76>P5E_PEX2_STN4_RX_DP<75>P5E_PEX2_STN4_TX_DP<75>P5E_PEX2_STN4_TX_C_DP<75>P5E_PEX2_STN4_RX_DN<75>P5E_PEX2_STN4_TX_DN<75>P5E_PEX2_STN4_TX_C_DN<75>P5E_PEX2_STN4_RX_DP<74>P5E_PEX2_STN4_TX_DP<74>P5E_PEX2_STN4_TX_C_DP<74>P5E_PEX2_STN4_RX_DN<74>P5E_PEX2_STN4_TX_DN<74>P5E_PEX2_STN4_TX_C_DN<74>P5E_PEX2_STN4_RX_DP<73>P5E_PEX2_STN4_TX_DP<73>P5E_PEX2_STN4_TX_C_DP<73>P5E_PEX2_STN4_RX_DN<73>P5E_PEX2_STN4_TX_DN<73>P5E_PEX2_STN4_TX_C_DN<73>P5E_PEX2_STN4_RX_DP<72>P5E_PEX2_STN4_TX_DP<72>P5E_PEX2_STN4_TX_C_DP<72>P5E_PEX2_STN4_RX_DN<72>P5E_PEX2_STN4_TX_DN<72>P5E_PEX2_STN4_TX_C_DN<72>P5E_PEX2_STN4_RX_DP<71>P5E_PEX2_STN4_TX_DP<71>P5E_PEX2_STN4_TX_C_DP<71>P5E_PEX2_STN4_RX_DN<71>P5E_PEX2_STN4_TX_DN<71>P5E_PEX2_STN4_TX_C_DN<71>P5E_PEX2_STN4_RX_DP<70>P5E_PEX2_STN4_TX_DP<70>P5E_PEX2_STN4_TX_C_DP<70>P5E_PEX2_STN4_RX_DN<70>P5E_PEX2_STN4_TX_DN<70>P5E_PEX2_STN4_TX_C_DN<70>P5E_PEX2_STN4_RX_DP<69>P5E_PEX2_STN4_TX_DP<69>P5E_PEX2_STN4_TX_C_DP<69>P5E_PEX2_STN4_RX_DN<69>P5E_PEX2_STN4_TX_DN<69>P5E_PEX2_STN4_TX_C_DN<69>P5E_PEX2_STN4_RX_DP<68>P5E_PEX2_STN4_TX_DP<68>P5E_PEX2_STN4_TX_C_DP<68>P5E_PEX2_STN4_RX_DN<68>P5E_PEX2_STN4_TX_DN<68>P5E_PEX2_STN4_TX_C_DN<68>P5E_PEX2_STN4_RX_DP<67>P5E_PEX2_STN4_TX_DP<67>P5E_PEX2_STN4_TX_C_DP<67>P5E_PEX2_STN4_RX_DN<67>P5E_PEX2_STN4_TX_DN<67>P5E_PEX2_STN4_TX_C_DN<67>P5E_PEX2_STN4_RX_DP<66>P5E_PEX2_STN4_TX_DP<66>P5E_PEX2_STN4_TX_C_DP<66>P5E_PEX2_STN4_RX_DN<66>P5E_PEX2_STN4_TX_DN<66>P5E_PEX2_STN4_TX_C_DN<66>P5E_PEX2_STN4_RX_DP<65>P5E_PEX2_STN4_TX_DP<65>P5E_PEX2_STN4_TX_C_DP<65>P5E_PEX2_STN4_RX_DN<65>P5E_PEX2_STN4_TX_DN<65>P5E_PEX2_STN4_TX_C_DN<65>P5E_PEX2_STN4_RX_DP<64>P5E_PEX2_STN4_TX_DP<64>P5E_PEX2_STN4_TX_C_DP<64>P5E_PEX2_STN4_RX_DN<64>P5E_PEX2_STN4_TX_DN<64>P5E_PEX2_STN4_TX_C_DN<64>P5E_PEX2_STN5_RX_DP<95>P5E_PEX2_STN5_TX_DP<95>P5E_PEX2_STN5_TX_C_DP<95>P5E_PEX2_STN5_RX_DN<95>P5E_PEX2_STN5_TX_DN<95>P5E_PEX2_STN5_TX_C_DN<95>P5E_PEX2_STN5_RX_DP<94>P5E_PEX2_STN5_TX_DP<94>P5E_PEX2_STN5_TX_C_DP<94>P5E_PEX2_STN5_RX_DN<94>P5E_PEX2_STN5_TX_DN<94>P5E_PEX2_STN5_TX_C_DN<94>P5E_PEX2_STN5_RX_DP<93>P5E_PEX2_STN5_TX_DP<93>P5E_PEX2_STN5_TX_C_DP<93>P5E_PEX2_STN5_RX_DN<93>P5E_PEX2_STN5_TX_DN<93>P5E_PEX2_STN5_TX_C_DN<93>P5E_PEX2_STN5_RX_DP<92>P5E_PEX2_STN5_TX_DP<92>P5E_PEX2_STN5_TX_C_DP<92>P5E_PEX2_STN5_RX_DN<92>P5E_PEX2_STN5_TX_DN<92>P5E_PEX2_STN5_TX_C_DN<92>P5E_PEX2_STN5_RX_DP<91>P5E_PEX2_STN5_TX_DP<91>P5E_PEX2_STN5_TX_C_DP<91>P5E_PEX2_STN5_RX_DN<91>P5E_PEX2_STN5_TX_DN<91>P5E_PEX2_STN5_TX_C_DN<91>P5E_PEX2_STN5_RX_DP<90>P5E_PEX2_STN5_TX_DP<90>P5E_PEX2_STN5_TX_C_DP<90>P5E_PEX2_STN5_RX_DN<90>P5E_PEX2_STN5_TX_DN<90>P5E_PEX2_STN5_TX_C_DN<90>P5E_PEX2_STN5_RX_DP<89>P5E_PEX2_STN5_TX_DP<89>P5E_PEX2_STN5_TX_C_DP<89>P5E_PEX2_STN5_RX_DN<89>P5E_PEX2_STN5_TX_DN<89>P5E_PEX2_STN5_TX_C_DN<89>P5E_PEX2_STN5_RX_DP<88>P5E_PEX2_STN5_TX_DP<88>P5E_PEX2_STN5_TX_C_DP<88>P5E_PEX2_STN5_RX_DN<88>P5E_PEX2_STN5_TX_DN<88>P5E_PEX2_STN5_TX_C_DN<88>P5E_PEX2_STN5_RX_DP<87>P5E_PEX2_STN5_TX_DP<87>P5E_PEX2_STN5_TX_C_DP<87>P5E_PEX2_STN5_RX_DN<87>P5E_PEX2_STN5_TX_DN<87>P5E_PEX2_STN5_TX_C_DN<87>P5E_PEX2_STN5_RX_DP<86>P5E_PEX2_STN5_TX_DP<86>P5E_PEX2_STN5_TX_C_DP<86>P5E_PEX2_STN5_RX_DN<86>P5E_PEX2_STN5_TX_DN<86>P5E_PEX2_STN5_TX_C_DN<86>P5E_PEX2_STN5_RX_DP<85>P5E_PEX2_STN5_TX_DP<85>P5E_PEX2_STN5_TX_C_DP<85>P5E_PEX2_STN5_RX_DN<85>P5E_PEX2_STN5_TX_DN<85>P5E_PEX2_STN5_TX_C_DN<85>P5E_PEX2_STN5_RX_DP<84>P5E_PEX2_STN5_TX_DP<84>P5E_PEX2_STN5_TX_C_DP<84>P5E_PEX2_STN5_RX_DN<84>P5E_PEX2_STN5_TX_DN<84>P5E_PEX2_STN5_TX_C_DN<84>P5E_PEX2_STN5_RX_DP<83>P5E_PEX2_STN5_TX_DP<83>P5E_PEX2_STN5_TX_C_DP<83>P5E_PEX2_STN5_RX_DN<83>P5E_PEX2_STN5_TX_DN<83>P5E_PEX2_STN5_TX_C_DN<83>P5E_PEX2_STN5_RX_DP<82>P5E_PEX2_STN5_TX_DP<82>P5E_PEX2_STN5_TX_C_DP<82>P5E_PEX2_STN5_RX_DN<82>P5E_PEX2_STN5_TX_DN<82>P5E_PEX2_STN5_TX_C_DN<82>P5E_PEX2_STN5_RX_DP<81>P5E_PEX2_STN5_TX_DP<81>P5E_PEX2_STN5_TX_C_DP<81>P5E_PEX2_STN5_RX_DN<81>P5E_PEX2_STN5_TX_DN<81>P5E_PEX2_STN5_TX_C_DN<81>P5E_PEX2_STN5_RX_DP<80>P5E_PEX2_STN5_TX_DP<80>P5E_PEX2_STN5_TX_C_DP<80>P5E_PEX2_STN5_RX_DN<80>P5E_PEX2_STN5_TX_DN<80>P5E_PEX2_STN5_TX_C_DN<80>



5
5
4
4
3
3
2
2
1
1
D D
C C
B B
A A
PEX_2_STN_67(4/11)
P5E_PEX2_STN7_TX_C_DP<112> [144]P5E_PEX2_STN7_TX_C_DN<112> [144]P5E_PEX2_STN7_TX_C_DP<113> [144]P5E_PEX2_STN7_TX_C_DN<113> [144]P5E_PEX2_STN7_TX_C_DP<115> [145]P5E_PEX2_STN7_TX_C_DN<115> [145]P5E_PEX2_STN7_TX_C_DP<114> [145]P5E_PEX2_STN7_TX_C_DN<114> [145]P5E_PEX2_STN7_TX_C_DP<119> [147]P5E_PEX2_STN7_TX_C_DN<119> [147]P5E_PEX2_STN7_TX_C_DP<118> [147]P5E_PEX2_STN7_TX_C_DN<118> [147]P5E_PEX2_STN7_TX_C_DP<117> [146]P5E_PEX2_STN7_TX_C_DN<117> [146]P5E_PEX2_STN7_TX_C_DP<116> [146]P5E_PEX2_STN7_TX_C_DN<116> [146]P5E_PEX2_STN7_TX_C_DP<120> [144]P5E_PEX2_STN7_TX_C_DN<120> [144]P5E_PEX2_STN7_TX_C_DP<121> [144]P5E_PEX2_STN7_TX_C_DN<121> [144]P5E_PEX2_STN7_TX_C_DP<123> [145]P5E_PEX2_STN7_TX_C_DN<123> [145]P5E_PEX2_STN7_TX_C_DP<122> [145]P5E_PEX2_STN7_TX_C_DN<122> [145]P5E_PEX2_STN7_TX_C_DP<127> [147]P5E_PEX2_STN7_TX_C_DN<127> [147]P5E_PEX2_STN7_TX_C_DP<126> [147]P5E_PEX2_STN7_TX_C_DN<126> [147]P5E_PEX2_STN7_TX_C_DP<125> [146]P5E_PEX2_STN7_TX_C_DN<125> [146]P5E_PEX2_STN7_TX_C_DP<124> [146]P5E_PEX2_STN7_TX_C_DN<124> [146]P5E_PEX2_STN7_RX_DP<127>[147]P5E_PEX2_STN7_RX_DN<127>[147]P5E_PEX2_STN7_RX_DP<126>[147]P5E_PEX2_STN7_RX_DN<126>[147]P5E_PEX2_STN7_RX_DP<125>[146]P5E_PEX2_STN7_RX_DN<125>[146]P5E_PEX2_STN7_RX_DP<124>[146]P5E_PEX2_STN7_RX_DN<124>[146]P5E_PEX2_STN7_RX_DP<123>[145]P5E_PEX2_STN7_RX_DN<123>[145]P5E_PEX2_STN7_RX_DP<122>[145]P5E_PEX2_STN7_RX_DN<122>[145]P5E_PEX2_STN7_RX_DP<121>[144]P5E_PEX2_STN7_RX_DN<121>[144]P5E_PEX2_STN7_RX_DP<120>[144]P5E_PEX2_STN7_RX_DN<120>[144]P5E_PEX2_STN7_RX_DP<119>[147]P5E_PEX2_STN7_RX_DN<119>[147]P5E_PEX2_STN7_RX_DP<118>[147]P5E_PEX2_STN7_RX_DN<118>[147]P5E_PEX2_STN7_RX_DP<117>[146]P5E_PEX2_STN7_RX_DN<117>[146]P5E_PEX2_STN7_RX_DP<116>[146]P5E_PEX2_STN7_RX_DN<116>[146]P5E_PEX2_STN7_RX_DP<115>[145]P5E_PEX2_STN7_RX_DN<115>[145]P5E_PEX2_STN7_RX_DP<114>[145]P5E_PEX2_STN7_RX_DN<114>[145]P5E_PEX2_STN7_RX_DP<113>[144]P5E_PEX2_STN7_RX_DN<113>[144]P5E_PEX2_STN7_RX_DP<112>[144]P5E_PEX2_STN7_RX_DN<112>[144]
P5E_PEX2_STN6_RX_DP<111>[149]P5E_PEX2_STN6_TX_C_DP<111> [149]P5E_PEX2_STN6_RX_DN<111>[149]P5E_PEX2_STN6_TX_C_DN<111> [149]P5E_PEX2_STN6_RX_DP<110>[149]P5E_PEX2_STN6_TX_C_DP<110> [149]P5E_PEX2_STN6_RX_DN<110>[149]P5E_PEX2_STN6_TX_C_DN<110> [149]P5E_PEX2_STN6_RX_DP<109>[150]P5E_PEX2_STN6_TX_C_DP<109> [150]P5E_PEX2_STN6_RX_DN<109>[150]P5E_PEX2_STN6_TX_C_DN<109> [150]P5E_PEX2_STN6_RX_DP<108>[150]P5E_PEX2_STN6_TX_C_DP<108> [150]P5E_PEX2_STN6_RX_DN<108>[150]P5E_PEX2_STN6_TX_C_DN<108> [150]P5E_PEX2_STN6_RX_DP<107>[151]P5E_PEX2_STN6_TX_C_DP<107> [151]P5E_PEX2_STN6_RX_DN<107>[151]P5E_PEX2_STN6_TX_C_DN<107> [151]P5E_PEX2_STN6_RX_DP<106>[151]P5E_PEX2_STN6_TX_C_DP<106> [151]P5E_PEX2_STN6_RX_DN<106>[151]P5E_PEX2_STN6_TX_C_DN<106> [151]P5E_PEX2_STN6_RX_DP<105>[152]P5E_PEX2_STN6_TX_C_DP<105> [152]P5E_PEX2_STN6_RX_DN<105>[152]P5E_PEX2_STN6_TX_C_DN<105> [152]P5E_PEX2_STN6_RX_DP<104>[152]P5E_PEX2_STN6_TX_C_DP<104> [152]P5E_PEX2_STN6_RX_DN<104>[152]P5E_PEX2_STN6_TX_C_DN<104> [152]P5E_PEX2_STN6_RX_DP<103>[149]P5E_PEX2_STN6_TX_C_DP<103> [149]P5E_PEX2_STN6_RX_DN<103>[149]P5E_PEX2_STN6_TX_C_DN<103> [149]P5E_PEX2_STN6_RX_DP<102>[149]P5E_PEX2_STN6_TX_C_DP<102> [149]P5E_PEX2_STN6_RX_DN<102>[149]P5E_PEX2_STN6_TX_C_DN<102> [149]P5E_PEX2_STN6_RX_DP<101>[150]P5E_PEX2_STN6_TX_C_DP<101> [150]P5E_PEX2_STN6_RX_DN<101>[150]P5E_PEX2_STN6_TX_C_DN<101> [150]P5E_PEX2_STN6_RX_DP<100>[150]P5E_PEX2_STN6_TX_C_DP<100> [150]P5E_PEX2_STN6_RX_DN<100>[150]P5E_PEX2_STN6_TX_C_DN<100> [150]P5E_PEX2_STN6_RX_DP<99>[151]P5E_PEX2_STN6_TX_C_DP<99> [151]P5E_PEX2_STN6_RX_DN<99>[151]P5E_PEX2_STN6_TX_C_DN<99> [151]P5E_PEX2_STN6_RX_DP<98>[151]P5E_PEX2_STN6_TX_C_DP<98> [151]P5E_PEX2_STN6_RX_DN<98>[151]P5E_PEX2_STN6_TX_C_DN<98> [151]P5E_PEX2_STN6_RX_DP<97>[152]P5E_PEX2_STN6_TX_C_DP<97> [152]P5E_PEX2_STN6_RX_DN<97>[152]P5E_PEX2_STN6_TX_C_DN<97> [152]P5E_PEX2_STN6_RX_DP<96>[152]P5E_PEX2_STN6_TX_C_DP<96> [152]P5E_PEX2_STN6_RX_DN<96>[152]P5E_PEX2_STN6_TX_C_DN<96> [152]
SizeDoc NumberRevDate: SheetofReviewerDesignerDepartmentProject
Page TitleCCBU D39 257Tuesday, August 29, 2023<project_name><Designer> GRANDTETON_SWB_20230829039 PEX_2_STN_67(4/11)<Reviewer>SizeDoc NumberRevDate: SheetofReviewerDesignerDepartmentProject
Page TitleCCBU D39 257Tuesday, August 29, 2023<project_name><Designer> GRANDTETON_SWB_20230829039 PEX_2_STN_67(4/11)<Reviewer>SizeDoc NumberRevDate: SheetofReviewerDesignerDepartmentProject
Page TitleCCBU D39 257Tuesday, August 29, 2023<project_name><Designer> GRANDTETON_SWB_20230829039 PEX_2_STN_67(4/11)<Reviewer>
C564 DIFF BUS_0.22UF
C602 DIFF BUS_0.22UFC577 DIFF BUS_0.22UFC552 DIFF BUS_0.22UF
C590 DIFF BUS_0.22UFC565 DIFF BUS_0.22UF
C603 DIFF BUS_0.22UFC578 DIFF BUS_0.22UFC553 DIFF BUS_0.22UF
C591 DIFF BUS_0.22UFC566 DIFF BUS_0.22UF
C604 DIFF BUS_0.22UF8/26PEX2HSS26-0A0P-01RXP127B7RXN127A7RXP126D6RXN126C6RXP125B5RXN125A5RXP124D4RXN124C4RXP123B3RXN123A3RXP122C2RXN122C1RXP121K2RXN121K1RXP120L4RXN120L3RXP119M2RXN119M1RXP118N4RXN118N3RXP117P2RXN117P1RXP116R4RXN116R3RXP115T2RXN115T1RXP114U4RXN114U3RXP113V2RXN113V1RXP112W4RXN112W3TXP127G7TXN127F7TXP126J6TXN126H6TXP125G5TXN125F5TXP124J4TXN124H4TXP123G3TXN123F3TXP122E2TXN122E1TXP121H2TXN121H1TXP120L7TXN120L6TXP119M9TXN119M8TXP118N7TXN118N6TXP117P9TXN117P8TXP116R7TXN116R6TXP115T9TXN115T8TXP114U7TXN114U6TXP113V9TXN113V8TXP112W7TXN112W6C579 DIFF BUS_0.22UFC554 DIFF BUS_0.22UF
C592 DIFF BUS_0.22UFC567 DIFF BUS_0.22UF
C605 DIFF BUS_0.22UFC580 DIFF BUS_0.22UFC555 DIFF BUS_0.22UF
C593 DIFF BUS_0.22UFC568 DIFF BUS_0.22UF
C606 DIFF BUS_0.22UFC581 DIFF BUS_0.22UFC556 DIFF BUS_0.22UF
C594 DIFF BUS_0.22UFC569 DIFF BUS_0.22UF
C607 DIFF BUS_0.22UFC582 DIFF BUS_0.22UFC557 DIFF BUS_0.22UF
C595 DIFF BUS_0.22UFC570 DIFF BUS_0.22UF
C608 DIFF BUS_0.22UFC583 DIFF BUS_0.22UFC558 DIFF BUS_0.22UF
C596 DIFF BUS_0.22UFC571 DIFF BUS_0.22UF
C609 DIFF BUS_0.22UFC584 DIFF BUS_0.22UFC559 DIFF BUS_0.22UF
C597 DIFF BUS_0.22UFC572 DIFF BUS_0.22UF
C610 DIFF BUS_0.22UFC585 DIFF BUS_0.22UF7/26PEX2GSS26-0A0P-01RXP111D8RXN111C8RXP110B9RXN110A9RXP109D10RXN109C10RXP108B11RXN108A11RXP107D12RXN107C12RXP106B13RXN106A13RXP105D14RXN105C14RXP104B15RXN104A15RXP103D16RXN103C16RXP102B17RXN102A17RXP101D18RXN101C18RXP100B19RXN100A19RXP99D20RXN99C20RXP98B21RXN98A21RXP97D22RXN97C22RXP96B23RXN96A23TXP111J8TXN111H8TXP110G9TXN110F9TXP109J10TXN109H10TXP108G11TXN108F11TXP107J12TXN107H12TXP106G13TXN106F13TXP105J14TXN105H14TXP104G15TXN104F15TXP103J16TXN103H16TXP102G17TXN102F17TXP101J18TXN101H18TXP100G19TXN100F19TXP99J20TXN99H20TXP98G21TXN98F21TXP97J22TXN97H22TXP96G23TXN96F23C560 DIFF BUS_0.22UF
C598 DIFF BUS_0.22UFC573 DIFF BUS_0.22UF
C611 DIFF BUS_0.22UFC586 DIFF BUS_0.22UFC561 DIFF BUS_0.22UF
C599 DIFF BUS_0.22UFC574 DIFF BUS_0.22UF
C612 DIFF BUS_0.22UFC587 DIFF BUS_0.22UFC562 DIFF BUS_0.22UF
C600 DIFF BUS_0.22UFC575 DIFF BUS_0.22UF
C613 DIFF BUS_0.22UFC588 DIFF BUS_0.22UFC563 DIFF BUS_0.22UF
C601 DIFF BUS_0.22UFC576 DIFF BUS_0.22UF
C614 DIFF BUS_0.22UF
C551 DIFF BUS_0.22UF
C589 DIFF BUS_0.22UFP5E_PEX2_STN7_TX_DP<112>P5E_PEX2_STN7_TX_C_DP<112>P5E_PEX2_STN7_TX_DN<112>P5E_PEX2_STN7_TX_C_DN<112>P5E_PEX2_STN7_TX_DP<113>P5E_PEX2_STN7_TX_DN<113>P5E_PEX2_STN7_TX_DP<115>P5E_PEX2_STN7_TX_DN<115>P5E_PEX2_STN7_TX_DP<114>P5E_PEX2_STN7_TX_DN<114>P5E_PEX2_STN7_TX_DP<119>P5E_PEX2_STN7_TX_DN<119>P5E_PEX2_STN7_TX_DP<118>P5E_PEX2_STN7_TX_DN<118>P5E_PEX2_STN7_TX_DP<117>P5E_PEX2_STN7_TX_DN<117>P5E_PEX2_STN7_TX_DP<116>P5E_PEX2_STN7_TX_DN<116>P5E_PEX2_STN7_TX_C_DP<113>P5E_PEX2_STN7_TX_C_DN<113>P5E_PEX2_STN7_TX_C_DP<115>P5E_PEX2_STN7_TX_C_DN<115>P5E_PEX2_STN7_TX_C_DP<114>P5E_PEX2_STN7_TX_C_DN<114>P5E_PEX2_STN7_TX_C_DP<119>P5E_PEX2_STN7_TX_C_DN<119>P5E_PEX2_STN7_TX_C_DP<118>P5E_PEX2_STN7_TX_C_DN<118>P5E_PEX2_STN7_TX_C_DP<117>P5E_PEX2_STN7_TX_C_DN<117P5E_PEX2_STN7_TX_C_DP<116>P5E_PEX2_STN7_TX_C_DN<116>P5E_PEX2_STN7_TX_DP<120>P5E_PEX2_STN7_TX_DN<120>P5E_PEX2_STN7_TX_DP<121>P5E_PEX2_STN7_TX_DN<121>P5E_PEX2_STN7_TX_DP<122>P5E_PEX2_STN7_TX_DN<122>P5E_PEX2_STN7_TX_DP<123>P5E_PEX2_STN7_TX_DN<123>P5E_PEX2_STN7_TX_DP<124>P5E_PEX2_STN7_TX_DN<124>P5E_PEX2_STN7_TX_DP<125>P5E_PEX2_STN7_TX_DN<125>P5E_PEX2_STN7_TX_DP<126>P5E_PEX2_STN7_TX_DN<126>P5E_PEX2_STN7_TX_DP<127>P5E_PEX2_STN7_TX_DN<127>P5E_PEX2_STN7_TX_C_DP<120>P5E_PEX2_STN7_TX_C_DN<120>P5E_PEX2_STN7_TX_C_DP<121>P5E_PEX2_STN7_TX_C_DN<121>P5E_PEX2_STN7_TX_C_DP<123>P5E_PEX2_STN7_TX_C_DN<123>P5E_PEX2_STN7_TX_C_DP<122>P5E_PEX2_STN7_TX_C_DN<122>P5E_PEX2_STN7_TX_C_DP<127>P5E_PEX2_STN7_TX_C_DN<127>P5E_PEX2_STN7_TX_C_DP<126>P5E_PEX2_STN7_TX_C_DN<126>P5E_PEX2_STN7_TX_C_DP<125>P5E_PEX2_STN7_TX_C_DN<125>P5E_PEX2_STN7_TX_C_DP<124>P5E_PEX2_STN7_TX_C_DN<124>P5E_PEX2_STN7_RX_DP<127>P5E_PEX2_STN7_RX_DN<127>P5E_PEX2_STN7_RX_DP<126>P5E_PEX2_STN7_RX_DN<126>P5E_PEX2_STN7_RX_DP<125>P5E_PEX2_STN7_RX_DN<125>P5E_PEX2_STN7_RX_DP<124>P5E_PEX2_STN7_RX_DN<124>P5E_PEX2_STN7_RX_DP<123>P5E_PEX2_STN7_RX_DN<123>P5E_PEX2_STN7_RX_DP<122>P5E_PEX2_STN7_RX_DN<122>P5E_PEX2_STN7_RX_DP<121>P5E_PEX2_STN7_RX_DN<121>P5E_PEX2_STN7_RX_DP<120>P5E_PEX2_STN7_RX_DN<120>P5E_PEX2_STN7_RX_DP<119>P5E_PEX2_STN7_RX_DN<119>P5E_PEX2_STN7_RX_DP<118>P5E_PEX2_STN7_RX_DN<118>P5E_PEX2_STN7_RX_DP<117>P5E_PEX2_STN7_RX_DN<117>P5E_PEX2_STN7_RX_DP<116>P5E_PEX2_STN7_RX_DN<116>P5E_PEX2_STN7_RX_DP<115>P5E_PEX2_STN7_RX_DN<115>P5E_PEX2_STN7_RX_DP<114>P5E_PEX2_STN7_RX_DN<114>P5E_PEX2_STN7_RX_DP<113>P5E_PEX2_STN7_RX_DN<113>P5E_PEX2_STN7_RX_DP<112>P5E_PEX2_STN7_RX_DN<112>
P5E_PEX2_STN6_RX_DP<111>P5E_PEX2_STN6_TX_DP<111>P5E_PEX2_STN6_TX_C_DP<111>P5E_PEX2_STN6_RX_DN<111>P5E_PEX2_STN6_TX_DN<111>P5E_PEX2_STN6_TX_C_DN<111>P5E_PEX2_STN6_RX_DP<110>P5E_PEX2_STN6_TX_DP<110>P5E_PEX2_STN6_TX_C_DP<110>P5E_PEX2_STN6_RX_DN<110>P5E_PEX2_STN6_TX_DN<110>P5E_PEX2_STN6_TX_C_DN<110>P5E_PEX2_STN6_RX_DP<109>P5E_PEX2_STN6_TX_DP<109>P5E_PEX2_STN6_TX_C_DP<109>P5E_PEX2_STN6_RX_DN<109>P5E_PEX2_STN6_TX_DN<109>P5E_PEX2_STN6_TX_C_DN<109>P5E_PEX2_STN6_RX_DP<108>P5E_PEX2_STN6_TX_DP<108>P5E_PEX2_STN6_TX_C_DP<108>P5E_PEX2_STN6_RX_DN<108>P5E_PEX2_STN6_TX_DN<108>P5E_PEX2_STN6_TX_C_DN<108>P5E_PEX2_STN6_RX_DP<107>P5E_PEX2_STN6_TX_DP<107>P5E_PEX2_STN6_TX_C_DP<107>P5E_PEX2_STN6_RX_DN<107>P5E_PEX2_STN6_TX_DN<107>P5E_PEX2_STN6_TX_C_DN<107>P5E_PEX2_STN6_RX_DP<106>P5E_PEX2_STN6_TX_DP<106>P5E_PEX2_STN6_TX_C_DP<106>P5E_PEX2_STN6_RX_DN<106>P5E_PEX2_STN6_TX_DN<106>P5E_PEX2_STN6_TX_C_DN<106>P5E_PEX2_STN6_RX_DP<105>P5E_PEX2_STN6_TX_DP<105>P5E_PEX2_STN6_TX_C_DP<105>P5E_PEX2_STN6_RX_DN<105>P5E_PEX2_STN6_TX_DN<105>P5E_PEX2_STN6_TX_C_DN<105>P5E_PEX2_STN6_RX_DP<104>P5E_PEX2_STN6_TX_DP<104>P5E_PEX2_STN6_TX_C_DP<104>P5E_PEX2_STN6_RX_DN<104>P5E_PEX2_STN6_TX_DN<104>P5E_PEX2_STN6_TX_C_DN<104>P5E_PEX2_STN6_RX_DP<103>P5E_PEX2_STN6_TX_DP<103>P5E_PEX2_STN6_TX_C_DP<103>P5E_PEX2_STN6_RX_DN<103>P5E_PEX2_STN6_TX_DN<103>P5E_PEX2_STN6_TX_C_DN<103>P5E_PEX2_STN6_RX_DP<102>P5E_PEX2_STN6_TX_DP<102>P5E_PEX2_STN6_TX_C_DP<102>P5E_PEX2_STN6_RX_DN<102>P5E_PEX2_STN6_TX_DN<102>P5E_PEX2_STN6_TX_C_DN<102>P5E_PEX2_STN6_RX_DP<101>P5E_PEX2_STN6_TX_DP<101>P5E_PEX2_STN6_TX_C_DP<101>P5E_PEX2_STN6_RX_DN<101>P5E_PEX2_STN6_TX_DN<101>P5E_PEX2_STN6_TX_C_DN<101>P5E_PEX2_STN6_RX_DP<100>P5E_PEX2_STN6_TX_DP<100>P5E_PEX2_STN6_TX_C_DP<100>P5E_PEX2_STN6_RX_DN<100>P5E_PEX2_STN6_TX_DN<100>P5E_PEX2_STN6_TX_C_DN<100>P5E_PEX2_STN6_RX_DP<99>P5E_PEX2_STN6_TX_DP<99>P5E_PEX2_STN6_TX_C_DP<99>P5E_PEX2_STN6_RX_DN<99>P5E_PEX2_STN6_TX_DN<99>P5E_PEX2_STN6_TX_C_DN<99>P5E_PEX2_STN6_RX_DP<98>P5E_PEX2_STN6_TX_DP<98>P5E_PEX2_STN6_TX_C_DP<98>P5E_PEX2_STN6_RX_DN<98>P5E_PEX2_STN6_TX_DN<98>P5E_PEX2_STN6_TX_C_DN<98>P5E_PEX2_STN6_RX_DP<97>P5E_PEX2_STN6_TX_DP<97>P5E_PEX2_STN6_TX_C_DP<97>P5E_PEX2_STN6_RX_DN<97>P5E_PEX2_STN6_TX_DN<97>P5E_PEX2_STN6_TX_C_DN<97>P5E_PEX2_STN6_RX_DP<96>P5E_PEX2_STN6_TX_DP<96>P5E_PEX2_STN6_TX_C_DP<96>P5E_PEX2_STN6_RX_DN<96>P5E_PEX2_STN6_TX_DN<96>P5E_PEX2_STN6_TX_C_DN<96>



5
5
4
4
3
3
2
2
1
1
D D
C C
B B
A A
PEX_2_STN_8(5/11)
CLK_100M_DB2000QL_PEX2_S1_R_DP [79]CLK_100M_DB2000QL_PEX2_S1_R_DN [79]CLK_100M_DB800ZL_PEX2_S0_R_DP [83]CLK_100M_DB800ZL_PEX2_S0_R_DN [83]CLK_100M_PEX2_REF_R_DP[82]CLK_100M_PEX2_REF_R_DN[82]RST_PEX2_PERST_R_N[118]RST_PEX2_S3_PERST_R_N [40]RST_PEX2_S1_PERST_R_N [40]RST_PEX2_S0_PERST_R_N [40]RST_PEX2_S0_PERST_R_N[40]RST_PEX2_S1_PERST_R_N[40]RST_PEX2_S3_PERST_R_N[40]CLK_100M_DB800ZL_PEX2_S3_R_DP [84]CLK_100M_DB800ZL_PEX2_S3_R_DN [84]P1V8_PEXP1V8_PEXSizeDoc NumberRevDate: SheetofReviewerDesignerDepartmentProject
Page TitleCCBU D40 257Tuesday, August 29, 2023<project_name><Designer> GRANDTETON_SWB_20230829040 PEX_2_STN_8(5/11)<Reviewer>SizeDoc NumberRevDate: SheetofReviewerDesignerDepartmentProject
Page TitleCCBU D40 257Tuesday, August 29, 2023<project_name><Designer> GRANDTETON_SWB_20230829040 PEX_2_STN_8(5/11)<Reviewer>SizeDoc NumberRevDate: SheetofReviewerDesignerDepartmentProject
Page TitleCCBU D40 257Tuesday, August 29, 2023<project_name><Designer> GRANDTETON_SWB_20230829040 PEX_2_STN_8(5/11)<Reviewer>R63954.7KR0402-02015%U427BSN74LVC3G34DCTR3584R6396 33 R0402-0201C41870.1UF10%16VC0402-0201U427ASN74LVC3G34DCTR1784U427CSN74LVC3G34DCTR6284R436210K1% R0402-0201<Part Number>NIR6394 33 R0402-0201
9/26PEX2ISS26-0A0P-01RXP143AM48RXN143AM49RXP142AL46RXN142AL47RXP141AK48RXN141AK49RXP140AJ46RXN140AJ47RXP139AH48RXN139AH49RXP138AG46RXN138AG47RXP137AF48RXN137AF49RXP136AE46RXN136AE47RXP135AD48RXN135AD49RXP134AC46RXN134AC47RXP133AB48RXN133AB49RXP132AA46RXN132AA47RXP131Y48RXN131Y49RXP130W46RXN130W47RXP129V48RXN129V49RXP128U46RXN128U47TXP143AM41TXN143AM42TXP142AL43TXN142AL44TXP141AK41TXN141AK42TXP140AJ43TXN140AJ44TXP139AH41TXN139AH42TXP138AG43TXN138AG44TXP137AF41TXN137AF42TXP136AE43TXN136AE44TXP135AD41TXN135AD42TXP134AC43TXN134AC44TXP133AB41TXN133AB42TXP132AA43TXN132AA44TXP131Y41TXN131Y42TXP130W43TXN130W44TXP129V41TXN129V42TXP128U43TXN128U44
R6397 33 R0402-0201
10/26PEX2JSS26-0A0P-01S7_PCE_PERST_NU38S6_PCE_PERST_NR38S5_PCE_PERST_NU39S4_PCE_PERST_NR39S3_PCE_PERST_NP38S2_PCE_PERST_NT39S1_PCE_PERST_NP39S0_PCE_PERST_NT38SYS_REF_CLK_PAA2SYS_REF_CLK_NAA1S7_PCE_REF_CLK_PAJ2S7_PCE_REF_CLK_NAJ1S6_PCE_REF_CLK_PAH5S6_PCE_REF_CLK_NAH4S5_PCE_REF_CLK_PAG2S5_PCE_REF_CLK_NAG1S4_PCE_REF_CLK_PAF5S4_PCE_REF_CLK_NAF4S3_PCE_REF_CLK_PAE2S3_PCE_REF_CLK_NAE1S2_PCE_REF_CLK_PAD5S2_PCE_REF_CLK_NAD4S1_PCE_REF_CLK_PAC2S1_PCE_REF_CLK_NAC1S0_PCE_REF_CLK_PAB5S0_PCE_REF_CLK_NAB4CLKREQ_INIT_NM13CLK_100M_DB2000QL_PEX2_S1_R_DPCLK_100M_DB2000QL_PEX2_S1_R_DNCLK_100M_DB800ZL_PEX2_S0_R_DPCLK_100M_DB800ZL_PEX2_S0_R_DNCLK_100M_PEX2_REF_R_DPCLK_100M_PEX2_REF_R_DNIRQ_PEX2_CLKREQ_INT_NRST_PEX2_PERST_R_NRST_PEX2_S3_PERST_NRST_PEX2_S3_PERST_R_NRST_PEX2_S1_PERST_NRST_PEX2_S1_PERST_R_NRST_PEX2_S0_PERST_NRST_PEX2_S0_PERST_R_NRST_PEX2_S0_PERST_R_NRST_PEX2_S1_PERST_R_NRST_PEX2_S3_PERST_R_NCLK_100M_DB800ZL_PEX2_S3_R_DPCLK_100M_DB800ZL_PEX2_S3_R_DN



5
5
4
4
3
3
2
2
1
1
D D
C C
B B
A A
Add Test Point
PEX_2_GPIO(6/11)
DVT_CHANGEPEX2_DBG_MODE4 [41]PEX2_DBG_MODE3 [41]PEX2_MODE_SEL12 [41]PEX2_DBG_MODE2 [41]PEX2_MODE_SEL11 [41]PEX2_DBG_MODE1 [41]PEX2_MODE_SEL10 [41]PEX2_DBG_MODE0 [41]PEX2_MODE_SEL9 [41]PEX2_DBG_SEL1 [41]PEX2_MODE_SEL8 [41]PEX2_DBG_SEL0 [41]PEX2_MODE_SEL7 [41]PEX2_MODE_SEL6 [41]PEX2_MODE_SEL5 [41]PEX2_MODE_SEL4 [41]PEX2_MODE_SEL3 [41]PEX2_MODE_SEL2 [41,121]PEX2_MODE_SEL1 [41,121]PEX2_MODE_SEL0 [41]PEX2_DBG_MODE4[41]PEX2_DBG_MODE3[41]PEX2_DBG_MODE2[41]PEX2_DBG_MODE1[41]PEX2_DBG_MODE0[41]PEX2_DBG_SEL1[41]PEX2_DBG_SEL0[41]PEX2_MODE_SEL12[41]PEX2_MODE_SEL11[41]PEX2_MODE_SEL10[41]PEX2_MODE_SEL9[41]PEX2_MODE_SEL8[41]PEX2_MODE_SEL7[41]PEX2_MODE_SEL6[41]PEX2_MODE_SEL5[41]PEX2_MODE_SEL4[41]PEX2_MODE_SEL3[41]PEX2_MODE_SEL2[41,121]PEX2_MODE_SEL1[41,121]PEX2_MODE_SEL0[41]PEX2_SYS_ERR_R_N [41]RST_PEX2_SYS_N [118]UART_PEX2_SDB_TX [67]UART_PEX2_SDB_BUF_RX [67]UART_PEX2_CLI_TX [68]UART_PEX2_CLI_BUF_RX [68]PEX2_SYS_ERR_R_N[41]PEX2_PCA9555_INT_R_N [74]PEX2_SYS_ERR_FPGA [118]
P1V8_PEXP1V8_PEXP1V8_PEXP1V8_PEXP3V3_AUXP1V8_PEX
P1V8_PEXP3V3_LEDP1V8_PEXSizeDoc NumberRevDate: SheetofReviewerDesignerDepartmentProject
Page TitleCCBU D41 257Tuesday, August 29, 2023<project_name><Designer> GRANDTETON_SWB_20230829041 PEX_2_GPIO(6/11)<Reviewer>SizeDoc NumberRevDate: SheetofReviewerDesignerDepartmentProject
Page TitleCCBU D41 257Tuesday, August 29, 2023<project_name><Designer> GRANDTETON_SWB_20230829041 PEX_2_GPIO(6/11)<Reviewer>SizeDoc NumberRevDate: SheetofReviewerDesignerDepartmentProject
Page TitleCCBU D41 257Tuesday, August 29, 2023<project_name><Designer> GRANDTETON_SWB_20230829041 PEX_2_GPIO(6/11)<Reviewer>R1395 4.75K R0402-02011%R13651KR0402-02011%NIR13291KR0402-02011%NI
R418110KR0402-02015%NI
11/26PEX2KSS26-0A0P-01DBG_MODE4AW34DBG_MODE3AW26DBG_MODE2AW30DBG_MODE1L13DBG_MODE0L12DBG_SEL1M19DBG_SEL0L18MODE_SEL12AW32MODE_SEL11AW31MODE_SEL10AV32MODE_SEL9AV28MODE_SEL8AW29MODE_SEL7AV26MODE_SEL6AV31MODE_SEL5AW25MODE_SEL4AW28MODE_SEL3AV27MODE_SEL2AV25MODE_SEL1AW38MODE_SEL0AW27AVG_TRST_LM18AVG_TCKM15AVG_TDIL17AVG_TDOL19AVG_TMSM20AVG_PAD_TRI_LL16AVG_TR_TCKL20AVG_ATPG_MODE_LL15SHPC_INT_NAV29SPARE7M27SPARE6L28SPARE5L25SPARE4M25SPARE3L32SPARE2L27SPARE1L30SPARE0M26DFT_IDDTM16ADCTEMP_VINP0Y39ADCTEMP_VINP1AA39SYS_ERROR_NAV30SYS_PWR_ON_RST_NM17SDB_TXAL39SDB_RXAK39UART_TXAJ38UART_RXAK38
R13481KR0402-02011%NIR138810KR0402-02015%R13721KR0402-02011%NIR138110K 1%R0402-0201<Part Number>R13391KR0402-02011%NIR13661KR0402-02011%
Q15BBSS138BKS<Part Number>D23G25S24
R13561KR0402-02011%R13301KR0402-02011%NI
R4182 1K R0402-02011%NI
R138910KR0402-02015%R13731KR0402-02011%NIR13401KR0402-02011%NIR13671KR0402-02011%NIR13571KR0402-02011%NIR13311KR0402-02011% R139010KR0402-02015%NIQ15ABSS138BKS<Part Number>S11G12D16R13741KR0402-02011%NIR13411KR0402-02011%NIR13581KR0402-02011%NIR13681KR0402-02011%R13321KR0402-02011%NIR13491KR0402-02011%R1391 0 R0402-02015%R13591KR0402-02011%R13751KR0402-02011%NIR13421KR0402-02011%NIR13331KR0402-02011%NIR13501KR0402-02011%R138210KR0402-02015%R13601KR0402-02011%R13761KR0402-02011%NIR13431KR0402-02011%NI
R1393 10K R0402-02015%R13511KR0402-02011%NIR13341KR0402-02011%NI R138310KR0402-02015%R396310KR0402-02015%R13611KR0402-02011%R13771KR0402-02011%R139649.9<Part Number>R0402-02011%1/16W
R13441KR0402-02011%NIR13351KR0402-02011%NIR13521KR0402-02011%R138410KR0402-02015%R13621KR0402-02011%R1394 4.75K R0402-02011%
R13451KR0402-02011%R13691KR0402-02011%NI12/26PEX2LSS26-0A0P-01GPIO31AV13GPIO30AV12GPIO29AW12GPIO28AW16GPIO27AV17GPIO26AV16GPIO25AW13GPIO24AW17GPIO23AV14GPIO21AW14GPIO20AW18GPIO19AV19GPIO18AV15GPIO17AW15GPIO16AW19GPIO15AV36GPIO14AU39GPIO13AW35GPIO12AJ39GPIO11AN39GPIO10AM38GPIO9AR39GPIO8AP39GPIO7AR38GPIO6AP38GPIO5AM39GPIO4AU38GPIO3AV39GPIO2AT39GPIO1AV34GPIO0AW39GPIO63M24GPIO62L23GPIO61M23GPIO60M22GPIO59L22GPIO58L24GPIO57AV23GPIO56AW22GPIO55AV22GPIO54AV21GPIO53M32GPIO52L31GPIO51M34GPIO50N39GPIO49L29GPIO48M33GPIO47AW21GPIO46AW23GPIO45L33GPIO44M31GPIO43M30GPIO42L35GPIO41AN38GPIO40AL38GPIO39AW37GPIO38AV37GPIO37AV38GPIO36AV35GPIO35AW36GPIO34AV33GPIO33AT38GPIO32AW33EXT_GPIO_LATCH_NL37GPIO22AV18R138510KR0402-02015%R13361KR0402-02011%NIR13531KR0402-02011%
D3LED_BLUEACR61554.7KR0402-02011%  
R13631KR0402-02011%
R5801 33 R0402-02011%R1392 10K R0402-02015%R13461KR0402-02011%NIR13541KR0402-02011%R13701KR0402-02011%NIR138610KR0402-02015%R13371KR0402-02011%R13641KR0402-02011%R138010K 1%R0402-0201R138710KR0402-02015%R13471KR0402-02011%R13551KR0402-02011%R13711KR0402-02011%NIR13974.7KR0402-02011%  
R13381KR0402-02011%PEX2_DBG_MODE4PEX2_DBG_MODE3PEX2_MODE_SEL12PEX2_DBG_MODE2PEX2_MODE_SEL11PEX2_DBG_MODE1PEX2_MODE_SEL10PEX2_DBG_MODE0PEX2_MODE_SEL9PEX2_DBG_SEL1PEX2_MODE_SEL8PEX2_DBG_SEL0PEX2_MODE_SEL7PEX2_MODE_SEL6PEX2_MODE_SEL5PEX2_MODE_SEL4PEX2_MODE_SEL3PEX2_MODE_SEL2PEX2_MODE_SEL1PEX2_MODE_SEL0PEX2_DBG_MODE4PEX2_DBG_MODE3PEX2_DBG_MODE2PEX2_DBG_MODE1PEX2_DBG_MODE0PEX2_SPARE7PEX2_DBG_SEL1PEX2_SPARE6PEX2_DBG_SEL0PEX2_SPARE5PEX2_SPARE4PEX2_MODE_SEL12PEX2_SPARE3PEX2_MODE_SEL11PEX2_SPARE2PEX2_MODE_SEL10PEX2_SPARE1PEX2_MODE_SEL9PEX2_SPARE0PEX2_MODE_SEL8PEX2_MODE_SEL7PEX2_DFT_IDDTPEX2_MODE_SEL6PEX2_MODE_SEL5PEX2_MODE_SEL4PEX2_MODE_SEL3PEX2_MODE_SEL2PEX2_MODE_SEL1PEX2_MODE_SEL0PEX2_SYS_ERR_NRST_PEX2_SYS_NTP_PEX2_TRST_LTP_PEX2_TCKTP_PEX2_TDIUART_PEX2_SDB_TXTP_PEX2_TDOUART_PEX2_SDB_BUF_RXTP_PEX2_TMSPU_PEX2_PAD_TRI_LUART_PEX2_CLI_TXPU_PEX2_TR_TCKUART_PEX2_CLI_BUF_RXPU_PEX2_ATPG_MODE_LPEX2_SYS_ERR_3V3_NLED_PEX2_SYS_ERR_NPEX2_SYS_ERR_N_GPEX2_ADCTEMP_VINP0PEX2_ADCTEMP_VINP1
PEX2_EXT_GPIO_LATCH_N



5
5
4
4
3
3
2
2
1
1
D D
C C
B B
A A
FLASH SOCKET
PEX VER. A0
PCA9555 3.3V Port
Pull UP 3V3
PEX 1.8V Port
To FPGA
PEX VER. B0
CO-LAYOUT
PEX_2_FLASH(7/11)
SEL_FLASH_PEX2_BUF_R[63,88]SPI_PEX2_CS_MUX_N[42]SPI_PEX2_CLK_MUX[42]SPI_PEX2_CLK_R [42]SPI_BIC1_CLK_LS23_R1 [63]SPI_PEX2_CS_R_N [42]SPI_BIC1_CS0_LS23_R1_N [63]SPI_PEX2_CS_MUX_N[42]SPI_PEX2_CLK_MUX[42]SPI_BIC1_MISO_LS23_R1 [63]SPI_BIC1_MOSI_LS23_R1 [63]SPI_PEX2_SDIO1_MUX[42]SPI_PEX2_SDIO0_MUX[42]SPI_PEX2_SDIO0_MUX[42]SPI_PEX2_SDIO1_MUX [42]SPI_PEX2_SDIO1_R [42]SPI_PEX2_SDIO0_R [42]SPI_PEX2_SDIO2_R[42]SPI_PEX2_SDIO3_R[42]
I2C_PEX2_HOST_R_SDA [42]I2C_PEX2_HOST_R_SCL [42]SMB_PEX2_SDA [95]SMB_PEX2_SCL [95]
SMB_PEX2_PCA9555_SCL[74]I2C_PEX2_HOST_R_SCL [42]SMB_PEX2_PCA9555_SDA[74]I2C_PEX2_HOST_R_SDA [42]PWRGD_P1V8_PEX_R[16,29,55,95,118,233]SMB_PEX2_FPGA_SCL[115]SMB_PEX2_FPGA_SDA[115]
SPI_PEX2_CS_R_N[42]SPI_PEX2_CLK_R[42]SPI_PEX2_SDIO3_R[42]SPI_PEX2_SDIO2_R[42]SPI_PEX2_SDIO1_R[42]SPI_PEX2_SDIO0_R[42]SPI_PEX2_RST_R_N[42]SPI_PEX2_RST_R_N [42]P3V3_AUX
P1V8_PEXP1V8_PEXP3V3_AUXP1V8_PEX
P1V8_PEXP1V8_PEXP1V8_PEX
SizeDoc NumberRevDate: SheetofReviewerDesignerDepartmentProject
Page TitleCCBU D42 257Tuesday, August 29, 2023<project_name><Designer> GRANDTETON_SWB_20230829042 PEX_2_FLASH(7/11)<Reviewer>SizeDoc NumberRevDate: SheetofReviewerDesignerDepartmentProject
Page TitleCCBU D42 257Tuesday, August 29, 2023<project_name><Designer> GRANDTETON_SWB_20230829042 PEX_2_FLASH(7/11)<Reviewer>SizeDoc NumberRevDate: SheetofReviewerDesignerDepartmentProject
Page TitleCCBU D42 257Tuesday, August 29, 2023<project_name><Designer> GRANDTETON_SWB_20230829042 PEX_2_FLASH(7/11)<Reviewer>
R3973 0 R0402-02015%
R61691KR0402-02011%NI<Part Number>R3988 0 R0402-02015%NIR34851K<Part Number>R0402-02011%U315PCA9617ADP<Part Number>EN5VCCA1VCCB8SCLA2SDAA3SDAB6SCLB7GND4
R6168 0 R0402-02015%R3473 0 R0402-02015%R3479 0 R0402-02015%R61704.75K1%R0402-0201<Part Number>R40172K1/16W1%R0402-0201R3480 0 R0402-02015%R6809 33 R0402-02011%R3481 0 R0402-02015%R3984 0 R0402-02015%
R3974 33 R0402-02011%R61591KR0402-02011%C24060.1UF10%16VC0402-0201JPEX2_FW1<Part Number>1R3474 0 R0402-02015%
R40182K1/16W1%<Part Number>R0402-0201
U67PI3CH480QEXS1E#15YA4YB7D113YC9YD12D014C110C011B16B05A13A02VCC16GND8 R34871K<Part Number>R0402-02011%NIR39784.7KR0402-02015%
R6719 33 R0402-02011%
R3982 33 R0402-02011%
R3975 0 R0402-02015%
R34881K<Part Number>R0402-02011%NI
R6810 33 R0402-02011%13/26PEX2MSS26-0A0P-01SPI0_CS_N1AJ8SPI0_CS_N0AK7SPI0_FLASH_CS_NAJ7SPI0_RST_NAG7SPI0_CLKAH7SPI0_SDIO3AH8SPI0_SDIO2AG8SPI0_SDIO1AF8SPI0_SDIO0AF7SPI1_CS_N1AB7SPI1_CS_N0AB8SPI1_RST_NAD7SPI1_CLKAE7SPI1_SDIO3AE8SPI1_SDIO2AC8SPI1_SDIO1AD8SPI1_SDIO0AC7SIO_BLINKL26I2C0_SDAM39I2C0_SCLM35I2C1_SDAM37I2C1_SCLL38I2C2_SDAL36I2C2_SCLM36I2C3_SDAM38I2C3_SCLL34I2C_S_SDAL39I2C_S_SCLN38SHPC_SDAM28SHPC_SCLM29C27820.1UF10%16VC0402-0201R39794.7KR0402-02015%
R6720 0 R0402-02015%R3475 0 R0402-02015%R3970 0 R0402-02015%NI
R3482 0 R0402-02015%R3985 33 R0402-02011%
14/26PEX2NSS26-0A0P-01MXSTEST_0_TST1AN36MXSTEST_0_TST0AP36MXSTEST_1_TST1AT36MXSTEST_1_TST0AR36MXSTEST_2_TST1AP14MXSTEST_2_TST0AN14MXSTEST_3_TST1U36MXSTEST_3_TST0P36MXSTEST_4_TST1T36MXSTEST_4_TST0R36MXSTEST_5_TST1T14MXSTEST_5_TST0U14MXSTEST_6_TST1AA35MXSTEST_6_TST0AB35CLKOBSAK5CLKOBS_NAK4R3470 0 R0402-02015%
C27580.1UF10%16VC0402-0201
R3976 0 R0402-02015%R3971 0 R0402-02015%
R3483 0 R0402-02015%C27590.1UF10%16VC0402-0201R3986 0 R0402-02015%U319W25Q256JWFIQNIHOLD#||RESET_IO3#1VCC2RESET#3NC14NC25NC36CS#7DO_IO18CLK16DI_IO015NC714NC613NC512NC411GND10WP_N_IO29 R3977 0 R0402-02015%R3471 0 R0402-02015%R394510K1% R0402-0201<Part Number>R3972 0 R0402-02015%NIC24050.1UF10%16VC0402-0201
R3983 0 R0402-02015%JPEX2SCONN16_ACASPI006P07<Part Number>VCC2HOLD_N1CS_N7WP_N9SI15SCK16VSS10SO8NC3PO24PO15PO06PO311PO412PO513PO614R34861K<Part Number>R0402-02011%R3987 0 R0402-02015%NI
R3478 4.7K R0402-02011%R3472 0 R0402-02015%
R3484 0 R0402-02015%SPI_PEX2_CS_MUX_NSPI_PEX2_SDIO1_MUXSPI_PEX2_SDIO1_RSPI_BIC1_MISO_LS23_R1SPI_PEX2_CS_R_NSPI_BIC1_CS0_LS23_R1_NSEL_FLASH_PEX2_BUF_RSPI_PEX2_SDIO0_MUXSPI_PEX2_CLK_MUXSPI_PEX2_SDIO0_RSPI_BIC1_MOSI_LS23_R1SPI_PEX2_CLK_RSPI_BIC1_CLK_LS23_R1SPI_MUX_PEX2_EN_NSPI_PEX2_SDIO1_MUX_RSPI_PEX2_SDIO1_MUXSPI_PEX2_SDIO3_RSPI_PEX2_SDIO3_R1SPI_PEX2_CS_MUX_NSPI_PEX2_CS_MUX_R_NSPI_PEX2_SDIO2_RSPI_PEX2_SDIO2_R1SPI_PEX2_SDIO0_MUXSPI_PEX2_SDIO0_MUX_RSPI_PEX2_CLK_MUXSPI_PEX2_CLK_MUX_RSPI_PEX2_CS_MUX_R_NSPI_PEX2_SDIO3_R1SPI_PEX2_SDIO2_R1
I2C0_PEX2_SDAI2C_PEX2_HOST_SDAI2C0_PEX2_SCLI2C_PEX2_HOST_SCLSMB_PEX2_SLAVE_SDASMB_PEX2_SLAVE_SCLI2C0_PEX2_SHPC_SDAI2C0_PEX2_SHPC_SCL
SMB_PEX2_HOST_LS_SCLSMB_PEX2_HOST_LS_SDAPWRGD_P1V8_PEX2_R
SPI_PEX2_CS_R_NSPI_PEX2_CS_NSPI_PEX2_CLK_RSPI_PEX2_CLKSPI_PEX2_SDIO3_RSPI_PEX2_SDIO3SPI_PEX2_SDIO2_RSPI_PEX2_SDIO2SPI_PEX2_SDIO1_RSPI_PEX2_SDIO1SPI_PEX2_SDIO0_RSPI_PEX2_SDIO0PU_PEX2_SIO_BLINKSPI_PEX2_CLK_MUX_RSPI_PEX2_CS_MUX_R_NSPI_PEX2_SDIO3_R1SPI_PEX2_SDIO2_R1SPI_PEX2_SDIO1_MUX_RSPI_PEX2_SDIO0_MUX_R
SPI_PEX2_RST_R_NSPI_PEX2_RST_N
SPI_PEX2_RST_R_NSPI_PEX2_RST_R_NSPI_PEX2_RST_R_N
SMB_PEX2_SLAVE1_SCLSMB_PEX2_SLAVE1_SDASMB_PEX2_R_SDASMB_PEX2_R_SCL



5
5
4
4
3
3
2
2
1
1
D D
C C
B B
A A
PEX0 P1V25_SERDES_VDDHTXDECOUPLING INFO.
Item QTY.
BGA BALLs 41
1000pF(0201) Caps
0.1uF(0201) Caps
1uF(0201) Caps
10uF(0603) Caps
11
25
5
2
PEX0 P1V25_SERDES_VDDHPLLDECOUPLING INFO.
Item QTY.
41BGA BALLs
1000pF(0201) Caps 11
0.1uF(0201) Caps 25
1uF(0201) Caps 5
10uF(0603) Caps 2
1
1
8
4
QTY.
13
PEX0 P1V8_SWDECOUPLING INFO.
10uF(0603) Caps
1uF(0201) Caps
0.1uF(0201) Caps
1000pF(0201) Caps
BGA BALLs
Item
1
1
8
4
QTY.
9
PEX0 P1V8_VDDADECOUPLING INFO.
10uF(0603) Caps
1uF(0201) Caps
0.1uF(0201) Caps
1000pF(0201) Caps
BGA BALLs
Item
Add Test Point
PEX_2_PWR_Cap_1(8/11)
VSENSE_P0V8_PEX2_SKT_VRTN[226]VSENSE_P0V8_PEX2_SKT_VSEN[226]
P1V25_PEX2P1V25_SERDES_VDDPLL_PEX2P1V8_VDDA_PEX2P0V8_PEX2P0V8_PEX2P1V25_PEX2P1V25_SERDES_VDDPLL_PEX2
P0V8_SERDES_VDDA_PEX2P0V8_SERDES_VDDA_PEX2P1V8_PEXP1V8_VDDA_PEX2P1V8_PEXPCEPLL7_VDDA18_PEX2PCEPLL6_VDDA18_PEX2PCEPLL5_VDDA18_PEX2PCEPLL4_VDDA18_PEX2PCEPLL3_VDDA18_PEX2PCEPLL2_VDDA18_PEX2PCEPLL1_VDDA18_PEX2PCEPLL0_VDDA18_PEX2SYSPLL_VDDA18_PEX2
SizeDoc NumberRevDate: SheetofReviewerDesignerDepartmentProject
Page TitleCCBU D43 257Tuesday, August 29, 2023<project_name><Designer> GRANDTETON_SWB_20230829043 PEX_2_PWR_Cap_1(8/11)<Reviewer>SizeDoc NumberRevDate: SheetofReviewerDesignerDepartmentProject
Page TitleCCBU D43 257Tuesday, August 29, 2023<project_name><Designer> GRANDTETON_SWB_20230829043 PEX_2_PWR_Cap_1(8/11)<Reviewer>SizeDoc NumberRevDate: SheetofReviewerDesignerDepartmentProject
Page TitleCCBU D43 257Tuesday, August 29, 2023<project_name><Designer> GRANDTETON_SWB_20230829043 PEX_2_PWR_Cap_1(8/11)<Reviewer>
C33180.1UFC020110%6.3VC32750.1UFC020110%6.3VC32700.1UFC020110%6.3V
C33461000PFC02015%16V
C32890.1UFC020110%6.3VC32910.1UFC020110%6.3VC32680.1UFC020110%6.3VC32900.1UFC020110%6.3V
C33540.1UFC020110%6.3V
C32651000PFC02015%16VC32790.1UFC020110%6.3VC33340.1UFC020110%6.3VC32760.1UFC020110%6.3VC32961UFC020120%4VC33170.1UFC020110%6.3VC33610.1UFC020110%6.3VC33570.1UFC020110%6.3VC33051000PFC02015%16V16/26PEX2PSS26-0A0P-01PCEPLL7_VDDA18AJ13PCEPLL6_VDDA18AH12PCEPLL5_VDDA18AG13PCEPLL4_VDDA18AF12PCEPLL3_VDDA18AE13PCEPLL2_VDDA18AD12PCEPLL1_VDDA18AB12PCEPLL0_VDDA18AA13SYSPLL_VDDA18AC13EDM_VDDW38VDDQ_EFUSEAM12VDD18_V35V35VDD18_W35W35VDD18_Y12Y12VDD18_Y35Y35VDD18_AE10AE10VDD18_AF10AF10VDD18_AH10AH10VDD18_AJ10AJ10VDD18_AK10AK10VDD18_AK12AK12VDD18_AK35AK35VDD18_AL35AL35VDD18_AM35AM35VDDA18_T35T35VDDA18_V14V14VDDA18_AA10AA10VDDA18_AA34AA34VDDA18_AA37AA37VDDA18_AB10AB10VDDA18_AC10AC10VDDA18_AM14AM14VDDA18_AP35AP35VDDA_SENSEAL15VSSA_SENSEAL14VDD_SENSEV39VSS_SENSEW39C32641000PFC02015%16VC33140.1UFC020110%6.3VC33451000PFC02015%16V
C32551UFC020120%4VC33031000PFC02015%16VC32740.1UFC020110%6.3VC32631000PFC02015%16VC32710.1UFC020110%6.3VC32780.1UFC020110%6.3VC333810UFC060320%6.3VC329310UFC060320%6.3VC32850.1UFC020110%6.3VC32820.1UFC020110%6.3VC33120.1UFC020110%6.3VC32971UFC020120%4VC32621000PFC02015%16VC33320.1UFC020110%6.3V17/26PEX2QSS26-0A0P-01VDDA_Y16Y16VDDA_Y17Y17VDDA_Y18Y18VDDA_Y19Y19VDDA_Y20Y20VDDA_Y21Y21VDDA_Y22Y22VDDA_Y23Y23VDDA_Y24Y24VDDA_Y25Y25VDDA_Y26Y26VDDA_Y27Y27VDDA_Y28Y28VDDA_Y29Y29VDDA_Y30Y30VDDA_Y31Y31VDDA_Y32Y32VDDA_Y33Y33VDDA_AB16AB16VDDA_AB17AB17VDDA_AB18AB18VDDA_AB19AB19VDDA_AB20AB20VDDA_AB21AB21VDDA_AB22AB22VDDA_AB23AB23VDDA_AB24AB24VDDA_AB25AB25VDDA_AB26AB26VDDA_AB27AB27VDDA_AB28AB28VDDA_AB29AB29VDDA_AB30AB30VDDA_AB31AB31VDDA_AB32AB32VDDA_AB33AB33VDDA_AD32AD32VDDA_AD33AD33VDDA_AD34AD34VDDA_AE33AE33VDDA_AE34AE34VDDA_AF32AF32VDDA_AF33AF33VDDA_AF34AF34VDDA_AH16AH16VDDA_AH17AH17VDDA_AH18AH18VDDA_AH19AH19VDDA_AH20AH20VDDA_AH21AH21VDDA_AH22AH22VDDA_AH23AH23VDDA_AH24AH24VDDA_AH25AH25VDDA_AH26AH26VDDA_AH27AH27VDDA_AH28AH28VDDA_AH29AH29VDDA_AH30AH30VDDA_AH31AH31VDDA_AH32AH32VDDA_AH33AH33VDDA_AK16AK16VDDA_AK17AK17VDDA_AK18AK18VDDA_AK19AK19VDDA_AK20AK20VDDA_AK21AK21VDDA_AK22AK22VDDA_AK23AK23VDDA_AK24AK24VDDA_AK25AK25VDDA_AK26AK26VDDA_AK27AK27VDDA_AK28AK28VDDA_AK29AK29VDDA_AK30AK30VDDA_AK31AK31VDDA_AK32AK32VDDA_AK33AK33C33290.1UFC020110%6.3VC32941UFC020120%4VC33470.1UFC020110%6.3V
C32611000PFC02015%16V
C33520.1UFC020110%6.3VC33391000PFC02015%16VC333610UFC060320%6.3VC33500.1UFC020110%6.3VC33200.1UFC020110%6.3VC33150.1UFC020110%6.3VC33240.1UFC020110%6.3VC32770.1UFC020110%6.3V
C33411000PFC02015%16VC33110.1UFC020110%6.3VC33560.1UFC020110%6.3VC33401000PFC02015%16VC33071000PFC02015%16VC33210.1UFC020110%6.3VC33330.1UFC020110%6.3VC32690.1UFC020110%6.3VC33300.1UFC020110%6.3VC33260.1UFC020110%6.3V
C32541UFC020120%4V
C33230.1UFC020110%6.3VC33530.1UFC020110%6.3VC32981UFC020120%4VC33021000PFC02015%16VC33620.1UFC020110%6.3VC33061000PFC02015%16VC32591000PFC02015%16VC32720.1UFC020110%6.3VC32581000PFC02015%16VC33011000PFC02015%16VC33580.1UFC020110%6.3VC33041000PFC02015%16VC32840.1UFC020110%6.3VC33081000PFC02015%16VC32601000PFC02015%16VC32951UFC020120%4VC33310.1UFC020110%6.3V
C32561UFC020120%4V
C33431000PFC02015%16VC329210UFC060320%6.3VC32730.1UFC020110%6.3VC32880.1UFC020110%6.3VC325310UFC060320%6.3V
C33480.1UFC020110%6.3VC33250.1UFC020110%6.3VC33270.1UFC020110%6.3VC33160.1UFC020110%6.3VC33421000PFC02015%16VC33100.1UFC020110%6.3VC32571000PFC02015%16V
C33351UFC020120%4V
C32661000PFC02015%16VC33001000PFC02015%16VC33490.1UFC020110%6.3V
C32810.1UFC020110%6.3VC32800.1UFC020110%6.3V15/26PEX2O
SS26-0A0P-01
VDD125_V16V16VDD125_V17V17VDD125_V18V18VDD125_V19V19VDD125_V20V20VDD125_V21V21VDD125_V22V22VDD125_V23V23VDD125_V24V24VDD125_V25V25VDD125_V26V26VDD125_V27V27VDD125_V28V28VDD125_V29V29VDD125_V30V30VDD125_V31V31VDD125_V32V32VDD125_V33V33VDD125_AC36AC36VDD125_AD36AD36VDD125_AE36AE36VDD125_AF36AF36VDD125_AG36AG36VDD125_AM16AM16VDD125_AM17AM17VDD125_AM18AM18VDD125_AM19AM19VDD125_AM20AM20VDD125_AM21AM21VDD125_AM22AM22VDD125_AM23AM23VDD125_AM24AM24VDD125_AM25AM25VDD125_AM26AM26VDD125_AM27AM27VDD125_AM28AM28VDD125_AM29AM29VDD125_AM30AM30VDD125_AM31AM31VDD125_AM32AM32VDD125_AM33AM33VDD_Y14Y14VDD_AA15AA15VDD_AB14AB14VDD_AC15AC15VDD_AC17AC17VDD_AC19AC19VDD_AC21AC21VDD_AC23AC23VDD_AC25AC25VDD_AC27AC27VDD_AC29AC29VDD_AC31AC31VDD_AC33AC33VDD_AD14AD14VDD_AD16AD16VDD_AD18AD18VDD_AD20AD20VDD_AD22AD22VDD_AD24AD24VDD_AD26AD26VDD_AD28AD28VDD_AD30AD30VDD_AE15AE15VDD_AE17AE17VDD_AE19AE19VDD_AE21AE21VDD_AE23AE23
VDDA125_T16T16VDDA125_T17T17VDDA125_T18T18VDDA125_T19T19VDDA125_T20T20VDDA125_T21T21VDDA125_T22T22VDDA125_T23T23VDDA125_T24T24VDDA125_T25T25VDDA125_T26T26VDDA125_T27T27VDDA125_T28T28VDDA125_T29T29VDDA125_T30T30VDDA125_T31T31VDDA125_T32T32VDDA125_T33T33VDDA125_AC38AC38VDDA125_AD38AD38VDDA125_AE38AE38VDDA125_AF38AF38VDDA125_AG38AG38VDDA125_AP16AP16VDDA125_AP17AP17VDDA125_AP18AP18VDDA125_AP19AP19VDDA125_AP20AP20VDDA125_AP21AP21VDDA125_AP22AP22VDDA125_AP23AP23VDDA125_AP24AP24VDDA125_AP25AP25VDDA125_AP26AP26VDDA125_AP28AP28VDDA125_AP29AP29VDDA125_AP30AP30VDDA125_AP31AP31VDDA125_AP32AP32VDDA125_AP33AP33VDD_AE25AE25VDD_AE27AE27VDD_AE29AE29VDD_AE31AE31VDD_AF14AF14VDD_AF16AF16VDD_AF18AF18VDD_AF20AF20VDD_AF22AF22VDD_AF24AF24VDD_AF26AF26VDD_AF28AF28VDD_AF30AF30VDD_AG15AG15VDD_AG17AG17VDD_AG19AG19VDD_AG21AG21VDD_AG23AG23VDD_AG25AG25VDD_AG27AG27VDD_AG29AG29VDD_AG31AG31VDD_AG33AG33VDD_AH14AH14VDD_AJ15AJ15VDD_AK14AK14VDDA125_AP27AP27
C33441000PFC02015%16VC33600.1UFC020110%6.3V
C32521000PFC02015%16VC33280.1UFC020110%6.3VC33510.1UFC020110%6.3VC33371UFC020120%4VC32830.1UFC020110%6.3VC32511UFC020120%4VC324910UFC060320%6.3VC33091000PFC02015%16VC33220.1UFC020110%6.3VC33590.1UFC020110%6.3V
C32870.1UFC020110%6.3VC32991000PFC02015%16VC32670.1UFC020110%6.3VC32501UFC020120%4VC32860.1UFC020110%6.3VC33190.1UFC020110%6.3VC33550.1UFC020110%6.3VC33130.1UFC020110%6.3VTP_PEX2_VDDQ_EFUSE



5
5
4
4
3
3
2
2
1
1
D D
C C
B B
A A
44
BGA BALLs
Item
Item
0.1uF(0201) Caps
3
PEX1 P0V8_SERDES_VDDADECOUPLING INFO.
4
33
30
4
17
1000pF(0201) Caps
QTY.
10uF(0603) Caps
QTY.
53
PEX1 P0V8DECOUPLING INFO.
6
10uF(0603) Caps
BGA BALLs
1uF(0201) Caps
1uF(0201) Caps
0.1uF(0201) Caps
80
1000pF(0201) Caps
PEX_2_PWR_Cap_2(9/11)
P0V8_PEX2P0V8_SERDES_VDDA_PEX2
SizeDoc NumberRevDate: SheetofReviewerDesignerDepartmentProject
Page TitleCCBU D44 257Tuesday, August 29, 2023<project_name><Designer> GRANDTETON_SWB_20230829044 PEX_2_PWR_Cap_2(9/11)<Reviewer>SizeDoc NumberRevDate: SheetofReviewerDesignerDepartmentProject
Page TitleCCBU D44 257Tuesday, August 29, 2023<project_name><Designer> GRANDTETON_SWB_20230829044 PEX_2_PWR_Cap_2(9/11)<Reviewer>SizeDoc NumberRevDate: SheetofReviewerDesignerDepartmentProject
Page TitleCCBU D44 257Tuesday, August 29, 2023<project_name><Designer> GRANDTETON_SWB_20230829044 PEX_2_PWR_Cap_2(9/11)<Reviewer>
C161210UFC060320%6.3VC16570.1UFC020110%6.3VC16520.1UFC020110%6.3VC17250.1UFC020110%6.3VC17011000PFC02015%16VC16851000PFC02015%16VC16450.1UFC020110%6.3VC17160.1UFC020110%6.3VC167010UFC060320%6.3VC17070.1UFC020110%6.3V
C16361000PFC02015%16V
C17460.1UFC020110%6.3V
C16281000PFC02015%16V
C17370.1UFC020110%6.3V
C16131UFC020120%4VC16580.1UFC020110%6.3VC17280.1UFC020110%6.3V
C16250.1UFC020110%6.3VC17260.1UFC020110%6.3VC17021000PFC02015%16VC16861000PFC02015%16V
18/26PEX2R
SS26-0A0P-01
VSS_A2A2VSS_A4A4VSS_A6A6VSS_A8A8VSS_A10A10VSS_A12A12VSS_A14A14VSS_A16A16VSS_A18A18VSS_A20A20VSS_A22A22VSS_A24A24VSS_A26A26VSS_A28A28VSS_A30A30VSS_A32A32VSS_A34A34VSS_A36A36VSS_A38A38VSS_A40A40VSS_A42A42VSS_A44A44VSS_A46A46VSS_A48A48VSS_B1B1VSS_B2B2VSS_B4B4VSS_B6B6VSS_B8B8VSS_B10B10VSS_B12B12VSS_B14B14VSS_B16B16VSS_B18B18VSS_B20B20VSS_B22B22VSS_B24B24VSS_B26B26VSS_B28B28VSS_B30B30VSS_B32B32VSS_B34B34VSS_B36B36VSS_B38B38VSS_B40B40VSS_B42B42VSS_B44B44VSS_B46B46VSS_B48B48VSS_B49B49VSS_C3C3VSS_C5C5VSS_C7C7VSS_C9C9VSS_C11C11VSS_C13C13VSS_C15C15VSS_C17C17VSS_C19C19VSS_C21C21VSS_C23C23VSS_C25C25VSS_C27C27VSS_C29C29VSS_C31C31VSS_C33C33VSS_C35C35VSS_C37C37VSS_C39C39VSS_C41C41VSS_C43C43VSS_C45C45VSS_C47C47VSS_D1D1VSS_D2D2VSS_D3D3VSS_D5D5VSS_D7D7VSS_D9D9VSS_D11D11
VSS_D13D13VSS_D15D15VSS_D17D17VSS_D19D19VSS_D21D21VSS_D23D23VSS_D25D25VSS_D27D27VSS_D29D29VSS_D31D31VSS_D33D33VSS_D35D35VSS_D37D37VSS_D39D39VSS_D41D41VSS_D43D43VSS_D45D45VSS_D47D47VSS_D48D48VSS_D49D49VSS_E3E3VSS_E4E4VSS_E6E6VSS_E7E7VSS_E8E8VSS_E9E9VSS_E10E10VSS_E11E11VSS_E12E12VSS_E13E13VSS_E14E14VSS_E15E15VSS_E16E16VSS_E17E17VSS_E18E18VSS_E19E19VSS_E20E20VSS_E21E21VSS_E22E22VSS_E23E23VSS_E24E24VSS_E25E25VSS_E26E26VSS_E27E27VSS_E28E28VSS_E29E29VSS_E30E30VSS_E31E31VSS_E32E32VSS_E33E33VSS_E34E34VSS_E35E35VSS_E36E36VSS_E37E37VSS_E38E38VSS_E40E40VSS_E41E41VSS_E42E42VSS_E43E43VSS_E44E44VSS_E45E45VSS_E46E46VSS_E47E47VSS_F1F1VSS_F2F2VSS_F4F4VSS_F6F6VSS_F8F8VSS_F10F10VSS_F12F12VSS_F14F14VSS_F16F16VSS_F18F18VSS_F20F20VSS_F22F22VSS_F24F24VSS_F26F26VSS_F28F28VSS_E39E39VSS_E5E519/26PEX2S
SS26-0A0P-01
VSS_F30F30VSS_F32F32VSS_F34F34VSS_F38F38VSS_F40F40VSS_F42F42VSS_F44F44VSS_F46F46VSS_F48F48VSS_F49F49VSS_G1G1VSS_G2G2VSS_G4G4VSS_G6G6VSS_G8G8VSS_G10G10VSS_G12G12VSS_G14G14VSS_G16G16VSS_G18G18VSS_G20G20VSS_G22G22VSS_G24G24VSS_G26G26VSS_G28G28VSS_G30G30VSS_G32G32VSS_G34G34VSS_G36G36VSS_G38G38VSS_G40G40VSS_G42G42VSS_G44G44VSS_G46G46VSS_G48G48VSS_G49G49VSS_H3H3VSS_H5H5VSS_H7H7VSS_H9H9VSS_H11H11VSS_H13H13VSS_H15H15VSS_H17H17VSS_H19H19VSS_H21H21VSS_H23H23VSS_H25H25VSS_H27H27VSS_H29H29VSS_H31H31VSS_H33H33VSS_H35H35VSS_H37H37VSS_H39H39VSS_H41H41VSS_H43H43VSS_H45H45VSS_H47H47VSS_J1J1VSS_J2J2VSS_J3J3VSS_J5J5VSS_J7J7VSS_J9J9VSS_J11J11VSS_J13J13VSS_J15J15VSS_J17J17VSS_J19J19VSS_J21J21VSS_J23J23VSS_J25J25VSS_J27J27VSS_J29J29VSS_J31J31VSS_J33J33VSS_J35J35VSS_J37J37
VSS_J39J39VSS_J41J41VSS_J43J43VSS_J45J45VSS_J47J47VSS_J48J48VSS_J49J49VSS_K3K3VSS_K4K4VSS_K5K5VSS_K6K6VSS_K7K7VSS_K8K8VSS_K9K9VSS_K10K10VSS_K11K11VSS_K12K12VSS_K13K13VSS_K14K14VSS_K15K15VSS_K16K16VSS_K17K17VSS_K18K18VSS_K19K19VSS_K20K20VSS_K21K21VSS_K22K22VSS_K23K23VSS_K24K24VSS_K25K25VSS_K26K26VSS_K27K27VSS_K28K28VSS_K29K29VSS_K30K30VSS_K31K31VSS_K32K32VSS_K33K33VSS_K34K34VSS_K35K35VSS_K36K36VSS_K37K37VSS_K38K38VSS_K39K39VSS_K40K40VSS_K41K41VSS_K42K42VSS_K43K43VSS_K44K44VSS_K45K45VSS_K46K46VSS_K47K47VSS_L1L1VSS_L2L2VSS_L5L5VSS_L8L8VSS_L9L9VSS_L10L10VSS_L11L11VSS_L14L14VSS_L21L21VSS_L40L40VSS_L41L41VSS_L42L42VSS_L45L45VSS_L48L48VSS_L49L49VSS_M3M3VSS_M4M4VSS_M5M5VSS_M6M6VSS_M7M7VSS_M10M10VSS_M11M11VSS_M12M12VSS_M14M14VSS_M21M21VSS_M40M40VSS_M43M43VSS_M44M44
VSS_F36F36C16460.1UFC020110%6.3VC17170.1UFC020110%6.3VC16771000PFC02015%16VC16711UFC020120%4VC16200.1UFC020110%6.3VC17080.1UFC020110%6.3V
C16371000PFC02015%16V
C17470.1UFC020110%6.3V
C16291000PFC02015%16V
C17380.1UFC020110%6.3V
C16141UFC020120%4VC16590.1UFC020110%6.3VC17290.1UFC020110%6.3VC17031000PFC02015%16VC16530.1UFC020110%6.3VC17270.1UFC020110%6.3VC16871000PFC02015%16VC17180.1UFC020110%6.3VC16941000PFC02015%16VC16470.1UFC020110%6.3VC16781000PFC02015%16VC16210.1UFC020110%6.3VC17090.1UFC020110%6.3V
C16381000PFC02015%16VC16721UFC020120%4VC17480.1UFC020110%6.3V
C16301000PFC02015%16V
C17390.1UFC020110%6.3V
C16151UFC020120%4VC16600.1UFC020110%6.3VC17300.1UFC020110%6.3V
C16540.1UFC020110%6.3VC17041000PFC02015%16VC16881000PFC02015%16VC16480.1UFC020110%6.3VC17190.1UFC020110%6.3VC16951000PFC02015%16VC16791000PFC02015%16VC16731UFC020120%4VC16400.1UFC020110%6.3VC17100.1UFC020110%6.3V
C16391000PFC02015%16V
C17490.1UFC020110%6.3V
C16311000PFC02015%16V
C17400.1UFC020110%6.3V
C16161UFC020120%4VC16610.1UFC020110%6.3VC17310.1UFC020110%6.3VC17051000PFC02015%16VC16891000PFC02015%16VC16230.1UFC020110%6.3VC17200.1UFC020110%6.3VC16961000PFC02015%16VC16801000PFC02015%16VC16410.1UFC020110%6.3VC17110.1UFC020110%6.3V
C16191000PFC02015%16VC16741UFC020120%4VC17500.1UFC020110%6.3V
C16321000PFC02015%16V
C17410.1UFC020110%6.3V
C16620.1UFC020110%6.3VC17320.1UFC020110%6.3VC17061000PFC02015%16VC16901000PFC02015%16VC16971000PFC02015%16VC16490.1UFC020110%6.3VC17210.1UFC020110%6.3VC16811000PFC02015%16VC16420.1UFC020110%6.3VC17120.1UFC020110%6.3VC16751UFC020120%4VC16331000PFC02015%16V
C17420.1UFC020110%6.3V
C16630.1UFC020110%6.3VC17330.1UFC020110%6.3VC16911000PFC02015%16VC16500.1UFC020110%6.3VC17220.1UFC020110%6.3VC16981000PFC02015%16VC16821000PFC02015%16VC16761UFC020120%4VC16220.1UFC020110%6.3VC17130.1UFC020110%6.3VC166710UFC060320%6.3VC16341000PFC02015%16V
C17430.1UFC020110%6.3V
C16261000PFC02015%16VC16640.1UFC020110%6.3VC17340.1UFC020110%6.3V
C161010UFC060320%6.3VC16550.1UFC020110%6.3VC16921000PFC02015%16VC16510.1UFC020110%6.3VC17230.1UFC020110%6.3VC16991000PFC02015%16VC16831000PFC02015%16VC16430.1UFC020110%6.3VC17140.1UFC020110%6.3VC166810UFC060320%6.3VC16181000PFC02015%16V
C17440.1UFC020110%6.3V
C16271000PFC02015%16VC16650.1UFC020110%6.3VC17350.1UFC020110%6.3V
C161110UFC060320%6.3VC16560.1UFC020110%6.3VC16931000PFC02015%16VC17001000PFC02015%16VC16240.1UFC020110%6.3VC17240.1UFC020110%6.3VC16841000PFC02015%16VC17150.1UFC020110%6.3V
C16440.1UFC020110%6.3VC16351000PFC02015%16VC166910UFC060320%6.3VC17450.1UFC020110%6.3V
C16171000PFC02015%16VC16660.1UFC020110%6.3VC17360.1UFC020110%6.3V



5
5
4
4
3
3
2
2
1
1
D D
C C
B B
A A
PEX_2_PWR_Cap_3(10/11)
Imax: 0.04A
Imax: 0.04A Imax: 0.04A Imax: 0.04A
Imax: 0.04A Imax: 0.04A Imax: 0.04A
Imax: 0.04A
Imax: 0.2A Imax: 0.1A
PCEPLL0_VDDA18_PEX2P1V8_PLL0_PEX2P1V8_PLL0_PEX2PCEPLL1_VDDA18_PEX2P1V8_PLL0_PEX2PCEPLL2_VDDA18_PEX2P1V8_PLL0_PEX2PCEPLL3_VDDA18_PEX2P1V8_PLL0_PEX2PCEPLL4_VDDA18_PEX2P1V8_PLL0_PEX2PCEPLL5_VDDA18_PEX2P1V8_PLL0_PEX2PCEPLL6_VDDA18_PEX2P1V8_PLL0_PEX2PCEPLL7_VDDA18_PEX2P1V8_PLL0_PEX2SYSPLL_VDDA18_PEX2P1V8_PLL0_PEX2P1V8_VDDA_PEX2
PCEPLL0_VDDA18_PEX2_RPCEPLL1_VDDA18_PEX2_RPCEPLL2_VDDA18_PEX2_RPCEPLL3_VDDA18_PEX2_RPCEPLL4_VDDA18_PEX2_RPCEPLL5_VDDA18_PEX2_RPCEPLL6_VDDA18_PEX2_RPCEPLL7_VDDA18_PEX2_RSYSPLL_VDDA18_PEX2_RP1V8_VDDA_PEX2_RSizeDoc NumberRevDate: SheetofReviewerDesignerDepartmentProject
Page TitleCCBU D45 257Tuesday, August 29, 2023<project_name><Designer> GRANDTETON_SWB_20230829045 PEX_2_PWR_Cap_3(10/11)<Reviewer>SizeDoc NumberRevDate: SheetofReviewerDesignerDepartmentProject
Page TitleCCBU D45 257Tuesday, August 29, 2023<project_name><Designer> GRANDTETON_SWB_20230829045 PEX_2_PWR_Cap_3(10/11)<Reviewer>SizeDoc NumberRevDate: SheetofReviewerDesignerDepartmentProject
Page TitleCCBU D45 257Tuesday, August 29, 2023<project_name><Designer> GRANDTETON_SWB_20230829045 PEX_2_PWR_Cap_3(10/11)<Reviewer>R45870.51C339847UFC342147UF
C33881UFC020120%4VC337210UFC060320%6.3VL124HCB2012KF-601T20<Part Number>21
C34170.1UFC020110%6.3VC34050.1UFC020110%6.3VC33920.1UFC020110%6.3V
C342247UFR45840.51R45850.51C337847UFL122HCB2012KF-601T20<Part Number>21C337510UFC060320%6.3V
C341122UFC0603_H4020%6.3V
C338522UFC0603_H4020%6.3VC338710UFC060320%6.3VC33701UFC020120%4VC340310UFC060320%6.3VC34021UFC020120%4VC33770.1UFC020110%6.3V
R45860.51C339747UFC33890.1UFC020110%6.3VR45820.51R45800.51C33861UFC020120%4VC339922UFC0603_H4020%6.3VC339010UFC060320%6.3VC34071UFC020120%4VC338122UFC0603_H4020%6.3VC339647UFR45780.51C338047UFC33950.1UFC020110%6.3VR45790.51L126HCB2012KF-601T20<Part Number>21 C33911UFC020120%4VC34001UFC020120%4VL129HCB2012KF-601T20<Part Number>21
C337947UFL125HCB2012KF-601T20<Part Number>21
C341510UFC060320%6.3VC34161UFC020120%4V
C336910UFC060320%6.3VC340947UFC340122UFC0603_H4020%6.3VR45830.51L127HCB2012KF-601T20<Part Number>21C339310UFC060320%6.3VL120HCB2012KF-601T20<Part Number>21 C33740.1UFC020110%6.3VC336322UFC0603_H4020%6.3VR45810.51L121HCB2012KF-601T20<Part Number>21
C340610UFC060320%6.3VL128HCB2012KF-601T20<Part Number>21C341322UFC0603_H4020%6.3V
C33761UFC020120%4VC33731UFC020120%4V
C34121UFC020120%4V
C33641UFC020120%4VC33841UFC020120%4VC33661UFC020120%4VC338322UFC0603_H4020%6.3V
C341810UFC060320%6.3VC34191UFC020120%4V
C33710.1UFC020110%6.3VC33941UFC020120%4VC34141UFC020120%4V
C336722UFC0603_H4020%6.3VC33821UFC020120%4VC336522UFC0603_H4020%6.3VC33681UFC020120%4VL123HCB2012KF-601T20<Part Number>21
C34200.1UFC020110%6.3VC341047UFC34041UFC020120%4VC34080.1UFC020110%6.3V



5
5
4
4
3
3
2
2
1
1
D D
C C
B B
A A
PEX_2_GND(11/11) SizeDoc NumberRevDate: SheetofReviewerDesignerDepartmentProject
Page TitleCCBU D46 257Tuesday, August 29, 2023<project_name><Designer> GRANDTETON_SWB_20230829046 PEX_2_GND(11/11)<Reviewer>SizeDoc NumberRevDate: SheetofReviewerDesignerDepartmentProject
Page TitleCCBU D46 257Tuesday, August 29, 2023<project_name><Designer> GRANDTETON_SWB_20230829046 PEX_2_GND(11/11)<Reviewer>SizeDoc NumberRevDate: SheetofReviewerDesignerDepartmentProject
Page TitleCCBU D46 257Tuesday, August 29, 2023<project_name><Designer> GRANDTETON_SWB_20230829046 PEX_2_GND(11/11)<Reviewer>
26/26PEX2ZSS26-0A0P-01VSS_BF7BF7VSS_BF9BF9VSS_BF11BF11VSS_BF13BF13VSS_BF15BF15VSS_BF17BF17VSS_BF19BF19VSS_BF21BF21VSS_BF23BF23VSS_BF25BF25VSS_BF27BF27VSS_BF29BF29VSS_BF31BF31VSS_BF33BF33VSS_BF35BF35VSS_BF37BF37VSS_BF39BF39VSS_BF41BF41VSS_BF43BF43VSS_BF45BF45VSS_BF47BF47VSS_BF48BF48VSS_BF49BF49VSS_BG3BG3VSS_BG5BG5VSS_BG7BG7VSS_BG9BG9VSS_BG11BG11VSS_BG13BG13VSS_BG15BG15VSS_BG17BG17VSS_BG19BG19VSS_BG21BG21VSS_BG23BG23VSS_BG25BG25VSS_BG27BG27VSS_BG29BG29VSS_BG31BG31VSS_BG33BG33VSS_BG35BG35VSS_BG37BG37VSS_BG39BG39VSS_BG41BG41VSS_BG43BG43VSS_BG45BG45VSS_BG47BG47VSS_BH1BH1VSS_BH2BH2VSS_BH4BH4VSS_BH6BH6VSS_BH8BH8VSS_BH10BH10VSS_BH12BH12VSS_BH14BH14VSS_BH16BH16VSS_BH18BH18VSS_BH20BH20VSS_BH22BH22VSS_BH24BH24VSS_BH26BH26VSS_BH28BH28VSS_BH30BH30VSS_BH32BH32VSS_BH34BH34VSS_BH36BH36VSS_BH38BH38VSS_BH40BH40VSS_BH42BH42VSS_BH44BH44VSS_BH46BH46VSS_BH48BH48VSS_BH49BH49VSS_BJ2BJ2VSS_BJ4BJ4VSS_BJ6BJ6VSS_BJ8BJ8VSS_BJ10BJ10VSS_BJ12BJ12VSS_BJ14BJ14VSS_BJ16BJ16VSS_BJ18BJ18VSS_BJ20BJ20VSS_BJ22BJ22VSS_BJ24BJ24VSS_BJ26BJ26VSS_BJ28BJ28VSS_BJ30BJ30VSS_BJ32BJ32VSS_BJ34BJ34VSS_BJ36BJ36VSS_BJ38BJ38VSS_BJ40BJ40VSS_BJ42BJ42VSS_BJ44BJ44VSS_BJ46BJ46VSS_BJ48BJ48PLL_VSSA_AA12AA12PLL_VSSA_AB13AB13PLL_VSSA_AC12AC12PLL_VSSA_AD13AD13PLL_VSSA_AE12AE12PLL_VSSA_AF13AF13PLL_VSSA_AG12AG12PLL_VSSA_AH13AH13PLL_VSSA_AJ12AJ1225/26PEX2Y
SS26-0A0P-01
VSS_AY39AY39VSS_AY40AY40VSS_AY41AY41VSS_AY42AY42VSS_AY43AY43VSS_AY44AY44VSS_AY45AY45VSS_AY46AY46VSS_AY47AY47VSS_BA1BA1VSS_BA2BA2VSS_BA3BA3VSS_BA5BA5VSS_BA7BA7VSS_BA9BA9VSS_BA11BA11VSS_BA13BA13VSS_BA15BA15VSS_BA17BA17VSS_BA19BA19VSS_BA21BA21VSS_BA23BA23VSS_BA25BA25VSS_BA27BA27VSS_BA29BA29VSS_BA31BA31VSS_BA33BA33VSS_BA35BA35VSS_BA37BA37VSS_BA39BA39VSS_BA41BA41VSS_BA43BA43VSS_BA45BA45VSS_BA47BA47VSS_BA48BA48VSS_BA49BA49VSS_BB3BB3VSS_BB5BB5VSS_BB7BB7VSS_BB9BB9VSS_BB11BB11VSS_BB13BB13VSS_BB15BB15VSS_BB17BB17VSS_BB19BB19VSS_BB21BB21VSS_BB23BB23VSS_BB25BB25VSS_BB27BB27VSS_BB29BB29VSS_BB31BB31VSS_BB33BB33VSS_BB35BB35VSS_BB37BB37VSS_BB39BB39VSS_BB41BB41VSS_BB43BB43VSS_BB45BB45VSS_BB47BB47VSS_BC1BC1VSS_BC2BC2VSS_BC4BC4VSS_BC6BC6VSS_BC8BC8VSS_BC10BC10VSS_BC12BC12VSS_BC14BC14VSS_BC16BC16VSS_BC18BC18VSS_BC20BC20VSS_BC22BC22VSS_BC24BC24VSS_BC26BC26VSS_BC28BC28VSS_BC30BC30VSS_BC32BC32VSS_BC34BC34VSS_BC36BC36VSS_BC38BC38VSS_BC40BC40
VSS_BC42BC42VSS_BC44BC44VSS_BC46BC46VSS_BC48BC48VSS_BC49BC49VSS_BD1BD1VSS_BD2BD2VSS_BD4BD4VSS_BD6BD6VSS_BD8BD8VSS_BD10BD10VSS_BD12BD12VSS_BD14BD14VSS_BD16BD16VSS_BD18BD18VSS_BD20BD20VSS_BD22BD22VSS_BD24BD24VSS_BD26BD26VSS_BD28BD28VSS_BD30BD30VSS_BD32BD32VSS_BD34BD34VSS_BD36BD36VSS_BD38BD38VSS_BD40BD40VSS_BD42BD42VSS_BD44BD44VSS_BD46BD46VSS_BD48BD48VSS_BD49BD49VSS_BE3BE3VSS_BE4BE4VSS_BE5BE5VSS_BE6BE6VSS_BE7BE7VSS_BE8BE8VSS_BE9BE9VSS_BE10BE10VSS_BE11BE11VSS_BE12BE12VSS_BE13BE13VSS_BE14BE14VSS_BE15BE15VSS_BE16BE16VSS_BE17BE17VSS_BE18BE18VSS_BE19BE19VSS_BE20BE20VSS_BE21BE21VSS_BE22BE22VSS_BE23BE23VSS_BE24BE24VSS_BE25BE25VSS_BE26BE26VSS_BE27BE27VSS_BE28BE28VSS_BE29BE29VSS_BE30BE30VSS_BE31BE31VSS_BE32BE32VSS_BE33BE33VSS_BE34BE34VSS_BE35BE35VSS_BE36BE36VSS_BE37BE37VSS_BE38BE38VSS_BE39BE39VSS_BE40BE40VSS_BE41BE41VSS_BE42BE42VSS_BE43BE43VSS_BE44BE44VSS_BE45BE45VSS_BE46BE46VSS_BE47BE47VSS_BF1BF1VSS_BF2BF2VSS_BF3BF3VSS_BF5BF5
20/26PEX2T
SS26-0A0P-01
VSS_M45M45VSS_M46M46VSS_M47M47VSS_N1N1VSS_N2N2VSS_N5N5VSS_N8N8VSS_N9N9VSS_N10N10VSS_N11N11VSS_N12N12VSS_N13N13VSS_N14N14VSS_N15N15VSS_N16N16VSS_N17N17VSS_N18N18VSS_N19N19VSS_N20N20VSS_N21N21VSS_N22N22VSS_N23N23VSS_N24N24VSS_N25N25VSS_N26N26VSS_N27N27VSS_N28N28VSS_N29N29VSS_N30N30VSS_N31N31VSS_N32N32VSS_N33N33VSS_N34N34VSS_N35N35VSS_N36N36VSS_N37N37VSS_N40N40VSS_N41N41VSS_N42N42VSS_N45N45VSS_N48N48VSS_N49N49VSS_P3P3VSS_P4P4VSS_P5P5VSS_P6P6VSS_P7P7VSS_P10P10VSS_P11P11VSS_P12P12VSS_P13P13VSS_P14P14VSS_P15P15VSS_P16P16VSS_P17P17VSS_P18P18VSS_P19P19VSS_P20P20VSS_P21P21VSS_P22P22VSS_P23P23VSS_P24P24VSS_P25P25VSS_P26P26VSS_P27P27VSS_P28P28VSS_P29P29VSS_P30P30VSS_P31P31VSS_P32P32VSS_P33P33VSS_P34P34VSS_P35P35VSS_P37P37VSS_P40P40VSS_P43P43VSS_P44P44VSS_P45P45VSS_P46P46VSS_P47P47
VSS_R1R1VSS_R2R2VSS_R5R5VSS_R8R8VSS_R9R9VSS_R10R10VSS_R11R11VSS_R12R12VSS_R13R13VSS_R14R14VSS_R15R15VSS_R16R16VSS_R17R17VSS_R18R18VSS_R19R19VSS_R20R20VSS_R21R21VSS_R22R22VSS_R23R23VSS_R24R24VSS_R25R25VSS_R26R26VSS_R27R27VSS_R28R28VSS_R29R29VSS_R30R30VSS_R31R31VSS_R32R32VSS_R33R33VSS_R34R34VSS_R35R35VSS_R37R37VSS_R40R40VSS_R41R41VSS_R42R42VSS_R45R45VSS_R48R48VSS_R49R49VSS_T3T3VSS_T4T4VSS_T5T5VSS_T6T6VSS_T7T7VSS_T10T10VSS_T11T11VSS_T12T12VSS_T13T13VSS_T15T15VSS_T34T34VSS_T37T37VSS_T40T40VSS_T43T43VSS_T44T44VSS_T45T45VSS_T46T46VSS_T47T47VSS_U1U1VSS_U2U2VSS_U5U5VSS_U8U8VSS_U9U9VSS_U10U10VSS_U11U11VSS_U12U12VSS_U13U13VSS_U15U15VSS_U16U16VSS_U17U17VSS_U18U18VSS_U19U19VSS_U20U20VSS_U21U21VSS_U22U22VSS_U23U23VSS_U24U24VSS_U25U25VSS_U26U26VSS_U27U27VSS_U28U28VSS_U29U29
21/26PEX2U
SS26-0A0P-01
VSS_U30U30VSS_U31U31VSS_U32U32VSS_U33U33VSS_U34U34VSS_U35U35VSS_U37U37VSS_U40U40VSS_U41U41VSS_U42U42VSS_U45U45VSS_U48U48VSS_U49U49VSS_V3V3VSS_V4V4VSS_V5V5VSS_V6V6VSS_V7V7VSS_V10V10VSS_V11V11VSS_V12V12VSS_V13V13VSS_V15V15VSS_V34V34VSS_V36V36VSS_V37V37VSS_V38V38VSS_V40V40VSS_V43V43VSS_V44V44VSS_V45V45VSS_V46V46VSS_V47V47VSS_W1W1VSS_W2W2VSS_W5W5VSS_W8W8VSS_W9W9VSS_W10W10VSS_W11W11VSS_W12W12VSS_W13W13VSS_W14W14VSS_W15W15VSS_W16W16VSS_W17W17VSS_W18W18VSS_W19W19VSS_W20W20VSS_W21W21VSS_W22W22VSS_W23W23VSS_W24W24VSS_W25W25VSS_W26W26VSS_W27W27VSS_W28W28VSS_W29W29VSS_W30W30VSS_W31W31VSS_W32W32VSS_W33W33VSS_W34W34VSS_W36W36VSS_W37W37VSS_W40W40VSS_W41W41VSS_W42W42VSS_W45W45VSS_W48W48VSS_W49W49VSS_Y1Y1VSS_Y2Y2VSS_Y3Y3VSS_Y4Y4VSS_Y5Y5VSS_Y6Y6VSS_Y7Y7VSS_Y8Y8VSS_Y9Y9
VSS_Y10Y10VSS_Y11Y11VSS_Y13Y13VSS_Y15Y15VSS_Y34Y34VSS_Y36Y36VSS_Y37Y37VSS_Y38Y38VSS_Y40Y40VSS_Y44Y44VSS_Y45Y45VSS_Y46Y46VSS_Y47Y47VSS_AA3AA3VSS_AA4AA4VSS_AA5AA5VSS_AA6AA6VSS_AA7AA7VSS_AA8AA8VSS_AA9AA9VSS_AA11AA11VSS_AA14AA14VSS_AA16AA16VSS_AA17AA17VSS_AA18AA18VSS_AA19AA19VSS_AA20AA20VSS_AA21AA21VSS_AA22AA22VSS_AA23AA23VSS_AA24AA24VSS_AA25AA25VSS_AA26AA26VSS_AA27AA27VSS_AA28AA28VSS_AA29AA29VSS_AA30AA30VSS_AA31AA31VSS_AA32AA32VSS_AA33AA33VSS_AA36AA36VSS_AA38AA38VSS_AA40AA40VSS_AA41AA41VSS_AA42AA42VSS_AA45AA45VSS_AA48AA48VSS_AA49AA49VSS_AB1AB1VSS_AB2AB2VSS_AB3AB3VSS_AB6AB6VSS_AB9AB9VSS_AB11AB11VSS_AB15AB15VSS_AB34AB34VSS_AB36AB36VSS_AB37AB37VSS_AB38AB38VSS_AB39AB39VSS_AB40AB40VSS_AB43AB43VSS_AB44AB44VSS_AB45AB45VSS_AB46AB46VSS_AB47AB47VSS_AC3AC3VSS_AC4AC4VSS_AC5AC5VSS_AC6AC6VSS_AC9AC9VSS_AC11AC11VSS_AC14AC14VSS_AC16AC16VSS_AC18AC18VSS_AC20AC20VSS_AC22AC22VSS_AC24AC24VSS_AC26AC26
VSS_Y43Y4324/26PEX2X
SS26-0A0P-01
VSS_AR26AR26VSS_AR27AR27VSS_AR28AR28VSS_AR29AR29VSS_AR30AR30VSS_AR31AR31VSS_AR32AR32VSS_AR33AR33VSS_AR34AR34VSS_AR35AR35VSS_AR37AR37VSS_AR40AR40VSS_AR41AR41VSS_AR42AR42VSS_AR45AR45VSS_AR48AR48VSS_AR49AR49VSS_AT3AT3VSS_AT4AT4VSS_AT5AT5VSS_AT6AT6VSS_AT7AT7VSS_AT10AT10VSS_AT11AT11VSS_AT12AT12VSS_AT13AT13VSS_AT14AT14VSS_AT15AT15VSS_AT16AT16VSS_AT17AT17VSS_AT18AT18VSS_AT19AT19VSS_AT20AT20VSS_AT21AT21VSS_AT22AT22VSS_AT23AT23VSS_AT24AT24VSS_AT25AT25VSS_AT26AT26VSS_AT27AT27VSS_AT28AT28VSS_AT29AT29VSS_AT30AT30VSS_AT31AT31VSS_AT32AT32VSS_AT33AT33VSS_AT34AT34VSS_AT35AT35VSS_AT37AT37VSS_AT40AT40VSS_AT43AT43VSS_AT44AT44VSS_AT45AT45VSS_AT46AT46VSS_AT47AT47VSS_AU1AU1VSS_AU2AU2VSS_AU5AU5VSS_AU8AU8VSS_AU9AU9VSS_AU10AU10VSS_AU11AU11VSS_AU12AU12VSS_AU13AU13VSS_AU14AU14VSS_AU15AU15VSS_AU16AU16VSS_AU17AU17VSS_AU18AU18VSS_AU19AU19VSS_AU20AU20VSS_AU21AU21VSS_AU22AU22VSS_AU23AU23VSS_AU24AU24VSS_AU25AU25VSS_AU26AU26VSS_AU27AU27VSS_AU28AU28VSS_AU29AU29
VSS_AU30AU30VSS_AU31AU31VSS_AU32AU32VSS_AU33AU33VSS_AU34AU34VSS_AU35AU35VSS_AU36AU36VSS_AU37AU37VSS_AU40AU40VSS_AU41AU41VSS_AU42AU42VSS_AU45AU45VSS_AU48AU48VSS_AU49AU49VSS_AV3AV3VSS_AV4AV4VSS_AV5AV5VSS_AV6AV6VSS_AV7AV7VSS_AV10AV10VSS_AV11AV11VSS_AV20AV20VSS_AV24AV24VSS_AV40AV40VSS_AV43AV43VSS_AV44AV44VSS_AV45AV45VSS_AV46AV46VSS_AV47AV47VSS_AW1AW1VSS_AW2AW2VSS_AW5AW5VSS_AW8AW8VSS_AW9AW9VSS_AW10AW10VSS_AW11AW11VSS_AW20AW20VSS_AW24AW24VSS_AW40AW40VSS_AW41AW41VSS_AW42AW42VSS_AW45AW45VSS_AW48AW48VSS_AW49AW49VSS_AY3AY3VSS_AY4AY4VSS_AY5AY5VSS_AY6AY6VSS_AY7AY7VSS_AY8AY8VSS_AY9AY9VSS_AY10AY10VSS_AY11AY11VSS_AY12AY12VSS_AY13AY13VSS_AY14AY14VSS_AY15AY15VSS_AY16AY16VSS_AY17AY17VSS_AY18AY18VSS_AY19AY19VSS_AY20AY20VSS_AY21AY21VSS_AY22AY22VSS_AY23AY23VSS_AY24AY24VSS_AY25AY25VSS_AY26AY26VSS_AY27AY27VSS_AY28AY28VSS_AY29AY29VSS_AY30AY30VSS_AY31AY31VSS_AY32AY32VSS_AY33AY33VSS_AY34AY34VSS_AY35AY35VSS_AY36AY36VSS_AY37AY37VSS_AY38AY38
23/26PEX2W
SS26-0A0P-01
VSS_AJ36AJ36VSS_AJ37AJ37VSS_AJ40AJ40VSS_AJ41AJ41VSS_AJ42AJ42VSS_AJ45AJ45VSS_AJ48AJ48VSS_AJ49AJ49VSS_AK1AK1VSS_AK2AK2VSS_AK3AK3VSS_AK6AK6VSS_AK8AK8VSS_AK9AK9VSS_AK11AK11VSS_AK13AK13VSS_AK15AK15VSS_AK34AK34VSS_AK36AK36VSS_AK37AK37VSS_AK40AK40VSS_AK43AK43VSS_AK44AK44VSS_AK45AK45VSS_AK46AK46VSS_AK47AK47VSS_AL1AL1VSS_AL2AL2VSS_AL3AL3VSS_AL4AL4VSS_AL5AL5VSS_AL6AL6VSS_AL7AL7VSS_AL8AL8VSS_AL9AL9VSS_AL10AL10VSS_AL11AL11VSS_AL12AL12VSS_AL13AL13VSS_AL16AL16VSS_AL17AL17VSS_AL18AL18VSS_AL19AL19VSS_AL20AL20VSS_AL21AL21VSS_AL22AL22VSS_AL23AL23VSS_AL24AL24VSS_AL25AL25VSS_AL26AL26VSS_AL27AL27VSS_AL28AL28VSS_AL29AL29VSS_AL30AL30VSS_AL31AL31VSS_AL32AL32VSS_AL33AL33VSS_AL34AL34VSS_AL36AL36VSS_AL37AL37VSS_AL40AL40VSS_AL41AL41VSS_AL42AL42VSS_AL45AL45VSS_AL48AL48VSS_AL49AL49VSS_AM3AM3VSS_AM4AM4VSS_AM5AM5VSS_AM6AM6VSS_AM7AM7VSS_AM10AM10VSS_AM11AM11VSS_AM13AM13VSS_AM15AM15VSS_AM34AM34VSS_AM36AM36VSS_AM37AM37VSS_AM40AM40VSS_AM43AM43
VSS_AM44AM44VSS_AM45AM45VSS_AM46AM46VSS_AM47AM47VSS_AN1AN1VSS_AN2AN2VSS_AN5AN5VSS_AN8AN8VSS_AN9AN9VSS_AN10AN10VSS_AN11AN11VSS_AN12AN12VSS_AN13AN13VSS_AN15AN15VSS_AN16AN16VSS_AN17AN17VSS_AN18AN18VSS_AN19AN19VSS_AN20AN20VSS_AN21AN21VSS_AN22AN22VSS_AN23AN23VSS_AN24AN24VSS_AN25AN25VSS_AN26AN26VSS_AN27AN27VSS_AN28AN28VSS_AN29AN29VSS_AN30AN30VSS_AN31AN31VSS_AN32AN32VSS_AN33AN33VSS_AN34AN34VSS_AN35AN35VSS_AN37AN37VSS_AN40AN40VSS_AN41AN41VSS_AN42AN42VSS_AN45AN45VSS_AN48AN48VSS_AN49AN49VSS_AP3AP3VSS_AP4AP4VSS_AP5AP5VSS_AP6AP6VSS_AP7AP7VSS_AP10AP10VSS_AP11AP11VSS_AP12AP12VSS_AP13AP13VSS_AP15AP15VSS_AP34AP34VSS_AP37AP37VSS_AP40AP40VSS_AP43AP43VSS_AP44AP44VSS_AP45AP45VSS_AP46AP46VSS_AP47AP47VSS_AR1AR1VSS_AR2AR2VSS_AR5AR5VSS_AR8AR8VSS_AR9AR9VSS_AR10AR10VSS_AR11AR11VSS_AR12AR12VSS_AR13AR13VSS_AR14AR14VSS_AR15AR15VSS_AR16AR16VSS_AR17AR17VSS_AR18AR18VSS_AR19AR19VSS_AR20AR20VSS_AR21AR21VSS_AR22AR22VSS_AR23AR23VSS_AR24AR24VSS_AR25AR25
22/26PEX2V
SS26-0A0P-01
VSS_AC28AC28VSS_AC30AC30VSS_AC32AC32VSS_AC34AC34VSS_AC35AC35VSS_AC37AC37VSS_AC39AC39VSS_AC40AC40VSS_AC41AC41VSS_AC42AC42VSS_AC45AC45VSS_AC48AC48VSS_AC49AC49VSS_AD1AD1VSS_AD2AD2VSS_AD3AD3VSS_AD6AD6VSS_AD9AD9VSS_AD10AD10VSS_AD11AD11VSS_AD15AD15VSS_AD17AD17VSS_AD19AD19VSS_AD21AD21VSS_AD23AD23VSS_AD25AD25VSS_AD27AD27VSS_AD29AD29VSS_AD31AD31VSS_AD35AD35VSS_AD37AD37VSS_AD39AD39VSS_AD40AD40VSS_AD43AD43VSS_AD44AD44VSS_AD45AD45VSS_AD46AD46VSS_AD47AD47VSS_AE3AE3VSS_AE4AE4VSS_AE5AE5VSS_AE6AE6VSS_AE9AE9VSS_AE11AE11VSS_AE14AE14VSS_AE16AE16VSS_AE18AE18VSS_AE20AE20VSS_AE22AE22VSS_AE24AE24VSS_AE26AE26VSS_AE28AE28VSS_AE30AE30VSS_AE32AE32VSS_AE35AE35VSS_AE37AE37VSS_AE39AE39VSS_AE40AE40VSS_AE41AE41VSS_AE42AE42VSS_AE45AE45VSS_AE48AE48VSS_AE49AE49VSS_AF1AF1VSS_AF2AF2VSS_AF3AF3VSS_AF6AF6VSS_AF9AF9VSS_AF11AF11VSS_AF15AF15VSS_AF17AF17VSS_AF19AF19VSS_AF21AF21VSS_AF23AF23VSS_AF25AF25VSS_AF27AF27VSS_AF29AF29VSS_AF31AF31VSS_AF35AF35VSS_AF37AF37
VSS_AF39AF39VSS_AF40AF40VSS_AF43AF43VSS_AF44AF44VSS_AF45AF45VSS_AF46AF46VSS_AF47AF47VSS_AG3AG3VSS_AG4AG4VSS_AG5AG5VSS_AG6AG6VSS_AG9AG9VSS_AG10AG10VSS_AG11AG11VSS_AG14AG14VSS_AG16AG16VSS_AG18AG18VSS_AG20AG20VSS_AG22AG22VSS_AG24AG24VSS_AG26AG26VSS_AG28AG28VSS_AG30AG30VSS_AG32AG32VSS_AG34AG34VSS_AG35AG35VSS_AG37AG37VSS_AG39AG39VSS_AG40AG40VSS_AG41AG41VSS_AG42AG42VSS_AG45AG45VSS_AG48AG48VSS_AG49AG49VSS_AH1AH1VSS_AH2AH2VSS_AH3AH3VSS_AH6AH6VSS_AH9AH9VSS_AH11AH11VSS_AH15AH15VSS_AH34AH34VSS_AH35AH35VSS_AH36AH36VSS_AH37AH37VSS_AH38AH38VSS_AH39AH39VSS_AH40AH40VSS_AH43AH43VSS_AH44AH44VSS_AH45AH45VSS_AH46AH46VSS_AH47AH47VSS_AJ3AJ3VSS_AJ4AJ4VSS_AJ5AJ5VSS_AJ6AJ6VSS_AJ9AJ9VSS_AJ11AJ11VSS_AJ14AJ14VSS_AJ16AJ16VSS_AJ17AJ17VSS_AJ18AJ18VSS_AJ19AJ19VSS_AJ20AJ20VSS_AJ21AJ21VSS_AJ22AJ22VSS_AJ23AJ23VSS_AJ24AJ24VSS_AJ25AJ25VSS_AJ26AJ26VSS_AJ27AJ27VSS_AJ28AJ28VSS_AJ29AJ29VSS_AJ30AJ30VSS_AJ31AJ31VSS_AJ32AJ32VSS_AJ33AJ33VSS_AJ34AJ34VSS_AJ35AJ35



5
5
4
4
3
3
2
2
1
1
D D
C C
B B
A A
PEX_2_PWR_FILTER
Co-Layout
DCR : 0.0021 ohm
Co-Layout
CAD NOTE:BUCK CAP NEAR FILTER
CAD NOTE:BUCK CAP NEAR FILTER
CAD NOTE:NEAR PACKAGE EDGE
CAD NOTE:NEAR PACKAGE EDGE
P0V8_SERDES_VDDA_PEX2P0V8_PEX2P0V8_PEX2P1V25_SERDES_VDDPLL_PEX2P1V25_PEX2P1V25_PEX2SizeDoc NumberRevDate: SheetofReviewerDesignerDepartmentProject
Page TitleCCBU D47 257Tuesday, August 29, 2023<project_name><Designer> GRANDTETON_SWB_20230829047 PEX_2_PWR_FILTER<Reviewer>SizeDoc NumberRevDate: SheetofReviewerDesignerDepartmentProject
Page TitleCCBU D47 257Tuesday, August 29, 2023<project_name><Designer> GRANDTETON_SWB_20230829047 PEX_2_PWR_FILTER<Reviewer>SizeDoc NumberRevDate: SheetofReviewerDesignerDepartmentProject
Page TitleCCBU D47 257Tuesday, August 29, 2023<project_name><Designer> GRANDTETON_SWB_20230829047 PEX_2_PWR_FILTER<Reviewer>
0.01R5792NI2B1B2A1A
R65290.51R65220.51R65160.51
C43501UFC020120%4V
R65080.51
C43371UFC020120%4VL116BLM31SN500SN1L21R65170.51R65300.51R65230.51
R65090.51
C43511UFC020120%4VC432447UFL117BLM31SN500SN1L21R65310.51R65240.51R65180.51C431047UFR65100.51L63BLM31SN500SN1L21C432547UFC431647UFR65320.51R65250.51C431147UFC430247UFL114BLM31SN500SN1L21L64BLM31SN500SN1L21C433847UFC432647UFC431747UFR65260.51R65330.51
C431247UFC430347UFL115BLM31SN500SN1L21C435247UFC433947UFC432747UFC433047UFC431847UFR65340.51
C431347UFC430447UF
0.01R6136NI2B1B2A1AC432822UFC0603_H4020%6.3VC435347UFC434047UFC433147UFC431947UFC434447UF
C431422UFC0603_H4020%6.3VC430547UFL61BLM31SN500SN1L21
C435447UFC434147UFC434547UFC433247UFC43201UFC020120%4V
0.01R6137NI2B1B2A1A
0.01R5793NI2B1B2A1AC432922UFC0603_H4020%6.3VC43061UFC020120%4VL62BLM31SN500SN1L21 C431522UFC0603_H4020%6.3V
C435547UFC4342100UFC0805_H61_SEL20%4VC433347UFC434647UF
C43211UFC020120%4V0.01R5794NI2B1B2A1AC4356100UFC0805_H61_SEL20%4V0.01R6134NI2B1B2A1A
C43071UFC020120%4V
C434747UFC43341UFC020120%4VC4343100UF20%4VR65130.51C43221UFC020120%4VC43481UFC020120%4V0.01R6135NI2B1B2A1A
R65050.51
C4357100UF20%4VC43351UFC020120%4V
C43081UFC020120%4VR65140.51R65060.510.01R5791NI2B1B2A1A
C43491UFC020120%4V
C43231UFC020120%4VR65150.51R65210.51C43091UFC020120%4VC43361UFC020120%4V
R65070.51



5
5
4
4
3
3
2
2
1
1
D D
C C
B B
A A
BLANK SizeDoc NumberRevDate: SheetofReviewerDesignerDepartmentProject
Page TitleCCBU D48 257Tuesday, August 29, 2023<project_name><Designer> GRANDTETON_SWB_20230829048 BLANK<Reviewer>SizeDoc NumberRevDate: SheetofReviewerDesignerDepartmentProject
Page TitleCCBU D48 257Tuesday, August 29, 2023<project_name><Designer> GRANDTETON_SWB_20230829048 BLANK<Reviewer>SizeDoc NumberRevDate: SheetofReviewerDesignerDepartmentProject
Page TitleCCBU D48 257Tuesday, August 29, 2023<project_name><Designer> GRANDTETON_SWB_20230829048 BLANK<Reviewer>



5
5
4
4
3
3
2
2
1
1
D D
C C
B B
A A
PEX_3_STN_01(1/11)
P5E_PEX3_STN0_TX_C_DP<15> [189]P5E_PEX3_STN0_TX_C_DN<15> [189]P5E_PEX3_STN0_TX_C_DN<14> [189]P5E_PEX3_STN0_TX_C_DP<14> [189]P5E_PEX3_STN0_TX_C_DP<13> [189]P5E_PEX3_STN0_TX_C_DN<13> [189]P5E_PEX3_STN0_TX_C_DN<12> [189]P5E_PEX3_STN0_TX_C_DP<12> [189]P5E_PEX3_STN0_TX_C_DP<11> [189]P5E_PEX3_STN0_TX_C_DN<11> [189]P5E_PEX3_STN0_TX_C_DP<10> [189]P5E_PEX3_STN0_TX_C_DN<10> [189]P5E_PEX3_STN0_TX_C_DP<9> [189]P5E_PEX3_STN0_TX_C_DN<9> [189]P5E_PEX3_STN0_TX_C_DP<8> [189]P5E_PEX3_STN0_TX_C_DN<8> [189]P5E_PEX3_STN0_TX_C_DP<7> [189]P5E_PEX3_STN0_TX_C_DN<7> [189]P5E_PEX3_STN0_TX_C_DP<6> [189]P5E_PEX3_STN0_TX_C_DN<6> [189]P5E_PEX3_STN0_TX_C_DP<5> [189]P5E_PEX3_STN0_TX_C_DN<5> [189]P5E_PEX3_STN0_TX_C_DP<4> [189]P5E_PEX3_STN0_TX_C_DN<4> [189]P5E_PEX3_STN0_TX_C_DP<3> [189]P5E_PEX3_STN0_TX_C_DN<3> [189]P5E_PEX3_STN0_TX_C_DP<2> [189]P5E_PEX3_STN0_TX_C_DN<2> [189]P5E_PEX3_STN0_TX_C_DP<1> [189]P5E_PEX3_STN0_TX_C_DN<1> [189]P5E_PEX3_STN0_TX_C_DP<0> [189]P5E_PEX3_STN0_TX_C_DN<0> [189]P5E_PEX3_STN1_TX_C_DP<16> [186]P5E_PEX3_STN1_TX_C_DN<16> [186]P5E_PEX3_STN1_TX_C_DN<17> [186]P5E_PEX3_STN1_TX_C_DP<17> [186]P5E_PEX3_STN1_TX_C_DN<19> [186]P5E_PEX3_STN1_TX_C_DP<19> [186]P5E_PEX3_STN1_TX_C_DP<18> [186]P5E_PEX3_STN1_TX_C_DN<18> [186]P5E_PEX3_STN1_TX_C_DN<23> [186]P5E_PEX3_STN1_TX_C_DP<23> [186]P5E_PEX3_STN1_TX_C_DP<22> [186]P5E_PEX3_STN1_TX_C_DN<22> [186]P5E_PEX3_STN1_TX_C_DN<21> [186]P5E_PEX3_STN1_TX_C_DP<21> [186]P5E_PEX3_STN1_TX_C_DP<20> [186]P5E_PEX3_STN1_TX_C_DN<20> [186]P5E_PEX3_STN1_TX_C_DP<24> [186]P5E_PEX3_STN1_TX_C_DN<24> [186]P5E_PEX3_STN1_TX_C_DN<25> [186]P5E_PEX3_STN1_TX_C_DP<25> [186]P5E_PEX3_STN1_TX_C_DN<27> [186]P5E_PEX3_STN1_TX_C_DP<27> [186]P5E_PEX3_STN1_TX_C_DP<26> [186]P5E_PEX3_STN1_TX_C_DN<26> [186]P5E_PEX3_STN1_TX_C_DN<31> [186]P5E_PEX3_STN1_TX_C_DP<31> [186]P5E_PEX3_STN1_TX_C_DP<30> [186]P5E_PEX3_STN1_TX_C_DN<30> [186]P5E_PEX3_STN1_TX_C_DN<29> [186]P5E_PEX3_STN1_TX_C_DP<29> [186]P5E_PEX3_STN1_TX_C_DP<28> [186]P5E_PEX3_STN1_TX_C_DN<28> [186]
P5E_PEX3_STN0_RX_DP<15>[189]P5E_PEX3_STN0_RX_DN<15>[189]P5E_PEX3_STN0_RX_DP<14>[189]P5E_PEX3_STN0_RX_DN<14>[189]P5E_PEX3_STN0_RX_DP<13>[189]P5E_PEX3_STN0_RX_DN<13>[189]P5E_PEX3_STN0_RX_DP<12>[189]P5E_PEX3_STN0_RX_DN<12>[189]P5E_PEX3_STN0_RX_DP<11>[189]P5E_PEX3_STN0_RX_DN<11>[189]P5E_PEX3_STN0_RX_DP<10>[189]P5E_PEX3_STN0_RX_DN<10>[189]P5E_PEX3_STN0_RX_DP<9>[189]P5E_PEX3_STN0_RX_DN<9>[189]P5E_PEX3_STN0_RX_DP<8>[189]P5E_PEX3_STN0_RX_DN<8>[189]P5E_PEX3_STN0_RX_DP<7>[189]P5E_PEX3_STN0_RX_DN<7>[189]P5E_PEX3_STN0_RX_DP<6>[189]P5E_PEX3_STN0_RX_DN<6>[189]P5E_PEX3_STN0_RX_DP<5>[189]P5E_PEX3_STN0_RX_DN<5>[189]P5E_PEX3_STN0_RX_DP<4>[189]P5E_PEX3_STN0_RX_DN<4>[189]P5E_PEX3_STN0_RX_DP<3>[189]P5E_PEX3_STN0_RX_DN<3>[189]P5E_PEX3_STN0_RX_DP<2>[189]P5E_PEX3_STN0_RX_DN<2>[189]P5E_PEX3_STN0_RX_DP<1>[189]P5E_PEX3_STN0_RX_DN<1>[189]P5E_PEX3_STN0_RX_DP<0>[189]P5E_PEX3_STN0_RX_DN<0>[189]P5E_PEX3_STN1_RX_DP<31>[186]P5E_PEX3_STN1_RX_DN<31>[186]P5E_PEX3_STN1_RX_DP<30>[186]P5E_PEX3_STN1_RX_DN<30>[186]P5E_PEX3_STN1_RX_DP<29>[186]P5E_PEX3_STN1_RX_DN<29>[186]P5E_PEX3_STN1_RX_DP<28>[186]P5E_PEX3_STN1_RX_DN<28>[186]P5E_PEX3_STN1_RX_DP<27>[186]P5E_PEX3_STN1_RX_DN<27>[186]P5E_PEX3_STN1_RX_DP<26>[186]P5E_PEX3_STN1_RX_DN<26>[186]P5E_PEX3_STN1_RX_DP<25>[186]P5E_PEX3_STN1_RX_DN<25>[186]P5E_PEX3_STN1_RX_DP<24>[186]P5E_PEX3_STN1_RX_DN<24>[186]P5E_PEX3_STN1_RX_DP<23>[186]P5E_PEX3_STN1_RX_DN<23>[186]P5E_PEX3_STN1_RX_DP<22>[186]P5E_PEX3_STN1_RX_DN<22>[186]P5E_PEX3_STN1_RX_DP<21>[186]P5E_PEX3_STN1_RX_DN<21>[186]P5E_PEX3_STN1_RX_DP<20>[186]P5E_PEX3_STN1_RX_DN<20>[186]P5E_PEX3_STN1_RX_DP<19>[186]P5E_PEX3_STN1_RX_DN<19>[186]P5E_PEX3_STN1_RX_DP<18>[186]P5E_PEX3_STN1_RX_DN<18>[186]P5E_PEX3_STN1_RX_DP<17>[186]P5E_PEX3_STN1_RX_DN<17>[186]P5E_PEX3_STN1_RX_DP<16>[186]P5E_PEX3_STN1_RX_DN<16>[186]SizeDoc NumberRevDate: SheetofReviewerDesignerDepartmentProject
Page TitleCCBU D49 257Tuesday, August 29, 2023<project_name><Designer> GRANDTETON_SWB_20230829049 PEX_3_STN_01(1/11)<Reviewer>SizeDoc NumberRevDate: SheetofReviewerDesignerDepartmentProject
Page TitleCCBU D49 257Tuesday, August 29, 2023<project_name><Designer> GRANDTETON_SWB_20230829049 PEX_3_STN_01(1/11)<Reviewer>SizeDoc NumberRevDate: SheetofReviewerDesignerDepartmentProject
Page TitleCCBU D49 257Tuesday, August 29, 2023<project_name><Designer> GRANDTETON_SWB_20230829049 PEX_3_STN_01(1/11)<Reviewer>
C635 DIFF BUS_0.22UF
C673 DIFF BUS_0.22UFC648 DIFF BUS_0.22UF
C686 DIFF BUS_0.22UFC661 DIFF BUS_0.22UFC636 DIFF BUS_0.22UF2/26PEX3BSS26-0A0P-01RXP31BF40RXN31BG40RXP30BH39RXN30BJ39RXP29BF38RXN29BG38RXP28BH37RXN28BJ37RXP27BF36RXN27BG36RXP26BH35RXN26BJ35RXP25BF34RXN25BG34RXP24BH33RXN24BJ33RXP23BF32RXN23BG32RXP22BH31RXN22BJ31RXP21BF30RXN21BG30RXP20BH29RXN20BJ29RXP19BF28RXN19BG28RXP18BH27RXN18BJ27RXP17BF26RXN17BG26RXP16BH25RXN16BJ25TXP31BA40TXN31BB40TXP30BC39TXN30BD39TXP29BA38TXN29BB38TXP28BC37TXN28BD37TXP27BA36TXN27BB36TXP26BC35TXN26BD35TXP25BA34TXN25BB34TXP24BC33TXN24BD33TXP23BA32TXN23BB32TXP22BC31TXN22BD31TXP21BA30TXN21BB30TXP20BC29TXN20BD29TXP19BA28TXN19BB28TXP18BC27TXN18BD27TXP17BA26TXP16BC25TXN16BD25TXN17BB26C674 DIFF BUS_0.22UFC649 DIFF BUS_0.22UF
C687 DIFF BUS_0.22UFC662 DIFF BUS_0.22UFC637 DIFF BUS_0.22UF
C675 DIFF BUS_0.22UFC650 DIFF BUS_0.22UF
C688 DIFF BUS_0.22UFC663 DIFF BUS_0.22UFC638 DIFF BUS_0.22UF
C676 DIFF BUS_0.22UFC651 DIFF BUS_0.22UF
C689 DIFF BUS_0.22UFC664 DIFF BUS_0.22UFC639 DIFF BUS_0.22UF
C677 DIFF BUS_0.22UFC652 DIFF BUS_0.22UF
C690 DIFF BUS_0.22UFC665 DIFF BUS_0.22UFC640 DIFF BUS_0.22UF
C678 DIFF BUS_0.22UFC653 DIFF BUS_0.22UF
C691 DIFF BUS_0.22UF
1/26
PEX3ASS26-0A0P-01RXP15BH41RXN15BJ41RXP14BF42RXN14BG42RXP13BH43RXN13BJ43RXP12BF44RXN12BG44RXP11BH45RXN11BJ45RXP10BF46RXN10BG46RXP9BH47RXN9BJ47RXP8BG48RXN8BG49RXP7AY48RXN7AY49RXP6AW46RXN6AW47RXP5AV48RXN5AV49RXP4AU46RXN4AU47RXP3AT48RXN3AT49RXP2AR46RXN2AR47RXP1AP48RXN1AP49RXP0AN46RXN0AN47TXP15BC41TXN15BD41TXP14BA42TXN14BB42TXP13BC43TXN13BD43TXP12BA44TXN12BB44TXP11BC45TXN11BD45TXP10BA46TXN10BB46TXP9BC47TXN9BD47TXP8BE48TXN8BE49TXP7BB48TXN7BB49TXP6AW43TXN6AW44TXP5AV41TXN5AV42TXP4AU43TXN4AU44TXP3AT41TXN3AT42TXP2AR43TXN2AR44TXP1AP41TXN1AP42TXP0AN43TXN0AN44C666 DIFF BUS_0.22UFC641 DIFF BUS_0.22UF
C679 DIFF BUS_0.22UFC654 DIFF BUS_0.22UF
C692 DIFF BUS_0.22UFC667 DIFF BUS_0.22UFC642 DIFF BUS_0.22UF
C680 DIFF BUS_0.22UFC655 DIFF BUS_0.22UF
C693 DIFF BUS_0.22UFC668 DIFF BUS_0.22UFC643 DIFF BUS_0.22UF
C681 DIFF BUS_0.22UFC656 DIFF BUS_0.22UF
C694 DIFF BUS_0.22UFC669 DIFF BUS_0.22UFC644 DIFF BUS_0.22UF
C682 DIFF BUS_0.22UFC657 DIFF BUS_0.22UF
C695 DIFF BUS_0.22UFC670 DIFF BUS_0.22UFC645 DIFF BUS_0.22UF
C683 DIFF BUS_0.22UFC658 DIFF BUS_0.22UF
C696 DIFF BUS_0.22UFC671 DIFF BUS_0.22UFC646 DIFF BUS_0.22UF
C684 DIFF BUS_0.22UFC659 DIFF BUS_0.22UF
C697 DIFF BUS_0.22UF
C634 DIFF BUS_0.22UF
C672 DIFF BUS_0.22UFC647 DIFF BUS_0.22UF
C685 DIFF BUS_0.22UFC660 DIFF BUS_0.22UFP5E_PEX3_STN0_TX_DP<0>P5E_PEX3_STN0_TX_DN<0>P5E_PEX3_STN1_TX_DN<31>P5E_PEX3_STN1_TX_DP<31>P5E_PEX3_STN0_TX_DP<1>P5E_PEX3_STN0_TX_DN<1>P5E_PEX3_STN0_TX_DP<3>P5E_PEX3_STN0_TX_DN<3>P5E_PEX3_STN0_TX_DP<2>P5E_PEX3_STN0_TX_DN<2>P5E_PEX3_STN0_TX_DP<7>P5E_PEX3_STN0_TX_DN<7>P5E_PEX3_STN0_TX_DP<6>P5E_PEX3_STN0_TX_DN<6>P5E_PEX3_STN0_TX_DP<5>P5E_PEX3_STN0_TX_DN<5>P5E_PEX3_STN0_TX_DP<4>P5E_PEX3_STN0_TX_DN<4>P5E_PEX3_STN0_TX_DP<15>P5E_PEX3_STN0_TX_DN<15>P5E_PEX3_STN0_TX_DN<14>P5E_PEX3_STN0_TX_DP<14>P5E_PEX3_STN0_TX_DP<13>P5E_PEX3_STN0_TX_DN<13>P5E_PEX3_STN0_TX_DN<12>P5E_PEX3_STN0_TX_DP<12>P5E_PEX3_STN0_TX_DP<11>P5E_PEX3_STN0_TX_DN<11>P5E_PEX3_STN0_TX_DP<10>P5E_PEX3_STN0_TX_DN<10>P5E_PEX3_STN0_TX_DP<9>P5E_PEX3_STN0_TX_DN<9>P5E_PEX3_STN0_TX_DP<8>P5E_PEX3_STN0_TX_DN<8>P5E_PEX3_STN1_TX_DP<30>P5E_PEX3_STN1_TX_DN<30>P5E_PEX3_STN1_TX_DN<29>P5E_PEX3_STN1_TX_DP<29>P5E_PEX3_STN1_TX_DP<28>P5E_PEX3_STN1_TX_DN<28>P5E_PEX3_STN1_TX_DN<27>P5E_PEX3_STN1_TX_DP<27>P5E_PEX3_STN1_TX_DP<26>P5E_PEX3_STN1_TX_DN<26>P5E_PEX3_STN1_TX_DN<25>P5E_PEX3_STN1_TX_DP<25>P5E_PEX3_STN1_TX_DP<24>P5E_PEX3_STN1_TX_DN<24>P5E_PEX3_STN1_TX_DN<23>P5E_PEX3_STN1_TX_DP<23>P5E_PEX3_STN1_TX_DP<22>P5E_PEX3_STN1_TX_DN<22>P5E_PEX3_STN1_TX_DN<21>P5E_PEX3_STN1_TX_DP<21>P5E_PEX3_STN1_TX_DP<20>P5E_PEX3_STN1_TX_DN<20>P5E_PEX3_STN1_TX_DN<19>P5E_PEX3_STN1_TX_DP<19>P5E_PEX3_STN1_TX_DP<18>P5E_PEX3_STN1_TX_DN<18>P5E_PEX3_STN1_TX_DN<17>P5E_PEX3_STN1_TX_DP<17>P5E_PEX3_STN1_TX_DP<16>P5E_PEX3_STN1_TX_DN<16>
P5E_PEX3_STN0_TX_C_DP<15>P5E_PEX3_STN0_TX_C_DN<15>P5E_PEX3_STN0_TX_C_DN<14>P5E_PEX3_STN0_TX_C_DP<14>P5E_PEX3_STN0_TX_C_DP<13>P5E_PEX3_STN0_TX_C_DN<13>P5E_PEX3_STN0_TX_C_DN<12>P5E_PEX3_STN0_TX_C_DP<12>P5E_PEX3_STN0_TX_C_DP<11>P5E_PEX3_STN0_TX_C_DN<11>P5E_PEX3_STN0_TX_C_DP<10>P5E_PEX3_STN0_TX_C_DN<10>P5E_PEX3_STN0_TX_C_DP<9>P5E_PEX3_STN0_TX_C_DN<9>P5E_PEX3_STN0_TX_C_DP<8>P5E_PEX3_STN0_TX_C_DN<8>P5E_PEX3_STN0_TX_C_DP<7>P5E_PEX3_STN0_TX_C_DN<7>P5E_PEX3_STN0_TX_C_DP<6>P5E_PEX3_STN0_TX_C_DN<6>P5E_PEX3_STN0_TX_C_DP<5>P5E_PEX3_STN0_TX_C_DN<5>P5E_PEX3_STN0_TX_C_DP<4>P5E_PEX3_STN0_TX_C_DN<4>P5E_PEX3_STN0_TX_C_DP<3>P5E_PEX3_STN0_TX_C_DN<3>P5E_PEX3_STN0_TX_C_DP<2>P5E_PEX3_STN0_TX_C_DN<2>P5E_PEX3_STN0_TX_C_DP<1>P5E_PEX3_STN0_TX_C_DN<1>P5E_PEX3_STN0_TX_C_DP<0>P5E_PEX3_STN0_TX_C_DN<0>P5E_PEX3_STN1_TX_C_DP<16>P5E_PEX3_STN1_TX_C_DN<16>P5E_PEX3_STN1_TX_C_DN<17>P5E_PEX3_STN1_TX_C_DP<17>P5E_PEX3_STN1_TX_C_DN<19>P5E_PEX3_STN1_TX_C_DP<19>P5E_PEX3_STN1_TX_C_DP<18>P5E_PEX3_STN1_TX_C_DN<18>P5E_PEX3_STN1_TX_C_DN<23>P5E_PEX3_STN1_TX_C_DP<23>P5E_PEX3_STN1_TX_C_DP<22>P5E_PEX3_STN1_TX_C_DN<22>P5E_PEX3_STN1_TX_C_DN<21>P5E_PEX3_STN1_TX_C_DP<21>P5E_PEX3_STN1_TX_C_DP<20>P5E_PEX3_STN1_TX_C_DN<20>P5E_PEX3_STN1_TX_C_DP<24>P5E_PEX3_STN1_TX_C_DN<24>P5E_PEX3_STN1_TX_C_DN<25>P5E_PEX3_STN1_TX_C_DP<25>P5E_PEX3_STN1_TX_C_DN<27>P5E_PEX3_STN1_TX_C_DP<27>P5E_PEX3_STN1_TX_C_DP<26>P5E_PEX3_STN1_TX_C_DN<26>P5E_PEX3_STN1_TX_C_DN<31>P5E_PEX3_STN1_TX_C_DP<31>P5E_PEX3_STN1_TX_C_DP<30>P5E_PEX3_STN1_TX_C_DN<30>P5E_PEX3_STN1_TX_C_DN<29>P5E_PEX3_STN1_TX_C_DP<29>P5E_PEX3_STN1_TX_C_DP<28>P5E_PEX3_STN1_TX_C_DN<28>
P5E_PEX3_STN0_RX_DP<15>P5E_PEX3_STN0_RX_DN<15>P5E_PEX3_STN0_RX_DP<14>P5E_PEX3_STN0_RX_DN<14>P5E_PEX3_STN0_RX_DP<13>P5E_PEX3_STN0_RX_DN<13>P5E_PEX3_STN0_RX_DP<12>P5E_PEX3_STN0_RX_DN<12>P5E_PEX3_STN0_RX_DP<11>P5E_PEX3_STN0_RX_DN<11>P5E_PEX3_STN0_RX_DP<10>P5E_PEX3_STN0_RX_DN<10>P5E_PEX3_STN0_RX_DP<9>P5E_PEX3_STN0_RX_DN<9>P5E_PEX3_STN0_RX_DP<8>P5E_PEX3_STN0_RX_DN<8>P5E_PEX3_STN0_RX_DP<7>P5E_PEX3_STN0_RX_DN<7>P5E_PEX3_STN0_RX_DP<6>P5E_PEX3_STN0_RX_DN<6>P5E_PEX3_STN0_RX_DP<5>P5E_PEX3_STN0_RX_DN<5>P5E_PEX3_STN0_RX_DP<4>P5E_PEX3_STN0_RX_DN<4>P5E_PEX3_STN0_RX_DP<3>P5E_PEX3_STN0_RX_DN<3>P5E_PEX3_STN0_RX_DP<2>P5E_PEX3_STN0_RX_DN<2>P5E_PEX3_STN0_RX_DP<1>P5E_PEX3_STN0_RX_DN<1>P5E_PEX3_STN0_RX_DP<0>P5E_PEX3_STN0_RX_DN<0>P5E_PEX3_STN1_RX_DP<31>P5E_PEX3_STN1_RX_DN<31>P5E_PEX3_STN1_RX_DP<30>P5E_PEX3_STN1_RX_DN<30>P5E_PEX3_STN1_RX_DP<29>P5E_PEX3_STN1_RX_DN<29>P5E_PEX3_STN1_RX_DP<28>P5E_PEX3_STN1_RX_DN<28>P5E_PEX3_STN1_RX_DP<27>P5E_PEX3_STN1_RX_DN<27>P5E_PEX3_STN1_RX_DP<26>P5E_PEX3_STN1_RX_DN<26>P5E_PEX3_STN1_RX_DP<25>P5E_PEX3_STN1_RX_DN<25>P5E_PEX3_STN1_RX_DP<24>P5E_PEX3_STN1_RX_DN<24>P5E_PEX3_STN1_RX_DP<23>P5E_PEX3_STN1_RX_DN<23>P5E_PEX3_STN1_RX_DP<22>P5E_PEX3_STN1_RX_DN<22>P5E_PEX3_STN1_RX_DP<21>P5E_PEX3_STN1_RX_DN<21>P5E_PEX3_STN1_RX_DP<20>P5E_PEX3_STN1_RX_DN<20>P5E_PEX3_STN1_RX_DP<19>P5E_PEX3_STN1_RX_DN<19>P5E_PEX3_STN1_RX_DP<18>P5E_PEX3_STN1_RX_DN<18>P5E_PEX3_STN1_RX_DP<17>P5E_PEX3_STN1_RX_DN<17>P5E_PEX3_STN1_RX_DP<16>P5E_PEX3_STN1_RX_DN<16>



5
5
4
4
3
3
2
2
1
1
D D
C C
B B
A A
PEX_3_STN_23(2/11)
P5E_PEX3_STN2_TX_C_DP<47> [200]P5E_PEX3_STN2_TX_C_DN<47> [200]P5E_PEX3_STN2_TX_C_DP<46> [200]P5E_PEX3_STN2_TX_C_DN<46> [200]P5E_PEX3_STN2_TX_C_DP<45> [200]P5E_PEX3_STN2_TX_C_DN<45> [200]P5E_PEX3_STN2_TX_C_DP<44> [200]P5E_PEX3_STN2_TX_C_DN<44> [200]P5E_PEX3_STN2_TX_C_DP<43> [200]P5E_PEX3_STN2_TX_C_DN<43> [200]P5E_PEX3_STN2_TX_C_DP<42> [200]P5E_PEX3_STN2_TX_C_DN<42> [200]P5E_PEX3_STN2_TX_C_DP<41> [200]P5E_PEX3_STN2_TX_C_DN<41> [200]P5E_PEX3_STN2_TX_C_DP<40> [200]P5E_PEX3_STN2_TX_C_DN<40> [200]P5E_PEX3_STN2_TX_C_DP<39> [201]P5E_PEX3_STN2_TX_C_DN<39> [201]P5E_PEX3_STN2_TX_C_DP<38> [201]P5E_PEX3_STN2_TX_C_DN<38> [201]P5E_PEX3_STN2_TX_C_DP<37> [201]P5E_PEX3_STN2_TX_C_DN<37> [201]P5E_PEX3_STN2_TX_C_DP<36> [201]P5E_PEX3_STN2_TX_C_DN<36> [201]P5E_PEX3_STN2_TX_C_DP<35> [201]P5E_PEX3_STN2_TX_C_DN<35> [201]P5E_PEX3_STN2_TX_C_DP<34> [201]P5E_PEX3_STN2_TX_C_DN<34> [201]P5E_PEX3_STN2_TX_C_DP<33> [201]P5E_PEX3_STN2_TX_C_DN<33> [201]P5E_PEX3_STN2_TX_C_DP<32> [201]P5E_PEX3_STN2_TX_C_DN<32> [201]P5E_PEX3_STN2_RX_DP<47>[200]P5E_PEX3_STN2_RX_DN<47>[200]P5E_PEX3_STN2_RX_DP<46>[200]P5E_PEX3_STN2_RX_DN<46>[200]P5E_PEX3_STN2_RX_DP<45>[200]P5E_PEX3_STN2_RX_DN<45>[200]P5E_PEX3_STN2_RX_DP<44>[200]P5E_PEX3_STN2_RX_DN<44>[200]P5E_PEX3_STN2_RX_DP<43>[200]P5E_PEX3_STN2_RX_DN<43>[200]P5E_PEX3_STN2_RX_DP<42>[200]P5E_PEX3_STN2_RX_DN<42>[200]P5E_PEX3_STN2_RX_DP<41>[200]P5E_PEX3_STN2_RX_DN<41>[200]P5E_PEX3_STN2_RX_DP<40>[200]P5E_PEX3_STN2_RX_DN<40>[200]P5E_PEX3_STN2_RX_DP<39>[201]P5E_PEX3_STN2_RX_DN<39>[201]P5E_PEX3_STN2_RX_DP<38>[201]P5E_PEX3_STN2_RX_DN<38>[201]P5E_PEX3_STN2_RX_DP<37>[201]P5E_PEX3_STN2_RX_DN<37>[201]P5E_PEX3_STN2_RX_DP<36>[201]P5E_PEX3_STN2_RX_DN<36>[201]P5E_PEX3_STN2_RX_DP<35>[201]P5E_PEX3_STN2_RX_DN<35>[201]P5E_PEX3_STN2_RX_DP<34>[201]P5E_PEX3_STN2_RX_DN<34>[201]P5E_PEX3_STN2_RX_DP<33>[201]P5E_PEX3_STN2_RX_DN<33>[201]P5E_PEX3_STN2_RX_DP<32>[201]P5E_PEX3_STN2_RX_DN<32>[201]
SizeDoc NumberRevDate: SheetofReviewerDesignerDepartmentProject
Page TitleCCBU D50 257Tuesday, August 29, 2023<project_name><Designer> GRANDTETON_SWB_20230829050 PEX_3_STN_23(2/11)<Reviewer>SizeDoc NumberRevDate: SheetofReviewerDesignerDepartmentProject
Page TitleCCBU D50 257Tuesday, August 29, 2023<project_name><Designer> GRANDTETON_SWB_20230829050 PEX_3_STN_23(2/11)<Reviewer>SizeDoc NumberRevDate: SheetofReviewerDesignerDepartmentProject
Page TitleCCBU D50 257Tuesday, August 29, 2023<project_name><Designer> GRANDTETON_SWB_20230829050 PEX_3_STN_23(2/11)<Reviewer>
C710 DIFF BUS_0.22UFC723 DIFF BUS_0.22UFC698 DIFF BUS_0.22UFC711 DIFF BUS_0.22UFC724 DIFF BUS_0.22UFC699 DIFF BUS_0.22UFC712 DIFF BUS_0.22UFC725 DIFF BUS_0.22UFC700 DIFF BUS_0.22UFC713 DIFF BUS_0.22UFC726 DIFF BUS_0.22UFC701 DIFF BUS_0.22UFC714 DIFF BUS_0.22UF4/26PEX3DSS26-0A0P-01RXP63BF8RXN63BG8RXP62BH7RXN62BJ7RXP61BF6RXN61BG6RXP60BH5RXN60BJ5RXP59BF4RXN59BG4RXP58BH3RXN58BJ3RXP57BG2RXN57BG1RXP56AY2RXN56AY1RXP55AW4RXN55AW3RXP54AV2RXN54AV1RXP53AU4RXN53AU3RXP52AT2RXN52AT1RXP51AR4RXN51AR3RXP50AP2RXN50AP1RXP49AN4RXN49AN3RXP48AM2RXN48AM1TXP63BA8TXN63BB8TXP62BC7TXN62BD7TXP61BA6TXN61BB6TXP60BC5TXN60BD5TXP59BA4TXN59BB4TXP58BC3TXN58BD3TXP57BE2TXN57BE1TXP56BB2TXN56BB1TXP55AW7TXN55AW6TXP54AV9TXN54AV8TXP53AU7TXN53AU6TXP52AT9TXN52AT8TXP51AR7TXN51AR6TXP50AP9TXN50AP8TXP49AN7TXN49AN6TXP48AM9TXN48AM8C727 DIFF BUS_0.22UFC702 DIFF BUS_0.22UFC715 DIFF BUS_0.22UFC728 DIFF BUS_0.22UFC703 DIFF BUS_0.22UFC716 DIFF BUS_0.22UFC729 DIFF BUS_0.22UFC704 DIFF BUS_0.22UFC717 DIFF BUS_0.22UFC705 DIFF BUS_0.22UFC718 DIFF BUS_0.22UFC706 DIFF BUS_0.22UF3/26PEX3CSS26-0A0P-01RXP47BH9RXN47BJ9RXP46BF10RXN46BG10RXP45BH11RXN45BJ11RXP44BF12RXN44BG12RXP43BH13RXN43BJ13RXP42BF14RXN42BG14RXP41BH15RXN41BJ15RXP40BF16RXN40BG16RXP39BH17RXN39BJ17RXP38BF18RXN38BG18RXP37BH19RXN37BJ19RXP36BF20RXN36BG20RXP35BH21RXN35BJ21RXP34BF22RXN34BG22RXP33BH23RXN33BJ23RXP32BF24RXN32BG24TXP47BC9TXN47BD9TXP46BA10TXN46BB10TXP45BC11TXN45BD11TXP44BA12TXN44BB12TXP43BC13TXN43BD13TXP42BA14TXN42BB14TXP41BC15TXN41BD15TXP40BA16TXN40BB16TXP39BC17TXN39BD17TXP38BA18TXN38BB18TXP37BC19TXN37BD19TXP36BA20TXN36BB20TXP35BC21TXN35BD21TXP34BA22TXN34BB22TXP33BC23TXN33BD23TXP32BA24TXN32BB24C719 DIFF BUS_0.22UFC707 DIFF BUS_0.22UFC720 DIFF BUS_0.22UFC708 DIFF BUS_0.22UFC721 DIFF BUS_0.22UFC709 DIFF BUS_0.22UFC722 DIFF BUS_0.22UFP5E_PEX3_STN2_TX_DP<47>P5E_PEX3_STN2_TX_DN<47>P5E_PEX3_STN2_TX_DP<39>P5E_PEX3_STN2_TX_DN<39>P5E_PEX3_STN2_TX_DP<46>P5E_PEX3_STN2_TX_DN<46>P5E_PEX3_STN2_TX_DP<45>P5E_PEX3_STN2_TX_DN<45>P5E_PEX3_STN2_TX_DP<44>P5E_PEX3_STN2_TX_DN<44>P5E_PEX3_STN2_TX_DP<43>P5E_PEX3_STN2_TX_DN<43>P5E_PEX3_STN2_TX_DP<42>P5E_PEX3_STN2_TX_DN<42>P5E_PEX3_STN2_TX_DP<41>P5E_PEX3_STN2_TX_DN<41>P5E_PEX3_STN2_TX_DP<40>P5E_PEX3_STN2_TX_DN<40>P5E_PEX3_STN2_TX_DP<38>P5E_PEX3_STN2_TX_DN<38>P5E_PEX3_STN2_TX_DP<37>P5E_PEX3_STN2_TX_DN<37>P5E_PEX3_STN2_TX_DP<36>P5E_PEX3_STN2_TX_DN<36>P5E_PEX3_STN2_TX_DP<35>P5E_PEX3_STN2_TX_DN<35>P5E_PEX3_STN2_TX_DP<34>P5E_PEX3_STN2_TX_DN<34>P5E_PEX3_STN2_TX_DP<33>P5E_PEX3_STN2_TX_DN<33>P5E_PEX3_STN2_TX_DP<32>P5E_PEX3_STN2_TX_DN<32>P5E_PEX3_STN2_TX_C_DP<47>P5E_PEX3_STN2_TX_C_DN<47>P5E_PEX3_STN2_TX_C_DP<46>P5E_PEX3_STN2_TX_C_DN<46>P5E_PEX3_STN2_TX_C_DP<45>P5E_PEX3_STN2_TX_C_DN<45>P5E_PEX3_STN2_TX_C_DP<44>P5E_PEX3_STN2_TX_C_DN<44>P5E_PEX3_STN2_TX_C_DP<43>P5E_PEX3_STN2_TX_C_DN<43>P5E_PEX3_STN2_TX_C_DP<42>P5E_PEX3_STN2_TX_C_DN<42>P5E_PEX3_STN2_TX_C_DP<41>P5E_PEX3_STN2_TX_C_DN<41>P5E_PEX3_STN2_TX_C_DP<40>P5E_PEX3_STN2_TX_C_DN<40>P5E_PEX3_STN2_TX_C_DP<39>P5E_PEX3_STN2_TX_C_DN<39>P5E_PEX3_STN2_TX_C_DP<38>P5E_PEX3_STN2_TX_C_DN<38>P5E_PEX3_STN2_TX_C_DP<37>P5E_PEX3_STN2_TX_C_DN<37>P5E_PEX3_STN2_TX_C_DP<36>P5E_PEX3_STN2_TX_C_DN<36>P5E_PEX3_STN2_TX_C_DP<35>P5E_PEX3_STN2_TX_C_DN<35>P5E_PEX3_STN2_TX_C_DP<34>P5E_PEX3_STN2_TX_C_DN<34>P5E_PEX3_STN2_TX_C_DP<33>P5E_PEX3_STN2_TX_C_DN<33>P5E_PEX3_STN2_TX_C_DP<32>P5E_PEX3_STN2_TX_C_DN<32>P5E_PEX3_STN2_RX_DP<47>P5E_PEX3_STN2_RX_DN<47>P5E_PEX3_STN2_RX_DP<46>P5E_PEX3_STN2_RX_DN<46>P5E_PEX3_STN2_RX_DP<45>P5E_PEX3_STN2_RX_DN<45>P5E_PEX3_STN2_RX_DP<44>P5E_PEX3_STN2_RX_DN<44>P5E_PEX3_STN2_RX_DP<43>P5E_PEX3_STN2_RX_DN<43>P5E_PEX3_STN2_RX_DP<42>P5E_PEX3_STN2_RX_DN<42>P5E_PEX3_STN2_RX_DP<41>P5E_PEX3_STN2_RX_DN<41>P5E_PEX3_STN2_RX_DP<40>P5E_PEX3_STN2_RX_DN<40>P5E_PEX3_STN2_RX_DP<39>P5E_PEX3_STN2_RX_DN<39>P5E_PEX3_STN2_RX_DP<38>P5E_PEX3_STN2_RX_DN<38>P5E_PEX3_STN2_RX_DP<37>P5E_PEX3_STN2_RX_DN<37>P5E_PEX3_STN2_RX_DP<36>P5E_PEX3_STN2_RX_DN<36>P5E_PEX3_STN2_RX_DP<35>P5E_PEX3_STN2_RX_DN<35>P5E_PEX3_STN2_RX_DP<34>P5E_PEX3_STN2_RX_DN<34>P5E_PEX3_STN2_RX_DP<33>P5E_PEX3_STN2_RX_DN<33>P5E_PEX3_STN2_RX_DP<32>P5E_PEX3_STN2_RX_DN<32>



5
5
4
4
3
3
2
2
1
1
D D
C C
B B
A A
PEX_3_STN_45(3/11)
P5E_PEX3_STN4_RX_DP<79>[159]P5E_PEX3_STN4_TX_C_DP<79> [159]P5E_PEX3_STN4_RX_DN<79>[159]P5E_PEX3_STN4_TX_C_DN<79> [159]P5E_PEX3_STN4_RX_DP<78>[159]P5E_PEX3_STN4_TX_C_DP<78> [159]P5E_PEX3_STN4_RX_DN<78>[159]P5E_PEX3_STN4_TX_C_DN<78> [159]P5E_PEX3_STN4_RX_DP<77>[160]P5E_PEX3_STN4_TX_C_DP<77> [160]P5E_PEX3_STN4_RX_DN<77>[160]P5E_PEX3_STN4_TX_C_DN<77> [160]P5E_PEX3_STN4_RX_DP<76>[160]P5E_PEX3_STN4_TX_C_DP<76> [160]P5E_PEX3_STN4_RX_DN<76>[160]P5E_PEX3_STN4_TX_C_DN<76> [160]P5E_PEX3_STN4_RX_DP<75>[161]P5E_PEX3_STN4_TX_C_DP<75> [161]P5E_PEX3_STN4_RX_DN<75>[161]P5E_PEX3_STN4_TX_C_DN<75> [161]P5E_PEX3_STN4_RX_DP<74>[161]P5E_PEX3_STN4_TX_C_DP<74> [161]P5E_PEX3_STN4_RX_DN<74>[161]P5E_PEX3_STN4_TX_C_DN<74> [161]P5E_PEX3_STN4_RX_DP<73>[162]P5E_PEX3_STN4_TX_C_DP<73> [162]P5E_PEX3_STN4_RX_DN<73>[162]P5E_PEX3_STN4_TX_C_DN<73> [162]P5E_PEX3_STN4_RX_DP<72>[162]P5E_PEX3_STN4_TX_C_DP<72> [162]P5E_PEX3_STN4_RX_DN<72>[162]P5E_PEX3_STN4_TX_C_DN<72> [162]P5E_PEX3_STN4_RX_DP<71>[159]P5E_PEX3_STN4_TX_C_DP<71> [159]P5E_PEX3_STN4_RX_DN<71>[159]P5E_PEX3_STN4_TX_C_DN<71> [159]P5E_PEX3_STN4_RX_DP<70>[159]P5E_PEX3_STN4_TX_C_DP<70> [159]P5E_PEX3_STN4_RX_DN<70>[159]P5E_PEX3_STN4_TX_C_DN<70> [159]P5E_PEX3_STN4_RX_DP<69>[160]P5E_PEX3_STN4_TX_C_DP<69> [160]P5E_PEX3_STN4_RX_DN<69>[160]P5E_PEX3_STN4_TX_C_DN<69> [160]P5E_PEX3_STN4_RX_DP<68>[160]P5E_PEX3_STN4_TX_C_DP<68> [160]P5E_PEX3_STN4_RX_DN<68>[160]P5E_PEX3_STN4_TX_C_DN<68> [160]P5E_PEX3_STN4_RX_DP<67>[161]P5E_PEX3_STN4_TX_C_DP<67> [161]P5E_PEX3_STN4_RX_DN<67>[161]P5E_PEX3_STN4_TX_C_DN<67> [161]P5E_PEX3_STN4_RX_DP<66>[161]P5E_PEX3_STN4_TX_C_DP<66> [161]P5E_PEX3_STN4_RX_DN<66>[161]P5E_PEX3_STN4_TX_C_DN<66> [161]P5E_PEX3_STN4_RX_DP<65>[162]P5E_PEX3_STN4_TX_C_DP<65> [162]P5E_PEX3_STN4_RX_DN<65>[162]P5E_PEX3_STN4_TX_C_DN<65> [162]P5E_PEX3_STN4_RX_DP<64>[162]P5E_PEX3_STN4_TX_C_DP<64> [162]P5E_PEX3_STN4_RX_DN<64>[162]P5E_PEX3_STN4_TX_C_DN<64> [162]P5E_PEX3_STN5_RX_DP<95>[157]P5E_PEX3_STN5_TX_C_DP<95> [157]P5E_PEX3_STN5_RX_DN<95>[157]P5E_PEX3_STN5_TX_C_DN<95> [157]P5E_PEX3_STN5_RX_DP<94>[157]P5E_PEX3_STN5_TX_C_DP<94> [157]P5E_PEX3_STN5_RX_DN<94>[157]P5E_PEX3_STN5_TX_C_DN<94> [157]P5E_PEX3_STN5_RX_DP<93>[156]P5E_PEX3_STN5_TX_C_DP<93> [156]P5E_PEX3_STN5_RX_DN<93>[156]P5E_PEX3_STN5_TX_C_DN<93> [156]P5E_PEX3_STN5_RX_DP<92>[156]P5E_PEX3_STN5_TX_C_DP<92> [156]P5E_PEX3_STN5_RX_DN<92>[156]P5E_PEX3_STN5_TX_C_DN<92> [156]P5E_PEX3_STN5_RX_DP<91>[155]P5E_PEX3_STN5_TX_C_DP<91> [155]P5E_PEX3_STN5_RX_DN<91>[155]P5E_PEX3_STN5_TX_C_DN<91> [155]P5E_PEX3_STN5_RX_DP<90>[155]P5E_PEX3_STN5_TX_C_DP<90> [155]P5E_PEX3_STN5_RX_DN<90>[155]P5E_PEX3_STN5_TX_C_DN<90> [155]P5E_PEX3_STN5_RX_DP<89>[154]P5E_PEX3_STN5_TX_C_DP<89> [154]P5E_PEX3_STN5_RX_DN<89>[154]P5E_PEX3_STN5_TX_C_DN<89> [154]P5E_PEX3_STN5_RX_DP<88>[154]P5E_PEX3_STN5_TX_C_DP<88> [154]P5E_PEX3_STN5_RX_DN<88>[154]P5E_PEX3_STN5_TX_C_DN<88> [154]P5E_PEX3_STN5_RX_DP<87>[157]P5E_PEX3_STN5_TX_C_DP<87> [157]P5E_PEX3_STN5_RX_DN<87>[157]P5E_PEX3_STN5_TX_C_DN<87> [157]P5E_PEX3_STN5_RX_DP<86>[157]P5E_PEX3_STN5_TX_C_DP<86> [157]P5E_PEX3_STN5_RX_DN<86>[157]P5E_PEX3_STN5_TX_C_DN<86> [157]P5E_PEX3_STN5_RX_DP<85>[156]P5E_PEX3_STN5_TX_C_DP<85> [156]P5E_PEX3_STN5_RX_DN<85>[156]P5E_PEX3_STN5_TX_C_DN<85> [156]P5E_PEX3_STN5_RX_DP<84>[156]P5E_PEX3_STN5_TX_C_DP<84> [156]P5E_PEX3_STN5_RX_DN<84>[156]P5E_PEX3_STN5_TX_C_DN<84> [156]P5E_PEX3_STN5_RX_DP<83>[155]P5E_PEX3_STN5_TX_C_DP<83> [155]P5E_PEX3_STN5_RX_DN<83>[155]P5E_PEX3_STN5_TX_C_DN<83> [155]P5E_PEX3_STN5_RX_DP<82>[155]P5E_PEX3_STN5_TX_C_DP<82> [155]P5E_PEX3_STN5_RX_DN<82>[155]P5E_PEX3_STN5_TX_C_DN<82> [155]P5E_PEX3_STN5_RX_DP<81>[154]P5E_PEX3_STN5_TX_C_DP<81> [154]P5E_PEX3_STN5_RX_DN<81>[154]P5E_PEX3_STN5_TX_C_DN<81> [154]P5E_PEX3_STN5_RX_DP<80>[154]P5E_PEX3_STN5_TX_C_DP<80> [154]P5E_PEX3_STN5_RX_DN<80>[154]P5E_PEX3_STN5_TX_C_DN<80> [154]SizeDoc NumberRevDate: SheetofReviewerDesignerDepartmentProject
Page TitleCCBU D51 257Tuesday, August 29, 2023<project_name><Designer> GRANDTETON_SWB_20230829051 PEX_3_STN_45(3/11)<Reviewer>SizeDoc NumberRevDate: SheetofReviewerDesignerDepartmentProject
Page TitleCCBU D51 257Tuesday, August 29, 2023<project_name><Designer> GRANDTETON_SWB_20230829051 PEX_3_STN_45(3/11)<Reviewer>SizeDoc NumberRevDate: SheetofReviewerDesignerDepartmentProject
Page TitleCCBU D51 257Tuesday, August 29, 2023<project_name><Designer> GRANDTETON_SWB_20230829051 PEX_3_STN_45(3/11)<Reviewer>
C2443 DIFF BUS_0.22UF
C747 DIFF BUS_0.22UFC2455 DIFF BUS_0.22UFC2442 DIFF BUS_0.22UF
C760 DIFF BUS_0.22UFC735 DIFF BUS_0.22UFC748 DIFF BUS_0.22UFC2454 DIFF BUS_0.22UF
C761 DIFF BUS_0.22UFC736 DIFF BUS_0.22UFC749 DIFF BUS_0.22UF
C2446 DIFF BUS_0.22UFC737 DIFF BUS_0.22UFC2451 DIFF BUS_0.22UF
C750 DIFF BUS_0.22UF
C2445 DIFF BUS_0.22UFC2452 DIFF BUS_0.22UFC738 DIFF BUS_0.22UFC2457 DIFF BUS_0.22UFC751 DIFF BUS_0.22UFC2470 DIFF BUS_0.22UFC2444 DIFF BUS_0.22UFC2465 DIFF BUS_0.22UFC2469 DIFF BUS_0.22UFC2464 DIFF BUS_0.22UFC739 DIFF BUS_0.22UFC2459 DIFF BUS_0.22UFC752 DIFF BUS_0.22UFC740 DIFF BUS_0.22UFC2458 DIFF BUS_0.22UFC2462 DIFF BUS_0.22UFC2463 DIFF BUS_0.22UFC753 DIFF BUS_0.22UFC2466 DIFF BUS_0.22UFC2461 DIFF BUS_0.22UFC741 DIFF BUS_0.22UFC2456 DIFF BUS_0.22UF
C754 DIFF BUS_0.22UF6/26PEX3FSS26-0A0P-01RXP95B39RXN95A39RXP94D38RXN94C38RXP93B37RXN93A37RXP92D36RXN92C36RXP91B35RXN91A35RXP90D34RXN90C34RXP89B33RXN89A33RXP88D32RXN88C32RXP87B31RXN87A31RXP86D30RXN86C30RXP85B29RXN85A29RXP84D28RXN84C28RXP83B27RXN83A27RXP82D26RXN82C26RXP81B25RXN81A25RXP80D24RXN80C24TXP95G39TXN95F39TXP94J38TXN94H38TXP93G37TXN93F37TXP92J36TXN92H36TXP91G35TXN91F35TXP90J34TXN90H34TXP89G33TXN89F33TXP88J32TXN88H32TXP87G31TXN87F31TXP86J30TXN86H30TXP85G29TXN85F29TXP84J28TXN84H28TXP83G27TXN83F27TXP82J26TXN82H26TXP81G25TXN81F25TXP80J24TXN80H24
C2439 DIFF BUS_0.22UFC2449 DIFF BUS_0.22UFC742 DIFF BUS_0.22UFC755 DIFF BUS_0.22UF
C2448 DIFF BUS_0.22UFC730 DIFF BUS_0.22UFC743 DIFF BUS_0.22UFC2460 DIFF BUS_0.22UF
C756 DIFF BUS_0.22UFC731 DIFF BUS_0.22UFC2447 DIFF BUS_0.22UF
C744 DIFF BUS_0.22UFC757 DIFF BUS_0.22UF
C2450 DIFF BUS_0.22UFC2467 DIFF BUS_0.22UFC732 DIFF BUS_0.22UFC745 DIFF BUS_0.22UFC2468 DIFF BUS_0.22UFC758 DIFF BUS_0.22UFC733 DIFF BUS_0.22UFC2441 DIFF BUS_0.22UFC2453 DIFF BUS_0.22UFC746 DIFF BUS_0.22UF
C2440 DIFF BUS_0.22UF5/26PEX3ESS26-0A0P-01RXP79D40RXN79C40RXP78B41RXN78A41RXP77D42RXN77C42RXP76B43RXN76A43RXP75D44RXN75C44RXP74B45RXN74A45RXP73D46RXN73C46RXP72B47RXN72A47RXP71C48RXN71C49RXP70K48RXN70K49RXP69L46RXN69L47RXP68M48RXN68M49RXP67N46RXN67N47RXP66P48RXN66P49RXP65R46RXN65R47RXP64T48RXN64T49TXP79J40TXN79H40TXP78G41TXN78F41TXP77J42TXN77H42TXP76G43TXN76F43TXP75J44TXN75H44TXP74G45TXN74F45TXP73J46TXN73H46TXP72G47TXN72F47TXP71E48TXN71E49TXP70H48TXN70H49TXP69L43TXN69L44TXP68M41TXN68M42TXP67N43TXN67N44TXP66P41TXN66P42TXP65R43TXN65R44TXP64T41TXN64T42C759 DIFF BUS_0.22UFC734 DIFF BUS_0.22UFP5E_PEX3_STN4_RX_DP<79>P5E_PEX3_STN4_TX_DP<79>P5E_PEX3_STN4_TX_C_DP<79>P5E_PEX3_STN4_RX_DN<79>P5E_PEX3_STN4_TX_DN<79>P5E_PEX3_STN4_TX_C_DN<79>P5E_PEX3_STN4_RX_DP<78>P5E_PEX3_STN4_TX_DP<78>P5E_PEX3_STN4_TX_C_DP<78>P5E_PEX3_STN4_RX_DN<78>P5E_PEX3_STN4_TX_DN<78>P5E_PEX3_STN4_TX_C_DN<78>P5E_PEX3_STN4_RX_DP<77>P5E_PEX3_STN4_TX_DP<77>P5E_PEX3_STN4_TX_C_DP<77>P5E_PEX3_STN4_RX_DN<77>P5E_PEX3_STN4_TX_DN<77>P5E_PEX3_STN4_TX_C_DN<77>P5E_PEX3_STN4_RX_DP<76>P5E_PEX3_STN4_TX_DP<76>P5E_PEX3_STN4_TX_C_DP<76>P5E_PEX3_STN4_RX_DN<76>P5E_PEX3_STN4_TX_DN<76>P5E_PEX3_STN4_TX_C_DN<76>P5E_PEX3_STN4_RX_DP<75>P5E_PEX3_STN4_TX_DP<75>P5E_PEX3_STN4_TX_C_DP<75>P5E_PEX3_STN4_RX_DN<75>P5E_PEX3_STN4_TX_DN<75>P5E_PEX3_STN4_TX_C_DN<75>P5E_PEX3_STN4_RX_DP<74>P5E_PEX3_STN4_TX_DP<74>P5E_PEX3_STN4_TX_C_DP<74>P5E_PEX3_STN4_RX_DN<74>P5E_PEX3_STN4_TX_DN<74>P5E_PEX3_STN4_TX_C_DN<74>P5E_PEX3_STN4_RX_DP<73>P5E_PEX3_STN4_TX_DP<73>P5E_PEX3_STN4_TX_C_DP<73>P5E_PEX3_STN4_RX_DN<73>P5E_PEX3_STN4_TX_DN<73>P5E_PEX3_STN4_TX_C_DN<73>P5E_PEX3_STN4_RX_DP<72>P5E_PEX3_STN4_TX_DP<72>P5E_PEX3_STN4_TX_C_DP<72>P5E_PEX3_STN4_RX_DN<72>P5E_PEX3_STN4_TX_DN<72>P5E_PEX3_STN4_TX_C_DN<72>P5E_PEX3_STN4_RX_DP<71>P5E_PEX3_STN4_TX_DP<71>P5E_PEX3_STN4_TX_C_DP<71>P5E_PEX3_STN4_RX_DN<71>P5E_PEX3_STN4_TX_DN<71>P5E_PEX3_STN4_TX_C_DN<71>P5E_PEX3_STN4_RX_DP<70>P5E_PEX3_STN4_TX_DP<70>P5E_PEX3_STN4_TX_C_DP<70>P5E_PEX3_STN4_RX_DN<70>P5E_PEX3_STN4_TX_DN<70>P5E_PEX3_STN4_TX_C_DN<70>P5E_PEX3_STN4_RX_DP<69>P5E_PEX3_STN4_TX_DP<69>P5E_PEX3_STN4_TX_C_DP<69>P5E_PEX3_STN4_RX_DN<69>P5E_PEX3_STN4_TX_DN<69>P5E_PEX3_STN4_TX_C_DN<69>P5E_PEX3_STN4_RX_DP<68>P5E_PEX3_STN4_TX_DP<68>P5E_PEX3_STN4_TX_C_DP<68>P5E_PEX3_STN4_RX_DN<68>P5E_PEX3_STN4_TX_DN<68>P5E_PEX3_STN4_TX_C_DN<68>P5E_PEX3_STN4_RX_DP<67>P5E_PEX3_STN4_TX_DP<67>P5E_PEX3_STN4_TX_C_DP<67>P5E_PEX3_STN4_RX_DN<67>P5E_PEX3_STN4_TX_DN<67>P5E_PEX3_STN4_TX_C_DN<67>P5E_PEX3_STN4_RX_DP<66>P5E_PEX3_STN4_TX_DP<66>P5E_PEX3_STN4_TX_C_DP<66>P5E_PEX3_STN4_RX_DN<66>P5E_PEX3_STN4_TX_DN<66>P5E_PEX3_STN4_TX_C_DN<66>P5E_PEX3_STN4_RX_DP<65>P5E_PEX3_STN4_TX_DP<65>P5E_PEX3_STN4_TX_C_DP<65>P5E_PEX3_STN4_RX_DN<65>P5E_PEX3_STN4_TX_DN<65>P5E_PEX3_STN4_TX_C_DN<65>P5E_PEX3_STN4_RX_DP<64>P5E_PEX3_STN4_TX_DP<64>P5E_PEX3_STN4_TX_C_DP<64>P5E_PEX3_STN4_RX_DN<64>P5E_PEX3_STN4_TX_DN<64>P5E_PEX3_STN4_TX_C_DN<64>P5E_PEX3_STN5_RX_DP<95>P5E_PEX3_STN5_TX_DP<95>P5E_PEX3_STN5_TX_C_DP<95>P5E_PEX3_STN5_RX_DN<95>P5E_PEX3_STN5_TX_DN<95>P5E_PEX3_STN5_TX_C_DN<95>P5E_PEX3_STN5_RX_DP<94>P5E_PEX3_STN5_TX_DP<94>P5E_PEX3_STN5_TX_C_DP<94>P5E_PEX3_STN5_RX_DN<94>P5E_PEX3_STN5_TX_DN<94>P5E_PEX3_STN5_TX_C_DN<94>P5E_PEX3_STN5_RX_DP<93>P5E_PEX3_STN5_TX_DP<93>P5E_PEX3_STN5_TX_C_DP<93>P5E_PEX3_STN5_RX_DN<93>P5E_PEX3_STN5_TX_DN<93>P5E_PEX3_STN5_TX_C_DN<93>P5E_PEX3_STN5_RX_DP<92>P5E_PEX3_STN5_TX_DP<92>P5E_PEX3_STN5_TX_C_DP<92>P5E_PEX3_STN5_RX_DN<92>P5E_PEX3_STN5_TX_DN<92>P5E_PEX3_STN5_TX_C_DN<92>P5E_PEX3_STN5_RX_DP<91>P5E_PEX3_STN5_TX_DP<91>P5E_PEX3_STN5_TX_C_DP<91>P5E_PEX3_STN5_RX_DN<91>P5E_PEX3_STN5_TX_DN<91>P5E_PEX3_STN5_TX_C_DN<91>P5E_PEX3_STN5_RX_DP<90>P5E_PEX3_STN5_TX_DP<90>P5E_PEX3_STN5_TX_C_DP<90>P5E_PEX3_STN5_RX_DN<90>P5E_PEX3_STN5_TX_DN<90>P5E_PEX3_STN5_TX_C_DN<90>P5E_PEX3_STN5_RX_DP<89>P5E_PEX3_STN5_TX_DP<89>P5E_PEX3_STN5_TX_C_DP<89>P5E_PEX3_STN5_RX_DN<89>P5E_PEX3_STN5_TX_DN<89>P5E_PEX3_STN5_TX_C_DN<89>P5E_PEX3_STN5_RX_DP<88>P5E_PEX3_STN5_TX_DP<88>P5E_PEX3_STN5_TX_C_DP<88>P5E_PEX3_STN5_RX_DN<88>P5E_PEX3_STN5_TX_DN<88>P5E_PEX3_STN5_TX_C_DN<88>P5E_PEX3_STN5_RX_DP<87>P5E_PEX3_STN5_TX_DP<87>P5E_PEX3_STN5_TX_C_DP<87>P5E_PEX3_STN5_RX_DN<87>P5E_PEX3_STN5_TX_DN<87>P5E_PEX3_STN5_TX_C_DN<87>P5E_PEX3_STN5_RX_DP<86>P5E_PEX3_STN5_TX_DP<86>P5E_PEX3_STN5_TX_C_DP<86>P5E_PEX3_STN5_RX_DN<86>P5E_PEX3_STN5_TX_DN<86>P5E_PEX3_STN5_TX_C_DN<86>P5E_PEX3_STN5_RX_DP<85>P5E_PEX3_STN5_TX_DP<85>P5E_PEX3_STN5_TX_C_DP<85>P5E_PEX3_STN5_RX_DN<85>P5E_PEX3_STN5_TX_DN<85>P5E_PEX3_STN5_TX_C_DN<85>P5E_PEX3_STN5_RX_DP<84>P5E_PEX3_STN5_TX_DP<84>P5E_PEX3_STN5_TX_C_DP<84>P5E_PEX3_STN5_RX_DN<84>P5E_PEX3_STN5_TX_DN<84>P5E_PEX3_STN5_TX_C_DN<84>P5E_PEX3_STN5_RX_DP<83>P5E_PEX3_STN5_TX_DP<83>P5E_PEX3_STN5_TX_C_DP<83>P5E_PEX3_STN5_RX_DN<83>P5E_PEX3_STN5_TX_DN<83>P5E_PEX3_STN5_TX_C_DN<83>P5E_PEX3_STN5_RX_DP<82>P5E_PEX3_STN5_TX_DP<82>P5E_PEX3_STN5_TX_C_DP<82>P5E_PEX3_STN5_RX_DN<82>P5E_PEX3_STN5_TX_DN<82>P5E_PEX3_STN5_TX_C_DN<82>P5E_PEX3_STN5_RX_DP<81>P5E_PEX3_STN5_TX_DP<81>P5E_PEX3_STN5_TX_C_DP<81>P5E_PEX3_STN5_RX_DN<81>P5E_PEX3_STN5_TX_DN<81>P5E_PEX3_STN5_TX_C_DN<81>P5E_PEX3_STN5_RX_DP<80>P5E_PEX3_STN5_TX_DP<80>P5E_PEX3_STN5_TX_C_DP<80>P5E_PEX3_STN5_RX_DN<80>P5E_PEX3_STN5_TX_DN<80>P5E_PEX3_STN5_TX_C_DN<80>



5
5
4
4
3
3
2
2
1
1
D D
C C
B B
A A
PEX_3_STN_67(4/11)
P5E_PEX3_STN7_TX_C_DP<112> [159]P5E_PEX3_STN7_TX_C_DN<112> [159]P5E_PEX3_STN7_TX_C_DP<113> [159]P5E_PEX3_STN7_TX_C_DN<113> [159]P5E_PEX3_STN7_TX_C_DP<115> [160]P5E_PEX3_STN7_TX_C_DN<115> [160]P5E_PEX3_STN7_TX_C_DP<114> [160]P5E_PEX3_STN7_TX_C_DN<114> [160]P5E_PEX3_STN7_TX_C_DP<119> [162]P5E_PEX3_STN7_TX_C_DN<119> [162]P5E_PEX3_STN7_TX_C_DP<118> [162]P5E_PEX3_STN7_TX_C_DN<118> [162]P5E_PEX3_STN7_TX_C_DP<117> [161]P5E_PEX3_STN7_TX_C_DN<117> [161]P5E_PEX3_STN7_TX_C_DP<116> [161]P5E_PEX3_STN7_TX_C_DN<116> [161]P5E_PEX3_STN7_TX_C_DP<120> [159]P5E_PEX3_STN7_TX_C_DN<120> [159]P5E_PEX3_STN7_TX_C_DP<121> [159]P5E_PEX3_STN7_TX_C_DN<121> [159]P5E_PEX3_STN7_TX_C_DP<123> [160]P5E_PEX3_STN7_TX_C_DN<123> [160]P5E_PEX3_STN7_TX_C_DP<122> [160]P5E_PEX3_STN7_TX_C_DN<122> [160]P5E_PEX3_STN7_TX_C_DP<127> [162]P5E_PEX3_STN7_TX_C_DN<127> [162]P5E_PEX3_STN7_TX_C_DP<126> [162]P5E_PEX3_STN7_TX_C_DN<126> [162]P5E_PEX3_STN7_TX_C_DP<125> [161]P5E_PEX3_STN7_TX_C_DN<125> [161]P5E_PEX3_STN7_TX_C_DP<124> [161]P5E_PEX3_STN7_TX_C_DN<124> [161]P5E_PEX3_STN7_RX_DP<127>[162]P5E_PEX3_STN7_RX_DN<127>[162]P5E_PEX3_STN7_RX_DP<126>[162]P5E_PEX3_STN7_RX_DN<126>[162]P5E_PEX3_STN7_RX_DP<125>[161]P5E_PEX3_STN7_RX_DN<125>[161]P5E_PEX3_STN7_RX_DP<124>[161]P5E_PEX3_STN7_RX_DN<124>[161]P5E_PEX3_STN7_RX_DP<123>[160]P5E_PEX3_STN7_RX_DN<123>[160]P5E_PEX3_STN7_RX_DP<122>[160]P5E_PEX3_STN7_RX_DN<122>[160]P5E_PEX3_STN7_RX_DP<121>[159]P5E_PEX3_STN7_RX_DN<121>[159]P5E_PEX3_STN7_RX_DP<120>[159]P5E_PEX3_STN7_RX_DN<120>[159]P5E_PEX3_STN7_RX_DP<119>[162]P5E_PEX3_STN7_RX_DN<119>[162]P5E_PEX3_STN7_RX_DP<118>[162]P5E_PEX3_STN7_RX_DN<118>[162]P5E_PEX3_STN7_RX_DP<117>[161]P5E_PEX3_STN7_RX_DN<117>[161]P5E_PEX3_STN7_RX_DP<116>[161]P5E_PEX3_STN7_RX_DN<116>[161]P5E_PEX3_STN7_RX_DP<115>[160]P5E_PEX3_STN7_RX_DN<115>[160]P5E_PEX3_STN7_RX_DP<114>[160]P5E_PEX3_STN7_RX_DN<114>[160]P5E_PEX3_STN7_RX_DP<113>[159]P5E_PEX3_STN7_RX_DN<113>[159]P5E_PEX3_STN7_RX_DP<112>[159]P5E_PEX3_STN7_RX_DN<112>[159]
P5E_PEX3_STN6_RX_DP<111>[154]P5E_PEX3_STN6_TX_C_DP<111> [154]P5E_PEX3_STN6_RX_DN<111>[154]P5E_PEX3_STN6_TX_C_DN<111> [154]P5E_PEX3_STN6_RX_DP<110>[154]P5E_PEX3_STN6_TX_C_DP<110> [154]P5E_PEX3_STN6_RX_DN<110>[154]P5E_PEX3_STN6_TX_C_DN<110> [154]P5E_PEX3_STN6_RX_DP<109>[155]P5E_PEX3_STN6_TX_C_DP<109> [155]P5E_PEX3_STN6_RX_DN<109>[155]P5E_PEX3_STN6_TX_C_DN<109> [155]P5E_PEX3_STN6_RX_DP<108>[155]P5E_PEX3_STN6_TX_C_DP<108> [155]P5E_PEX3_STN6_RX_DN<108>[155]P5E_PEX3_STN6_TX_C_DN<108> [155]P5E_PEX3_STN6_RX_DP<107>[156]P5E_PEX3_STN6_TX_C_DP<107> [156]P5E_PEX3_STN6_RX_DN<107>[156]P5E_PEX3_STN6_TX_C_DN<107> [156]P5E_PEX3_STN6_RX_DP<106>[156]P5E_PEX3_STN6_TX_C_DP<106> [156]P5E_PEX3_STN6_RX_DN<106>[156]P5E_PEX3_STN6_TX_C_DN<106> [156]P5E_PEX3_STN6_RX_DP<105>[157]P5E_PEX3_STN6_TX_C_DP<105> [157]P5E_PEX3_STN6_RX_DN<105>[157]P5E_PEX3_STN6_TX_C_DN<105> [157]P5E_PEX3_STN6_RX_DP<104>[157]P5E_PEX3_STN6_TX_C_DP<104> [157]P5E_PEX3_STN6_RX_DN<104>[157]P5E_PEX3_STN6_TX_C_DN<104> [157]P5E_PEX3_STN6_RX_DP<103>[154]P5E_PEX3_STN6_TX_C_DP<103> [154]P5E_PEX3_STN6_RX_DN<103>[154]P5E_PEX3_STN6_TX_C_DN<103> [154]P5E_PEX3_STN6_RX_DP<102>[154]P5E_PEX3_STN6_TX_C_DP<102> [154]P5E_PEX3_STN6_RX_DN<102>[154]P5E_PEX3_STN6_TX_C_DN<102> [154]P5E_PEX3_STN6_RX_DP<101>[155]P5E_PEX3_STN6_TX_C_DP<101> [155]P5E_PEX3_STN6_RX_DN<101>[155]P5E_PEX3_STN6_TX_C_DN<101> [155]P5E_PEX3_STN6_RX_DP<100>[155]P5E_PEX3_STN6_TX_C_DP<100> [155]P5E_PEX3_STN6_RX_DN<100>[155]P5E_PEX3_STN6_TX_C_DN<100> [155]P5E_PEX3_STN6_RX_DP<99>[156]P5E_PEX3_STN6_TX_C_DP<99> [156]P5E_PEX3_STN6_RX_DN<99>[156]P5E_PEX3_STN6_TX_C_DN<99> [156]P5E_PEX3_STN6_RX_DP<98>[156]P5E_PEX3_STN6_TX_C_DP<98> [156]P5E_PEX3_STN6_RX_DN<98>[156]P5E_PEX3_STN6_TX_C_DN<98> [156]P5E_PEX3_STN6_RX_DP<97>[157]P5E_PEX3_STN6_TX_C_DP<97> [157]P5E_PEX3_STN6_RX_DN<97>[157]P5E_PEX3_STN6_TX_C_DN<97> [157]P5E_PEX3_STN6_RX_DP<96>[157]P5E_PEX3_STN6_TX_C_DP<96> [157]P5E_PEX3_STN6_RX_DN<96>[157]P5E_PEX3_STN6_TX_C_DN<96> [157]
SizeDoc NumberRevDate: SheetofReviewerDesignerDepartmentProject
Page TitleCCBU D52 257Tuesday, August 29, 2023<project_name><Designer> GRANDTETON_SWB_20230829052 PEX_3_STN_67(4/11)<Reviewer>SizeDoc NumberRevDate: SheetofReviewerDesignerDepartmentProject
Page TitleCCBU D52 257Tuesday, August 29, 2023<project_name><Designer> GRANDTETON_SWB_20230829052 PEX_3_STN_67(4/11)<Reviewer>SizeDoc NumberRevDate: SheetofReviewerDesignerDepartmentProject
Page TitleCCBU D52 257Tuesday, August 29, 2023<project_name><Designer> GRANDTETON_SWB_20230829052 PEX_3_STN_67(4/11)<Reviewer>
C777 DIFF BUS_0.22UF
C815 DIFF BUS_0.22UFC790 DIFF BUS_0.22UFC765 DIFF BUS_0.22UF
C803 DIFF BUS_0.22UFC778 DIFF BUS_0.22UF
C816 DIFF BUS_0.22UFC791 DIFF BUS_0.22UFC766 DIFF BUS_0.22UF
C804 DIFF BUS_0.22UFC779 DIFF BUS_0.22UF
C817 DIFF BUS_0.22UFC792 DIFF BUS_0.22UFC767 DIFF BUS_0.22UF7/26PEX3GSS26-0A0P-01RXP111D8RXN111C8RXP110B9RXN110A9RXP109D10RXN109C10RXP108B11RXN108A11RXP107D12RXN107C12RXP106B13RXN106A13RXP105D14RXN105C14RXP104B15RXN104A15RXP103D16RXN103C16RXP102B17RXN102A17RXP101D18RXN101C18RXP100B19RXN100A19RXP99D20RXN99C20RXP98B21RXN98A21RXP97D22RXN97C22RXP96B23RXN96A23TXP111J8TXN111H8TXP110G9TXN110F9TXP109J10TXN109H10TXP108G11TXN108F11TXP107J12TXN107H12TXP106G13TXN106F13TXP105J14TXN105H14TXP104G15TXN104F15TXP103J16TXN103H16TXP102G17TXN102F17TXP101J18TXN101H18TXP100G19TXN100F19TXP99J20TXN99H20TXP98G21TXN98F21TXP97J22TXN97H22TXP96G23TXN96F23C805 DIFF BUS_0.22UFC780 DIFF BUS_0.22UF
C818 DIFF BUS_0.22UFC793 DIFF BUS_0.22UFC768 DIFF BUS_0.22UF
C806 DIFF BUS_0.22UFC781 DIFF BUS_0.22UF
C819 DIFF BUS_0.22UFC794 DIFF BUS_0.22UFC769 DIFF BUS_0.22UF
C807 DIFF BUS_0.22UFC782 DIFF BUS_0.22UF
C820 DIFF BUS_0.22UFC795 DIFF BUS_0.22UFC770 DIFF BUS_0.22UF
C808 DIFF BUS_0.22UFC783 DIFF BUS_0.22UF
C821 DIFF BUS_0.22UFC796 DIFF BUS_0.22UFC771 DIFF BUS_0.22UF
C809 DIFF BUS_0.22UFC784 DIFF BUS_0.22UF
C822 DIFF BUS_0.22UFC797 DIFF BUS_0.22UFC772 DIFF BUS_0.22UF
C810 DIFF BUS_0.22UFC785 DIFF BUS_0.22UF
C823 DIFF BUS_0.22UFC798 DIFF BUS_0.22UFC773 DIFF BUS_0.22UF
C811 DIFF BUS_0.22UFC786 DIFF BUS_0.22UF
C824 DIFF BUS_0.22UFC799 DIFF BUS_0.22UFC774 DIFF BUS_0.22UF
C812 DIFF BUS_0.22UFC787 DIFF BUS_0.22UF
C825 DIFF BUS_0.22UF
C762 DIFF BUS_0.22UF
C800 DIFF BUS_0.22UF8/26PEX3HSS26-0A0P-01RXP127B7RXN127A7RXP126D6RXN126C6RXP125B5RXN125A5RXP124D4RXN124C4RXP123B3RXN123A3RXP122C2RXN122C1RXP121K2RXN121K1RXP120L4RXN120L3RXP119M2RXN119M1RXP118N4RXN118N3RXP117P2RXN117P1RXP116R4RXN116R3RXP115T2RXN115T1RXP114U4RXN114U3RXP113V2RXN113V1RXP112W4RXN112W3TXP127G7TXN127F7TXP126J6TXN126H6TXP125G5TXN125F5TXP124J4TXN124H4TXP123G3TXN123F3TXP122E2TXN122E1TXP121H2TXN121H1TXP120L7TXN120L6TXP119M9TXN119M8TXP118N7TXN118N6TXP117P9TXN117P8TXP116R7TXN116R6TXP115T9TXN115T8TXP114U7TXN114U6TXP113V9TXN113V8TXP112W7TXN112W6
C775 DIFF BUS_0.22UF
C813 DIFF BUS_0.22UFC788 DIFF BUS_0.22UFC763 DIFF BUS_0.22UF
C801 DIFF BUS_0.22UFC776 DIFF BUS_0.22UF
C814 DIFF BUS_0.22UFC789 DIFF BUS_0.22UFC764 DIFF BUS_0.22UF
C802 DIFF BUS_0.22UFP5E_PEX3_STN7_TX_DP<112>P5E_PEX3_STN7_TX_C_DP<112>P5E_PEX3_STN7_TX_DN<112>P5E_PEX3_STN7_TX_C_DN<112>P5E_PEX3_STN7_TX_DP<113>P5E_PEX3_STN7_TX_DN<113>P5E_PEX3_STN7_TX_DP<115>P5E_PEX3_STN7_TX_DN<115>P5E_PEX3_STN7_TX_DP<114>P5E_PEX3_STN7_TX_DN<114>P5E_PEX3_STN7_TX_DP<119>P5E_PEX3_STN7_TX_DN<119>P5E_PEX3_STN7_TX_DP<118>P5E_PEX3_STN7_TX_DN<118>P5E_PEX3_STN7_TX_DP<117>P5E_PEX3_STN7_TX_DN<117>P5E_PEX3_STN7_TX_DP<116>P5E_PEX3_STN7_TX_DN<116>P5E_PEX3_STN7_TX_C_DP<113>P5E_PEX3_STN7_TX_C_DN<113>P5E_PEX3_STN7_TX_C_DP<115>P5E_PEX3_STN7_TX_C_DN<115>P5E_PEX3_STN7_TX_C_DP<114>P5E_PEX3_STN7_TX_C_DN<114>P5E_PEX3_STN7_TX_C_DP<119>P5E_PEX3_STN7_TX_C_DN<119>P5E_PEX3_STN7_TX_C_DP<118>P5E_PEX3_STN7_TX_C_DN<118>P5E_PEX3_STN7_TX_C_DP<117>P5E_PEX3_STN7_TX_C_DN<117P5E_PEX3_STN7_TX_C_DP<116>P5E_PEX3_STN7_TX_C_DN<116>P5E_PEX3_STN7_TX_DP<120>P5E_PEX3_STN7_TX_DN<120>P5E_PEX3_STN7_TX_DP<121>P5E_PEX3_STN7_TX_DN<121>P5E_PEX3_STN7_TX_DP<122>P5E_PEX3_STN7_TX_DN<122>P5E_PEX3_STN7_TX_DP<123>P5E_PEX3_STN7_TX_DN<123>P5E_PEX3_STN7_TX_DP<124>P5E_PEX3_STN7_TX_DN<124>P5E_PEX3_STN7_TX_DP<125>P5E_PEX3_STN7_TX_DN<125>P5E_PEX3_STN7_TX_DP<126>P5E_PEX3_STN7_TX_DN<126>P5E_PEX3_STN7_TX_DP<127>P5E_PEX3_STN7_TX_DN<127>P5E_PEX3_STN7_TX_C_DP<120>P5E_PEX3_STN7_TX_C_DN<120>P5E_PEX3_STN7_TX_C_DP<121>P5E_PEX3_STN7_TX_C_DN<121>P5E_PEX3_STN7_TX_C_DP<123>P5E_PEX3_STN7_TX_C_DN<123>P5E_PEX3_STN7_TX_C_DP<122>P5E_PEX3_STN7_TX_C_DN<122>P5E_PEX3_STN7_TX_C_DP<127>P5E_PEX3_STN7_TX_C_DN<127>P5E_PEX3_STN7_TX_C_DP<126>P5E_PEX3_STN7_TX_C_DN<126>P5E_PEX3_STN7_TX_C_DP<125>P5E_PEX3_STN7_TX_C_DN<125>P5E_PEX3_STN7_TX_C_DP<124>P5E_PEX3_STN7_TX_C_DN<124>P5E_PEX3_STN7_RX_DP<127>P5E_PEX3_STN7_RX_DN<127>P5E_PEX3_STN7_RX_DP<126>P5E_PEX3_STN7_RX_DN<126>P5E_PEX3_STN7_RX_DP<125>P5E_PEX3_STN7_RX_DN<125>P5E_PEX3_STN7_RX_DP<124>P5E_PEX3_STN7_RX_DN<124>P5E_PEX3_STN7_RX_DP<123>P5E_PEX3_STN7_RX_DN<123>P5E_PEX3_STN7_RX_DP<122>P5E_PEX3_STN7_RX_DN<122>P5E_PEX3_STN7_RX_DP<121>P5E_PEX3_STN7_RX_DN<121>P5E_PEX3_STN7_RX_DP<120>P5E_PEX3_STN7_RX_DN<120>P5E_PEX3_STN7_RX_DP<119>P5E_PEX3_STN7_RX_DN<119>P5E_PEX3_STN7_RX_DP<118>P5E_PEX3_STN7_RX_DN<118>P5E_PEX3_STN7_RX_DP<117>P5E_PEX3_STN7_RX_DN<117>P5E_PEX3_STN7_RX_DP<116>P5E_PEX3_STN7_RX_DN<116>P5E_PEX3_STN7_RX_DP<115>P5E_PEX3_STN7_RX_DN<115>P5E_PEX3_STN7_RX_DP<114>P5E_PEX3_STN7_RX_DN<114>P5E_PEX3_STN7_RX_DP<113>P5E_PEX3_STN7_RX_DN<113>P5E_PEX3_STN7_RX_DP<112>P5E_PEX3_STN7_RX_DN<112>
P5E_PEX3_STN6_RX_DP<111>P5E_PEX3_STN6_TX_DP<111>P5E_PEX3_STN6_TX_C_DP<111>P5E_PEX3_STN6_RX_DN<111>P5E_PEX3_STN6_TX_DN<111>P5E_PEX3_STN6_TX_C_DN<111>P5E_PEX3_STN6_RX_DP<110>P5E_PEX3_STN6_TX_DP<110>P5E_PEX3_STN6_TX_C_DP<110>P5E_PEX3_STN6_RX_DN<110>P5E_PEX3_STN6_TX_DN<110>P5E_PEX3_STN6_TX_C_DN<110>P5E_PEX3_STN6_RX_DP<109>P5E_PEX3_STN6_TX_DP<109>P5E_PEX3_STN6_TX_C_DP<109>P5E_PEX3_STN6_RX_DN<109>P5E_PEX3_STN6_TX_DN<109>P5E_PEX3_STN6_TX_C_DN<109>P5E_PEX3_STN6_RX_DP<108>P5E_PEX3_STN6_TX_DP<108>P5E_PEX3_STN6_TX_C_DP<108>P5E_PEX3_STN6_RX_DN<108>P5E_PEX3_STN6_TX_DN<108>P5E_PEX3_STN6_TX_C_DN<108>P5E_PEX3_STN6_RX_DP<107>P5E_PEX3_STN6_TX_DP<107>P5E_PEX3_STN6_TX_C_DP<107>P5E_PEX3_STN6_RX_DN<107>P5E_PEX3_STN6_TX_DN<107>P5E_PEX3_STN6_TX_C_DN<107>P5E_PEX3_STN6_RX_DP<106>P5E_PEX3_STN6_TX_DP<106>P5E_PEX3_STN6_TX_C_DP<106>P5E_PEX3_STN6_RX_DN<106>P5E_PEX3_STN6_TX_DN<106>P5E_PEX3_STN6_TX_C_DN<106>P5E_PEX3_STN6_RX_DP<105>P5E_PEX3_STN6_TX_DP<105>P5E_PEX3_STN6_TX_C_DP<105>P5E_PEX3_STN6_RX_DN<105>P5E_PEX3_STN6_TX_DN<105>P5E_PEX3_STN6_TX_C_DN<105>P5E_PEX3_STN6_RX_DP<104>P5E_PEX3_STN6_TX_DP<104>P5E_PEX3_STN6_TX_C_DP<104>P5E_PEX3_STN6_RX_DN<104>P5E_PEX3_STN6_TX_DN<104>P5E_PEX3_STN6_TX_C_DN<104>P5E_PEX3_STN6_RX_DP<103>P5E_PEX3_STN6_TX_DP<103>P5E_PEX3_STN6_TX_C_DP<103>P5E_PEX3_STN6_RX_DN<103>P5E_PEX3_STN6_TX_DN<103>P5E_PEX3_STN6_TX_C_DN<103>P5E_PEX3_STN6_RX_DP<102>P5E_PEX3_STN6_TX_DP<102>P5E_PEX3_STN6_TX_C_DP<102>P5E_PEX3_STN6_RX_DN<102>P5E_PEX3_STN6_TX_DN<102>P5E_PEX3_STN6_TX_C_DN<102>P5E_PEX3_STN6_RX_DP<101>P5E_PEX3_STN6_TX_DP<101>P5E_PEX3_STN6_TX_C_DP<101>P5E_PEX3_STN6_RX_DN<101>P5E_PEX3_STN6_TX_DN<101>P5E_PEX3_STN6_TX_C_DN<101>P5E_PEX3_STN6_RX_DP<100>P5E_PEX3_STN6_TX_DP<100>P5E_PEX3_STN6_TX_C_DP<100>P5E_PEX3_STN6_RX_DN<100>P5E_PEX3_STN6_TX_DN<100>P5E_PEX3_STN6_TX_C_DN<100>P5E_PEX3_STN6_RX_DP<99>P5E_PEX3_STN6_TX_DP<99>P5E_PEX3_STN6_TX_C_DP<99>P5E_PEX3_STN6_RX_DN<99>P5E_PEX3_STN6_TX_DN<99>P5E_PEX3_STN6_TX_C_DN<99>P5E_PEX3_STN6_RX_DP<98>P5E_PEX3_STN6_TX_DP<98>P5E_PEX3_STN6_TX_C_DP<98>P5E_PEX3_STN6_RX_DN<98>P5E_PEX3_STN6_TX_DN<98>P5E_PEX3_STN6_TX_C_DN<98>P5E_PEX3_STN6_RX_DP<97>P5E_PEX3_STN6_TX_DP<97>P5E_PEX3_STN6_TX_C_DP<97>P5E_PEX3_STN6_RX_DN<97>P5E_PEX3_STN6_TX_DN<97>P5E_PEX3_STN6_TX_C_DN<97>P5E_PEX3_STN6_RX_DP<96>P5E_PEX3_STN6_TX_DP<96>P5E_PEX3_STN6_TX_C_DP<96>P5E_PEX3_STN6_RX_DN<96>P5E_PEX3_STN6_TX_DN<96>P5E_PEX3_STN6_TX_C_DN<96>



5
5
4
4
3
3
2
2
1
1
D D
C C
B B
A A
PEX_3_STN_8(5/11)
CLK_100M_DB2000QL_PEX3_S1_R_DP [79]CLK_100M_DB2000QL_PEX3_S1_R_DN [79]CLK_100M_DB800ZL_PEX3_S0_R_DP [83]CLK_100M_DB800ZL_PEX3_S0_R_DN [83]CLK_100M_PEX3_REF_R_DP[82]CLK_100M_PEX3_REF_R_DN[82]RST_PEX3_PERST_R_N[118]RST_PEX3_S3_PERST_R_N [53]RST_PEX3_S1_PERST_R_N [53]RST_PEX3_S0_PERST_R_N [53]RST_PEX3_S0_PERST_R_N[53]RST_PEX3_S1_PERST_R_N[53]RST_PEX3_S3_PERST_R_N[53]CLK_100M_DB800ZL_PEX3_S3_R_DP [84]CLK_100M_DB800ZL_PEX3_S3_R_DN [84]P1V8_PEXP1V8_PEXSizeDoc NumberRevDate: SheetofReviewerDesignerDepartmentProject
Page TitleCCBU D53 257Tuesday, August 29, 2023<project_name><Designer> GRANDTETON_SWB_20230829053 PEX_3_STN_8(5/11)<Reviewer>SizeDoc NumberRevDate: SheetofReviewerDesignerDepartmentProject
Page TitleCCBU D53 257Tuesday, August 29, 2023<project_name><Designer> GRANDTETON_SWB_20230829053 PEX_3_STN_8(5/11)<Reviewer>SizeDoc NumberRevDate: SheetofReviewerDesignerDepartmentProject
Page TitleCCBU D53 257Tuesday, August 29, 2023<project_name><Designer> GRANDTETON_SWB_20230829053 PEX_3_STN_8(5/11)<Reviewer>U428ASN74LVC3G34DCTR178410/26PEX3JSS26-0A0P-01S7_PCE_PERST_NU38S6_PCE_PERST_NR38S5_PCE_PERST_NU39S4_PCE_PERST_NR39S3_PCE_PERST_NP38S2_PCE_PERST_NT39S1_PCE_PERST_NP39S0_PCE_PERST_NT38SYS_REF_CLK_PAA2SYS_REF_CLK_NAA1S7_PCE_REF_CLK_PAJ2S7_PCE_REF_CLK_NAJ1S6_PCE_REF_CLK_PAH5S6_PCE_REF_CLK_NAH4S5_PCE_REF_CLK_PAG2S5_PCE_REF_CLK_NAG1S4_PCE_REF_CLK_PAF5S4_PCE_REF_CLK_NAF4S3_PCE_REF_CLK_PAE2S3_PCE_REF_CLK_NAE1S2_PCE_REF_CLK_PAD5S2_PCE_REF_CLK_NAD4S1_PCE_REF_CLK_PAC2S1_PCE_REF_CLK_NAC1S0_PCE_REF_CLK_PAB5S0_PCE_REF_CLK_NAB4CLKREQ_INIT_NM13U428CSN74LVC3G34DCTR6284R6398 33 R0402-0201R436310K1% R0402-0201<Part Number>NIR6401 33 R0402-0201
9/26PEX3ISS26-0A0P-01RXP143AM48RXN143AM49RXP142AL46RXN142AL47RXP141AK48RXN141AK49RXP140AJ46RXN140AJ47RXP139AH48RXN139AH49RXP138AG46RXN138AG47RXP137AF48RXN137AF49RXP136AE46RXN136AE47RXP135AD48RXN135AD49RXP134AC46RXN134AC47RXP133AB48RXN133AB49RXP132AA46RXN132AA47RXP131Y48RXN131Y49RXP130W46RXN130W47RXP129V48RXN129V49RXP128U46RXN128U47TXP143AM41TXN143AM42TXP142AL43TXN142AL44TXP141AK41TXN141AK42TXP140AJ43TXN140AJ44TXP139AH41TXN139AH42TXP138AG43TXN138AG44TXP137AF41TXN137AF42TXP136AE43TXN136AE44TXP135AD41TXN135AD42TXP134AC43TXN134AC44TXP133AB41TXN133AB42TXP132AA43TXN132AA44TXP131Y41TXN131Y42TXP130W43TXN130W44TXP129V41TXN129V42TXP128U43TXN128U44
R63994.7KR0402-02015%U428BSN74LVC3G34DCTR3584R6400 33 R0402-0201C41880.1UF10%16VC0402-0201CLK_100M_DB2000QL_PEX3_S1_R_DPCLK_100M_DB2000QL_PEX3_S1_R_DNCLK_100M_DB800ZL_PEX3_S0_R_DPCLK_100M_DB800ZL_PEX3_S0_R_DNCLK_100M_PEX3_REF_R_DPCLK_100M_PEX3_REF_R_DNIRQ_PEX3_CLKREQ_INT_NRST_PEX3_PERST_R_NRST_PEX3_S3_PERST_NRST_PEX3_S3_PERST_R_NRST_PEX3_S1_PERST_NRST_PEX3_S1_PERST_R_NRST_PEX3_S0_PERST_NRST_PEX3_S0_PERST_R_NRST_PEX3_S0_PERST_R_NRST_PEX3_S1_PERST_R_NRST_PEX3_S3_PERST_R_NCLK_100M_DB800ZL_PEX3_S3_R_DPCLK_100M_DB800ZL_PEX3_S3_R_DN



5
5
4
4
3
3
2
2
1
1
D D
C C
B B
A A
Add Test Point
PEX_3_GPIO(6/11)
DVT_CHANGEPEX3_DBG_MODE4 [54]PEX3_DBG_MODE3 [54]PEX3_MODE_SEL12 [54]PEX3_DBG_MODE2 [54]PEX3_MODE_SEL11 [54]PEX3_DBG_MODE1 [54]PEX3_MODE_SEL10 [54]PEX3_DBG_MODE0 [54]PEX3_MODE_SEL9 [54]PEX3_DBG_SEL1 [54]PEX3_MODE_SEL8 [54]PEX3_DBG_SEL0 [54]PEX3_MODE_SEL7 [54]PEX3_MODE_SEL6 [54]PEX3_MODE_SEL5 [54]PEX3_MODE_SEL4 [54]PEX3_MODE_SEL3 [54]PEX3_MODE_SEL2 [54,121]PEX3_MODE_SEL1 [54,121]PEX3_MODE_SEL0 [54]PEX3_DBG_MODE4[54]PEX3_DBG_MODE3[54]PEX3_DBG_MODE2[54]PEX3_DBG_MODE1[54]PEX3_DBG_MODE0[54]PEX3_DBG_SEL1[54]PEX3_DBG_SEL0[54]PEX3_MODE_SEL12[54]PEX3_MODE_SEL11[54]PEX3_MODE_SEL10[54]PEX3_MODE_SEL9[54]PEX3_MODE_SEL8[54]PEX3_MODE_SEL7[54]PEX3_MODE_SEL6[54]PEX3_MODE_SEL5[54]PEX3_MODE_SEL4[54]PEX3_MODE_SEL3[54]PEX3_MODE_SEL2[54,121]PEX3_MODE_SEL1[54,121]PEX3_MODE_SEL0[54]PEX3_SYS_ERR_R_N [54]RST_PEX3_SYS_N [118]UART_PEX3_SDB_TX [67]UART_PEX3_SDB_BUF_RX [67]UART_PEX3_CLI_TX [68]UART_PEX3_CLI_BUF_RX [68]PEX3_SYS_ERR_R_N[54]PEX3_PCA9555_INT_R_N [75]PEX3_SYS_ERR_FPGA [118]
P1V8_PEXP1V8_PEXP1V8_PEXP1V8_PEXP3V3_AUXP1V8_PEX
P1V8_PEXP3V3_LEDP1V8_PEXSizeDoc NumberRevDate: SheetofReviewerDesignerDepartmentProject
Page TitleCCBU D54 257Tuesday, August 29, 2023<project_name><Designer> GRANDTETON_SWB_20230829054 PEX_3_GPIO(6/11)<Reviewer>SizeDoc NumberRevDate: SheetofReviewerDesignerDepartmentProject
Page TitleCCBU D54 257Tuesday, August 29, 2023<project_name><Designer> GRANDTETON_SWB_20230829054 PEX_3_GPIO(6/11)<Reviewer>SizeDoc NumberRevDate: SheetofReviewerDesignerDepartmentProject
Page TitleCCBU D54 257Tuesday, August 29, 2023<project_name><Designer> GRANDTETON_SWB_20230829054 PEX_3_GPIO(6/11)<Reviewer>R1461 4.75K R0402-02011%
R14141KR0402-02011%R14381KR0402-02011%NIR145210KR0402-02015%R14051KR0402-02011%NIR14221KR0402-02011%R14321KR0402-02011%R1459 10K R0402-02015%R61564.7KR0402-02011%  
R14151KR0402-02011%NIR14231KR0402-02011%R14391KR0402-02011%NIR145310KR0402-02015%R14061KR0402-02011%R396510KR0402-02015%R14331KR0402-02011%R145410KR0402-02015%R14161KR0402-02011%R14241KR0402-02011%R14401KR0402-02011%NIR14071KR0402-02011%R14341KR0402-02011%NIR1462 4.75K R0402-02011%
R13981KR0402-02011%NI11/26PEX3KSS26-0A0P-01DBG_MODE4AW34DBG_MODE3AW26DBG_MODE2AW30DBG_MODE1L13DBG_MODE0L12DBG_SEL1M19DBG_SEL0L18MODE_SEL12AW32MODE_SEL11AW31MODE_SEL10AV32MODE_SEL9AV28MODE_SEL8AW29MODE_SEL7AV26MODE_SEL6AV31MODE_SEL5AW25MODE_SEL4AW28MODE_SEL3AV27MODE_SEL2AV25MODE_SEL1AW38MODE_SEL0AW27AVG_TRST_LM18AVG_TCKM15AVG_TDIL17AVG_TDOL19AVG_TMSM20AVG_PAD_TRI_LL16AVG_TR_TCKL20AVG_ATPG_MODE_LL15SHPC_INT_NAV29SPARE7M27SPARE6L28SPARE5L25SPARE4M25SPARE3L32SPARE2L27SPARE1L30SPARE0M26DFT_IDDTM16ADCTEMP_VINP0Y39ADCTEMP_VINP1AA39SYS_ERROR_NAV30SYS_PWR_ON_RST_NM17SDB_TXAL39SDB_RXAK39UART_TXAJ38UART_RXAK38R145510KR0402-02015%R146349.9<Part Number>R0402-02011%1/16W
R14171KR0402-02011%NIR14411KR0402-02011%NIR14081KR0402-02011%NIR14351KR0402-02011%R14251KR0402-02011%R13991KR0402-02011%NI R145610KR0402-02015%NIR14421KR0402-02011%NIR14361KR0402-02011%NIR14091KR0402-02011%NIR14261KR0402-02011%NI
D4LED_BLUEAC
R14001KR0402-02011% R145710KR0402-02015%NIR5802 33 R0402-02011%
R14431KR0402-02011%NIR14101KR0402-02011%NIR14271KR0402-02011%NIR14371KR0402-02011%R14011KR0402-02011%NIR14181KR0402-02011%R144710K 1%R0402-0201R1458 0 R0402-02015%R14441KR0402-02011%NIR14281KR0402-02011%
R14644.7KR0402-02011%  
R14111KR0402-02011%NIR14021KR0402-02011%NIR14191KR0402-02011%R144910KR0402-02015%R14291KR0402-02011%R144810K 1%R0402-0201<Part Number>R14451KR0402-02011%R14121KR0402-02011%NI
R1460 10K R0402-02015%Q20BBSS138BKS<Part Number>D23G25S24R418310KR0402-02015%NI
R14201KR0402-02011%NIR14031KR0402-02011%NI R145010KR0402-02015%R14301KR0402-02011%R14461KR0402-02011%R14131KR0402-02011%NI
R4184 1K R0402-02011%NI
R14041KR0402-02011%NIR14211KR0402-02011%R145110KR0402-02015%12/26PEX3LSS26-0A0P-01GPIO31AV13GPIO30AV12GPIO29AW12GPIO28AW16GPIO27AV17GPIO26AV16GPIO25AW13GPIO24AW17GPIO23AV14GPIO21AW14GPIO20AW18GPIO19AV19GPIO18AV15GPIO17AW15GPIO16AW19GPIO15AV36GPIO14AU39GPIO13AW35GPIO12AJ39GPIO11AN39GPIO10AM38GPIO9AR39GPIO8AP39GPIO7AR38GPIO6AP38GPIO5AM39GPIO4AU38GPIO3AV39GPIO2AT39GPIO1AV34GPIO0AW39GPIO63M24GPIO62L23GPIO61M23GPIO60M22GPIO59L22GPIO58L24GPIO57AV23GPIO56AW22GPIO55AV22GPIO54AV21GPIO53M32GPIO52L31GPIO51M34GPIO50N39GPIO49L29GPIO48M33GPIO47AW21GPIO46AW23GPIO45L33GPIO44M31GPIO43M30GPIO42L35GPIO41AN38GPIO40AL38GPIO39AW37GPIO38AV37GPIO37AV38GPIO36AV35GPIO35AW36GPIO34AV33GPIO33AT38GPIO32AW33EXT_GPIO_LATCH_NL37GPIO22AV18
R14311KR0402-02011%
Q20ABSS138BKS<Part Number>S11G12D16
PEX3_DBG_MODE4PEX3_DBG_MODE3PEX3_MODE_SEL12PEX3_DBG_MODE2PEX3_MODE_SEL11PEX3_DBG_MODE1PEX3_MODE_SEL10PEX3_DBG_MODE0PEX3_MODE_SEL9PEX3_DBG_SEL1PEX3_MODE_SEL8PEX3_DBG_SEL0PEX3_MODE_SEL7PEX3_MODE_SEL6PEX3_MODE_SEL5PEX3_MODE_SEL4PEX3_MODE_SEL3PEX3_MODE_SEL2PEX3_MODE_SEL1PEX3_MODE_SEL0PEX3_DBG_MODE4PEX3_DBG_MODE3PEX3_DBG_MODE2PEX3_DBG_MODE1PEX3_DBG_MODE0PEX3_SPARE7PEX3_DBG_SEL1PEX3_SPARE6PEX3_DBG_SEL0PEX3_SPARE5PEX3_SPARE4PEX3_MODE_SEL12PEX3_SPARE3PEX3_MODE_SEL11PEX3_SPARE2PEX3_MODE_SEL10PEX3_SPARE1PEX3_MODE_SEL9PEX3_SPARE0PEX3_MODE_SEL8PEX3_MODE_SEL7PEX3_DFT_IDDTPEX3_MODE_SEL6PEX3_MODE_SEL5PEX3_MODE_SEL4PEX3_MODE_SEL3PEX3_MODE_SEL2PEX3_MODE_SEL1PEX3_MODE_SEL0PEX3_SYS_ERR_NRST_PEX3_SYS_NTP_PEX3_TRST_LTP_PEX3_TCKTP_PEX3_TDIUART_PEX3_SDB_TXTP_PEX3_TDOUART_PEX3_SDB_BUF_RXTP_PEX3_TMSPU_PEX3_PAD_TRI_LUART_PEX3_CLI_TXPU_PEX3_TR_TCKUART_PEX3_CLI_BUF_RXPU_PEX3_ATPG_MODE_LPEX3_ADCTEMP_VINP0PEX3_ADCTEMP_VINP1PEX3_SYS_ERR_3V3_NLED_PEX3_SYS_ERR_NPEX3_SYS_ERR_N_GPEX3_EXT_GPIO_LATCH_N



5
5
4
4
3
3
2
2
1
1
D D
C C
B B
A A
FLASH SOCKET
PEX VER. A0
PCA9555 3.3V Port
Pull UP 3V3
PEX 1.8V Port
To FPGA
PEX VER. B0
CO-LAYOUT
PEX_3_FLASH(7/11)
SEL_FLASH_PEX3_BUF_R[63,88]SPI_PEX3_CS_MUX_N[55]SPI_PEX3_CLK_MUX[55]SPI_PEX3_CLK_R [55]SPI_BIC1_CLK_LS23_R2 [63]SPI_PEX3_CS_R_N [55]SPI_BIC1_CS0_LS23_R2_N [63]SPI_PEX3_CS_MUX_N[55]SPI_PEX3_CLK_MUX[55]SPI_BIC1_MISO_LS23_R2 [63]SPI_BIC1_MOSI_LS23_R2 [63]SPI_PEX3_SDIO1_MUX[55]SPI_PEX3_SDIO0_MUX[55]SPI_PEX3_SDIO0_MUX[55]SPI_PEX3_SDIO1_MUX [55]SPI_PEX3_SDIO1_R [55]SPI_PEX3_SDIO0_R [55]SPI_PEX3_SDIO2_R[55]SPI_PEX3_SDIO3_R[55]
I2C_PEX3_HOST_R_SDA [55]I2C_PEX3_HOST_R_SCL [55]SMB_PEX3_SDA [95]SMB_PEX3_SCL [95]
SMB_PEX3_PCA9555_SCL[75]I2C_PEX3_HOST_R_SCL [55]SMB_PEX3_PCA9555_SDA[75]I2C_PEX3_HOST_R_SDA [55]PWRGD_P1V8_PEX_R[16,29,42,95,118,233]SMB_PEX3_FPGA_SCL[115]SMB_PEX3_FPGA_SDA[115]
SPI_PEX3_CS_R_N[55]SPI_PEX3_CLK_R[55]SPI_PEX3_SDIO3_R[55]SPI_PEX3_SDIO2_R[55]SPI_PEX3_SDIO1_R[55]SPI_PEX3_SDIO0_R[55]SPI_PEX3_RST_R_N[55]SPI_PEX3_RST_R_N [55]P3V3_AUX
P1V8_PEXP1V8_PEXP3V3_AUXP1V8_PEX
P1V8_PEXP1V8_PEXP1V8_PEX
SizeDoc NumberRevDate: SheetofReviewerDesignerDepartmentProject
Page TitleCCBU D55 257Tuesday, August 29, 2023<project_name><Designer> GRANDTETON_SWB_20230829055 PEX_3_FLASH(7/11)<Reviewer>SizeDoc NumberRevDate: SheetofReviewerDesignerDepartmentProject
Page TitleCCBU D55 257Tuesday, August 29, 2023<project_name><Designer> GRANDTETON_SWB_20230829055 PEX_3_FLASH(7/11)<Reviewer>SizeDoc NumberRevDate: SheetofReviewerDesignerDepartmentProject
Page TitleCCBU D55 257Tuesday, August 29, 2023<project_name><Designer> GRANDTETON_SWB_20230829055 PEX_3_FLASH(7/11)<Reviewer>
R3992 0 R0402-02015%
R61734.75K1%R0402-0201<Part Number>R4007 0 R0402-02015%NIR35061K<Part Number>R0402-02011%NIU316PCA9617ADP<Part Number>EN5VCCA1VCCB8SCLA2SDAA3SDAB6SCLB7GND4
R6812 33 R0402-02011%R6721 33 R0402-02011%R3492 0 R0402-02015%
R3503 0 R0402-02015%U321W25Q256JWFIQNI<Part Number>HOLD#||RESET_IO3#1VCC2RESET#3NC14NC25NC36CS#7DO_IO18CLK16DI_IO015NC714NC613NC512NC411GND10WP_N_IO29R3497 4.7K R0402-02011%R6722 0 R0402-02015%
R4003 0 R0402-02015%
R3993 33 R0402-02011%
R35071K<Part Number>R0402-02011%NI
R3493 0 R0402-02015%JPEX3SCONN16_ACASPI006P07<Part Number>VCC2HOLD_N1CS_N7WP_N9SI15SCK16VSS10SO8NC3PO24PO15PO06PO311PO412PO513PO614R39974.7KR0402-02015%R4001 33 R0402-02011%
R3994 0 R0402-02015%R3499 0 R0402-02015%R3500 0 R0402-02015%
13/26PEX3MSS26-0A0P-01SPI0_CS_N1AJ8SPI0_CS_N0AK7SPI0_FLASH_CS_NAJ7SPI0_RST_NAG7SPI0_CLKAH7SPI0_SDIO3AH8SPI0_SDIO2AG8SPI0_SDIO1AF8SPI0_SDIO0AF7SPI1_CS_N1AB7SPI1_CS_N0AB8SPI1_RST_NAD7SPI1_CLKAE7SPI1_SDIO3AE8SPI1_SDIO2AC8SPI1_SDIO1AD8SPI1_SDIO0AC7SIO_BLINKL26I2C0_SDAM39I2C0_SCLM35I2C1_SDAM37I2C1_SCLL38I2C2_SDAL36I2C2_SCLM36I2C3_SDAM38I2C3_SCLL34I2C_S_SDAL39I2C_S_SCLN38SHPC_SDAM28SHPC_SCLM29
R39984.7KR0402-02015%
R3989 0 R0402-02015%NIR3494 0 R0402-02015%
R4004 33 R0402-02011%
R3491 0 R0402-02015%
C27600.1UF10%16VC0402-0201
R3995 0 R0402-02015%R3990 0 R0402-02015%R61601KR0402-02011%
R3498 0 R0402-02015%C27610.1UF10%16VC0402-0201R40192K1/16W1%R0402-0201JPEX3_FW1<Part Number>1R4005 0 R0402-02015%C25040.1UF10%16VC0402-0201R3501 0 R0402-02015%R3996 0 R0402-02015%R3489 0 R0402-02015%14/26PEX3NSS26-0A0P-01MXSTEST_0_TST1AN36MXSTEST_0_TST0AP36MXSTEST_1_TST1AT36MXSTEST_1_TST0AR36MXSTEST_2_TST1AP14MXSTEST_2_TST0AN14MXSTEST_3_TST1U36MXSTEST_3_TST0P36MXSTEST_4_TST1T36MXSTEST_4_TST0R36MXSTEST_5_TST1T14MXSTEST_5_TST0U14MXSTEST_6_TST1AA35MXSTEST_6_TST0AB35CLKOBSAK5CLKOBS_NAK4C25030.1UF10%16VC0402-0201R394610K1% R0402-0201<Part Number>
R61721KR0402-02011%NI<Part Number>R40202K1/16W1%<Part Number>R0402-0201
R3991 0 R0402-02015%NI
R4002 0 R0402-02015%R35041K<Part Number>R0402-02011%R3502 0 R0402-02015%R4006 0 R0402-02015%NI
U68PI3CH480QEXS1E#15YA4YB7D113YC9YD12D014C110C011B16B05A13A02VCC16GND8C27840.1UF10%16VC0402-0201R6171 0 R0402-02015%R6811 33 R0402-02011%R3490 0 R0402-02015%
R35051K<Part Number>R0402-02011%
SPI_PEX3_CS_MUX_NSPI_PEX3_SDIO1_MUXSPI_PEX3_SDIO1_RSPI_BIC1_MISO_LS23_R2SPI_PEX3_CS_R_NSPI_BIC1_CS0_LS23_R2_NSEL_FLASH_PEX3_BUF_RSPI_PEX3_SDIO0_MUXSPI_PEX3_CLK_MUXSPI_PEX3_SDIO0_RSPI_BIC1_MOSI_LS23_R2SPI_PEX3_CLK_RSPI_BIC1_CLK_LS23_R2SPI_MUX_PEX3_EN_NSPI_PEX3_SDIO1_MUX_RSPI_PEX3_SDIO1_MUXSPI_PEX3_SDIO3_RSPI_PEX3_SDIO3_R1SPI_PEX3_CS_MUX_NSPI_PEX3_CS_MUX_R_NSPI_PEX3_SDIO2_RSPI_PEX3_SDIO2_R1SPI_PEX3_SDIO0_MUXSPI_PEX3_SDIO0_MUX_RSPI_PEX3_CLK_MUXSPI_PEX3_CLK_MUX_RSPI_PEX3_CS_MUX_R_NSPI_PEX3_SDIO3_R1SPI_PEX3_SDIO2_R1
I2C0_PEX3_SDAI2C_PEX3_HOST_SDAI2C0_PEX3_SCLI2C_PEX3_HOST_SCLSMB_PEX3_SLAVE_SDASMB_PEX3_SLAVE_SCLI2C0_PEX3_SHPC_SDAI2C0_PEX3_SHPC_SCL
SMB_PEX3_HOST_LS_SCLSMB_PEX3_HOST_LS_SDAPWRGD_P1V8_PEX3_R
SPI_PEX3_CS_R_NSPI_PEX3_CS_NSPI_PEX3_CLK_RSPI_PEX3_CLKSPI_PEX3_SDIO3_RSPI_PEX3_SDIO3SPI_PEX3_SDIO2_RSPI_PEX3_SDIO2SPI_PEX3_SDIO1_RSPI_PEX3_SDIO1SPI_PEX3_SDIO0_RSPI_PEX3_SDIO0PU_PEX3_SIO_BLINKSPI_PEX3_CLK_MUX_RSPI_PEX3_CS_MUX_R_NSPI_PEX3_SDIO3_R1SPI_PEX3_SDIO2_R1SPI_PEX3_SDIO1_MUX_RSPI_PEX3_SDIO0_MUX_R
SPI_PEX3_RST_R_NSPI_PEX3_RST_N
SPI_PEX3_RST_R_NSPI_PEX3_RST_R_NSPI_PEX3_RST_R_N
SMB_PEX3_SLAVE1_SDASMB_PEX3_SLAVE1_SCLSMB_PEX3_R_SDASMB_PEX3_R_SCL



5
5
4
4
3
3
2
2
1
1
D D
C C
B B
A A
PEX0 P1V25_SERDES_VDDHTXDECOUPLING INFO.
Item QTY.
BGA BALLs 41
1000pF(0201) Caps
0.1uF(0201) Caps
1uF(0201) Caps
10uF(0603) Caps
11
25
5
2
PEX0 P1V25_SERDES_VDDHPLLDECOUPLING INFO.
Item QTY.
41BGA BALLs
1000pF(0201) Caps 11
0.1uF(0201) Caps 25
1uF(0201) Caps 5
10uF(0603) Caps 2
1
1
8
4
QTY.
13
PEX0 P1V8_SWDECOUPLING INFO.
10uF(0603) Caps
1uF(0201) Caps
0.1uF(0201) Caps
1000pF(0201) Caps
BGA BALLs
Item
1
1
8
4
QTY.
9
PEX0 P1V8_VDDADECOUPLING INFO.
10uF(0603) Caps
1uF(0201) Caps
0.1uF(0201) Caps
1000pF(0201) Caps
BGA BALLs
Item
Add Test Point
PEX_3_PWR_Cap_1(8/11)
VSENSE_P0V8_PEX3_SKT_VRTN[226]VSENSE_P0V8_PEX3_SKT_VSEN[226]
P1V25_PEX3P1V25_SERDES_VDDPLL_PEX3P1V8_VDDA_PEX3P0V8_PEX3P0V8_PEX3P1V25_PEX3P1V25_SERDES_VDDPLL_PEX3
P0V8_SERDES_VDDA_PEX3P0V8_SERDES_VDDA_PEX3P1V8_PEXP1V8_VDDA_PEX3P1V8_PEXPCEPLL7_VDDA18_PEX3PCEPLL6_VDDA18_PEX3PCEPLL5_VDDA18_PEX3PCEPLL4_VDDA18_PEX3PCEPLL3_VDDA18_PEX3PCEPLL2_VDDA18_PEX3PCEPLL1_VDDA18_PEX3PCEPLL0_VDDA18_PEX3SYSPLL_VDDA18_PEX3
SizeDoc NumberRevDate: SheetofReviewerDesignerDepartmentProject
Page TitleCCBU D56 257Tuesday, August 29, 2023<project_name><Designer> GRANDTETON_SWB_20230829056 PEX_3_PWR_Cap_1(8/11)<Reviewer>SizeDoc NumberRevDate: SheetofReviewerDesignerDepartmentProject
Page TitleCCBU D56 257Tuesday, August 29, 2023<project_name><Designer> GRANDTETON_SWB_20230829056 PEX_3_PWR_Cap_1(8/11)<Reviewer>SizeDoc NumberRevDate: SheetofReviewerDesignerDepartmentProject
Page TitleCCBU D56 257Tuesday, August 29, 2023<project_name><Designer> GRANDTETON_SWB_20230829056 PEX_3_PWR_Cap_1(8/11)<Reviewer>
C34590.1UFC020110%6.3VC34281UFC020120%4VC342410UFC060320%6.3VC34940.1UFC020110%6.3VC34960.1UFC020110%6.3VC35330.1UFC020110%6.3VC35151000PFC02015%16V
C34640.1UFC020110%6.3VC35141000PFC02015%16VC34950.1UFC020110%6.3VC34630.1UFC020110%6.3VC34930.1UFC020110%6.3VC35290.1UFC020110%6.3VC35040.1UFC020110%6.3VC35070.1UFC020110%6.3VC34490.1UFC020110%6.3VC34440.1UFC020110%6.3VC35000.1UFC020110%6.3VC34560.1UFC020110%6.3VC34761000PFC02015%16VC34420.1UFC020110%6.3VC34321000PFC02015%16VC34311000PFC02015%16V
C35280.1UFC020110%6.3V
C34391000PFC02015%16VC35080.1UFC020110%6.3VC34701UFC020120%4VC35320.1UFC020110%6.3VC34781000PFC02015%16VC35350.1UFC020110%6.3VC35310.1UFC020110%6.3VC34791000PFC02015%16VC34600.1UFC020110%6.3VC34691UFC020120%4VC34880.1UFC020110%6.3VC35171000PFC02015%16V
C34261UFC020120%4VC34470.1UFC020110%6.3VC34371000PFC02015%16VC34450.1UFC020110%6.3VC342310UFC060320%6.3VC346710UFC060320%6.3VC351210UFC060320%6.3VC34580.1UFC020110%6.3VC34990.1UFC020110%6.3VC35010.1UFC020110%6.3VC35060.1UFC020110%6.3V17/26PEX3QSS26-0A0P-01VDDA_Y16Y16VDDA_Y17Y17VDDA_Y18Y18VDDA_Y19Y19VDDA_Y20Y20VDDA_Y21Y21VDDA_Y22Y22VDDA_Y23Y23VDDA_Y24Y24VDDA_Y25Y25VDDA_Y26Y26VDDA_Y27Y27VDDA_Y28Y28VDDA_Y29Y29VDDA_Y30Y30VDDA_Y31Y31VDDA_Y32Y32VDDA_Y33Y33VDDA_AB16AB16VDDA_AB17AB17VDDA_AB18AB18VDDA_AB19AB19VDDA_AB20AB20VDDA_AB21AB21VDDA_AB22AB22VDDA_AB23AB23VDDA_AB24AB24VDDA_AB25AB25VDDA_AB26AB26VDDA_AB27AB27VDDA_AB28AB28VDDA_AB29AB29VDDA_AB30AB30VDDA_AB31AB31VDDA_AB32AB32VDDA_AB33AB33VDDA_AD32AD32VDDA_AD33AD33VDDA_AD34AD34VDDA_AE33AE33VDDA_AE34AE34VDDA_AF32AF32VDDA_AF33AF33VDDA_AF34AF34VDDA_AH16AH16VDDA_AH17AH17VDDA_AH18AH18VDDA_AH19AH19VDDA_AH20AH20VDDA_AH21AH21VDDA_AH22AH22VDDA_AH23AH23VDDA_AH24AH24VDDA_AH25AH25VDDA_AH26AH26VDDA_AH27AH27VDDA_AH28AH28VDDA_AH29AH29VDDA_AH30AH30VDDA_AH31AH31VDDA_AH32AH32VDDA_AH33AH33VDDA_AK16AK16VDDA_AK17AK17VDDA_AK18AK18VDDA_AK19AK19VDDA_AK20AK20VDDA_AK21AK21VDDA_AK22AK22VDDA_AK23AK23VDDA_AK24AK24VDDA_AK25AK25VDDA_AK26AK26VDDA_AK27AK27VDDA_AK28AK28VDDA_AK29AK29VDDA_AK30AK30VDDA_AK31AK31VDDA_AK32AK32VDDA_AK33AK33C34900.1UFC020110%6.3VC34711UFC020120%4VC34361000PFC02015%16VC34840.1UFC020110%6.3VC35210.1UFC020110%6.3VC34741000PFC02015%16VC34351000PFC02015%16V
C35240.1UFC020110%6.3V
C34570.1UFC020110%6.3VC351010UFC060320%6.3VC34980.1UFC020110%6.3VC34890.1UFC020110%6.3VC34510.1UFC020110%6.3VC34331000PFC02015%16VC35020.1UFC020110%6.3VC35250.1UFC020110%6.3VC34850.1UFC020110%6.3VC35300.1UFC020110%6.3VC35111UFC020120%4VC34811000PFC02015%16VC34831000PFC02015%16VC34430.1UFC020110%6.3VC34731000PFC02015%16VC34251UFC020120%4V
C34970.1UFC020110%6.3VC35270.1UFC020110%6.3VC34721UFC020120%4VC34410.1UFC020110%6.3VC34271UFC020120%4VC34870.1UFC020110%6.3VC35360.1UFC020110%6.3VC34801000PFC02015%16VC34920.1UFC020110%6.3VC34460.1UFC020110%6.3V
C35201000PFC02015%16VC34751000PFC02015%16VC34620.1UFC020110%6.3VC34610.1UFC020110%6.3VC34821000PFC02015%16VC34341000PFC02015%16VC35050.1UFC020110%6.3V
C34291UFC020120%4VC34530.1UFC020110%6.3VC346610UFC060320%6.3VC34500.1UFC020110%6.3VC34910.1UFC020110%6.3VC34650.1UFC020110%6.3V16/26PEX3PSS26-0A0P-01PCEPLL7_VDDA18AJ13PCEPLL6_VDDA18AH12PCEPLL5_VDDA18AG13PCEPLL4_VDDA18AF12PCEPLL3_VDDA18AE13PCEPLL2_VDDA18AD12PCEPLL1_VDDA18AB12PCEPLL0_VDDA18AA13SYSPLL_VDDA18AC13EDM_VDDW38VDDQ_EFUSEAM12VDD18_V35V35VDD18_W35W35VDD18_Y12Y12VDD18_Y35Y35VDD18_AE10AE10VDD18_AF10AF10VDD18_AH10AH10VDD18_AJ10AJ10VDD18_AK10AK10VDD18_AK12AK12VDD18_AK35AK35VDD18_AL35AL35VDD18_AM35AM35VDDA18_T35T35VDDA18_V14V14VDDA18_AA10AA10VDDA18_AA34AA34VDDA18_AA37AA37VDDA18_AB10AB10VDDA18_AC10AC10VDDA18_AM14AM14VDDA18_AP35AP35VDDA_SENSEAL15VSSA_SENSEAL14VDD_SENSEV39VSS_SENSEW39C34381000PFC02015%16V
C35220.1UFC020110%6.3VC35191000PFC02015%16VC35161000PFC02015%16VC34771000PFC02015%16VC34480.1UFC020110%6.3VC35091UFC020120%4V
C34401000PFC02015%16VC34301000PFC02015%16VC34520.1UFC020110%6.3VC34550.1UFC020110%6.3V
C35230.1UFC020110%6.3VC34860.1UFC020110%6.3VC34540.1UFC020110%6.3V15/26PEX3O
SS26-0A0P-01
VDD125_V16V16VDD125_V17V17VDD125_V18V18VDD125_V19V19VDD125_V20V20VDD125_V21V21VDD125_V22V22VDD125_V23V23VDD125_V24V24VDD125_V25V25VDD125_V26V26VDD125_V27V27VDD125_V28V28VDD125_V29V29VDD125_V30V30VDD125_V31V31VDD125_V32V32VDD125_V33V33VDD125_AC36AC36VDD125_AD36AD36VDD125_AE36AE36VDD125_AF36AF36VDD125_AG36AG36VDD125_AM16AM16VDD125_AM17AM17VDD125_AM18AM18VDD125_AM19AM19VDD125_AM20AM20VDD125_AM21AM21VDD125_AM22AM22VDD125_AM23AM23VDD125_AM24AM24VDD125_AM25AM25VDD125_AM26AM26VDD125_AM27AM27VDD125_AM28AM28VDD125_AM29AM29VDD125_AM30AM30VDD125_AM31AM31VDD125_AM32AM32VDD125_AM33AM33VDD_Y14Y14VDD_AA15AA15VDD_AB14AB14VDD_AC15AC15VDD_AC17AC17VDD_AC19AC19VDD_AC21AC21VDD_AC23AC23VDD_AC25AC25VDD_AC27AC27VDD_AC29AC29VDD_AC31AC31VDD_AC33AC33VDD_AD14AD14VDD_AD16AD16VDD_AD18AD18VDD_AD20AD20VDD_AD22AD22VDD_AD24AD24VDD_AD26AD26VDD_AD28AD28VDD_AD30AD30VDD_AE15AE15VDD_AE17AE17VDD_AE19AE19VDD_AE21AE21VDD_AE23AE23
VDDA125_T16T16VDDA125_T17T17VDDA125_T18T18VDDA125_T19T19VDDA125_T20T20VDDA125_T21T21VDDA125_T22T22VDDA125_T23T23VDDA125_T24T24VDDA125_T25T25VDDA125_T26T26VDDA125_T27T27VDDA125_T28T28VDDA125_T29T29VDDA125_T30T30VDDA125_T31T31VDDA125_T32T32VDDA125_T33T33VDDA125_AC38AC38VDDA125_AD38AD38VDDA125_AE38AE38VDDA125_AF38AF38VDDA125_AG38AG38VDDA125_AP16AP16VDDA125_AP17AP17VDDA125_AP18AP18VDDA125_AP19AP19VDDA125_AP20AP20VDDA125_AP21AP21VDDA125_AP22AP22VDDA125_AP23AP23VDDA125_AP24AP24VDDA125_AP25AP25VDDA125_AP26AP26VDDA125_AP28AP28VDDA125_AP29AP29VDDA125_AP30AP30VDDA125_AP31AP31VDDA125_AP32AP32VDDA125_AP33AP33VDD_AE25AE25VDD_AE27AE27VDD_AE29AE29VDD_AE31AE31VDD_AF14AF14VDD_AF16AF16VDD_AF18AF18VDD_AF20AF20VDD_AF22AF22VDD_AF24AF24VDD_AF26AF26VDD_AF28AF28VDD_AF30AF30VDD_AG15AG15VDD_AG17AG17VDD_AG19AG19VDD_AG21AG21VDD_AG23AG23VDD_AG25AG25VDD_AG27AG27VDD_AG29AG29VDD_AG31AG31VDD_AG33AG33VDD_AH14AH14VDD_AJ15AJ15VDD_AK14AK14VDDA125_AP27AP27C35030.1UFC020110%6.3VC34681UFC020120%4VC35181000PFC02015%16VC35340.1UFC020110%6.3VC35260.1UFC020110%6.3VC35131000PFC02015%16VTP_PEX3_VDDQ_EFUSE



5
5
4
4
3
3
2
2
1
1
D D
C C
B B
A A
44
1uF(0201) Caps
6
QTY.
4
3
0.1uF(0201) Caps
Item
BGA BALLs
53
1000pF(0201) Caps
4
0.1uF(0201) Caps
1000pF(0201) Caps
1uF(0201) Caps
PEX3 P0V8DECOUPLING INFO.
33
10uF(0603) Caps
PEX3 P0V8_SERDES_VDDADECOUPLING INFO.
BGA BALLs
80
10uF(0603) Caps
QTY.
17
Item
30
PEX_3_PWR_Cap_2(9/11)
P0V8_PEX3P0V8_SERDES_VDDA_PEX3
SizeDoc NumberRevDate: SheetofReviewerDesignerDepartmentProject
Page TitleCCBU D57 257Tuesday, August 29, 2023<project_name><Designer> GRANDTETON_SWB_20230829057 PEX_3_PWR_Cap_2(9/11)<Reviewer>SizeDoc NumberRevDate: SheetofReviewerDesignerDepartmentProject
Page TitleCCBU D57 257Tuesday, August 29, 2023<project_name><Designer> GRANDTETON_SWB_20230829057 PEX_3_PWR_Cap_2(9/11)<Reviewer>SizeDoc NumberRevDate: SheetofReviewerDesignerDepartmentProject
Page TitleCCBU D57 257Tuesday, August 29, 2023<project_name><Designer> GRANDTETON_SWB_20230829057 PEX_3_PWR_Cap_2(9/11)<Reviewer>C19940.1UFC020110%6.3V
C18701UFC020120%4VC19150.1UFC020110%6.3VC19850.1UFC020110%6.3VC19591000PFC02015%16VC19090.1UFC020110%6.3V19/26PEX3S
SS26-0A0P-01
VSS_F30F30VSS_F32F32VSS_F34F34VSS_F38F38VSS_F40F40VSS_F42F42VSS_F44F44VSS_F46F46VSS_F48F48VSS_F49F49VSS_G1G1VSS_G2G2VSS_G4G4VSS_G6G6VSS_G8G8VSS_G10G10VSS_G12G12VSS_G14G14VSS_G16G16VSS_G18G18VSS_G20G20VSS_G22G22VSS_G24G24VSS_G26G26VSS_G28G28VSS_G30G30VSS_G32G32VSS_G34G34VSS_G36G36VSS_G38G38VSS_G40G40VSS_G42G42VSS_G44G44VSS_G46G46VSS_G48G48VSS_G49G49VSS_H3H3VSS_H5H5VSS_H7H7VSS_H9H9VSS_H11H11VSS_H13H13VSS_H15H15VSS_H17H17VSS_H19H19VSS_H21H21VSS_H23H23VSS_H25H25VSS_H27H27VSS_H29H29VSS_H31H31VSS_H33H33VSS_H35H35VSS_H37H37VSS_H39H39VSS_H41H41VSS_H43H43VSS_H45H45VSS_H47H47VSS_J1J1VSS_J2J2VSS_J3J3VSS_J5J5VSS_J7J7VSS_J9J9VSS_J11J11VSS_J13J13VSS_J15J15VSS_J17J17VSS_J19J19VSS_J21J21VSS_J23J23VSS_J25J25VSS_J27J27VSS_J29J29VSS_J31J31VSS_J33J33VSS_J35J35VSS_J37J37
VSS_J39J39VSS_J41J41VSS_J43J43VSS_J45J45VSS_J47J47VSS_J48J48VSS_J49J49VSS_K3K3VSS_K4K4VSS_K5K5VSS_K6K6VSS_K7K7VSS_K8K8VSS_K9K9VSS_K10K10VSS_K11K11VSS_K12K12VSS_K13K13VSS_K14K14VSS_K15K15VSS_K16K16VSS_K17K17VSS_K18K18VSS_K19K19VSS_K20K20VSS_K21K21VSS_K22K22VSS_K23K23VSS_K24K24VSS_K25K25VSS_K26K26VSS_K27K27VSS_K28K28VSS_K29K29VSS_K30K30VSS_K31K31VSS_K32K32VSS_K33K33VSS_K34K34VSS_K35K35VSS_K36K36VSS_K37K37VSS_K38K38VSS_K39K39VSS_K40K40VSS_K41K41VSS_K42K42VSS_K43K43VSS_K44K44VSS_K45K45VSS_K46K46VSS_K47K47VSS_L1L1VSS_L2L2VSS_L5L5VSS_L8L8VSS_L9L9VSS_L10L10VSS_L11L11VSS_L14L14VSS_L21L21VSS_L40L40VSS_L41L41VSS_L42L42VSS_L45L45VSS_L48L48VSS_L49L49VSS_M3M3VSS_M4M4VSS_M5M5VSS_M6M6VSS_M7M7VSS_M10M10VSS_M11M11VSS_M12M12VSS_M14M14VSS_M21M21VSS_M40M40VSS_M43M43VSS_M44M44
VSS_F36F36C19431000PFC02015%16VC18820.1UFC020110%6.3VC19740.1UFC020110%6.3VC19501000PFC02015%16VC19341000PFC02015%16VC18790.1UFC020110%6.3VC19650.1UFC020110%6.3V
C18781000PFC02015%16VC19281UFC020120%4VC20040.1UFC020110%6.3V
C18911000PFC02015%16V
C19950.1UFC020110%6.3V
C18711UFC020120%4VC19160.1UFC020110%6.3VC19860.1UFC020110%6.3VC19601000PFC02015%16VC19441000PFC02015%16VC19511000PFC02015%16VC19060.1UFC020110%6.3VC19750.1UFC020110%6.3VC19351000PFC02015%16VC19660.1UFC020110%6.3V
C18971000PFC02015%16VC19291UFC020120%4VC19000.1UFC020110%6.3V
C20050.1UFC020110%6.3V
C18921000PFC02015%16V
C19960.1UFC020110%6.3V
C19170.1UFC020110%6.3VC19870.1UFC020110%6.3VC19611000PFC02015%16VC19451000PFC02015%16VC18830.1UFC020110%6.3VC19760.1UFC020110%6.3VC19521000PFC02015%16VC19361000PFC02015%16VC19301UFC020120%4VC19010.1UFC020110%6.3VC19670.1UFC020110%6.3V
C18751000PFC02015%16V
C19970.1UFC020110%6.3V
C19180.1UFC020110%6.3VC19880.1UFC020110%6.3VC19461000PFC02015%16VC19070.1UFC020110%6.3VC19770.1UFC020110%6.3VC19531000PFC02015%16VC19371000PFC02015%16VC18800.1UFC020110%6.3VC19680.1UFC020110%6.3VC19311UFC020120%4VC192210UFC060320%6.3VC18931000PFC02015%16V
C19980.1UFC020110%6.3V
C18721000PFC02015%16VC19190.1UFC020110%6.3VC19890.1UFC020110%6.3V
C186510UFC060320%6.3VC19100.1UFC020110%6.3VC19471000PFC02015%16VC19541000PFC02015%16VC18840.1UFC020110%6.3VC19780.1UFC020110%6.3VC19381000PFC02015%16VC19690.1UFC020110%6.3V
C19020.1UFC020110%6.3VC18941000PFC02015%16VC192310UFC060320%6.3VC19990.1UFC020110%6.3V
C18881000PFC02015%16V
C19900.1UFC020110%6.3V
C19200.1UFC020110%6.3VC186610UFC060320%6.3VC19110.1UFC020110%6.3VC19481000PFC02015%16VC18850.1UFC020110%6.3VC19790.1UFC020110%6.3VC19551000PFC02015%16VC19391000PFC02015%16VC19030.1UFC020110%6.3VC19700.1UFC020110%6.3VC192410UFC060320%6.3VC18951000PFC02015%16V
C20000.1UFC020110%6.3V
C18731000PFC02015%16VC19210.1UFC020110%6.3VC19910.1UFC020110%6.3V
C186710UFC060320%6.3VC19120.1UFC020110%6.3VC19080.1UFC020110%6.3VC19800.1UFC020110%6.3VC19561000PFC02015%16VC19401000PFC02015%16VC18810.1UFC020110%6.3VC19710.1UFC020110%6.3VC19620.1UFC020110%6.3V
C18761000PFC02015%16VC192510UFC060320%6.3VC20010.1UFC020110%6.3V
C18891000PFC02015%16V
C19920.1UFC020110%6.3V
C18681UFC020120%4VC19130.1UFC020110%6.3VC19830.1UFC020110%6.3VC19571000PFC02015%16V
18/26PEX3R
SS26-0A0P-01
VSS_A2A2VSS_A4A4VSS_A6A6VSS_A8A8VSS_A10A10VSS_A12A12VSS_A14A14VSS_A16A16VSS_A18A18VSS_A20A20VSS_A22A22VSS_A24A24VSS_A26A26VSS_A28A28VSS_A30A30VSS_A32A32VSS_A34A34VSS_A36A36VSS_A38A38VSS_A40A40VSS_A42A42VSS_A44A44VSS_A46A46VSS_A48A48VSS_B1B1VSS_B2B2VSS_B4B4VSS_B6B6VSS_B8B8VSS_B10B10VSS_B12B12VSS_B14B14VSS_B16B16VSS_B18B18VSS_B20B20VSS_B22B22VSS_B24B24VSS_B26B26VSS_B28B28VSS_B30B30VSS_B32B32VSS_B34B34VSS_B36B36VSS_B38B38VSS_B40B40VSS_B42B42VSS_B44B44VSS_B46B46VSS_B48B48VSS_B49B49VSS_C3C3VSS_C5C5VSS_C7C7VSS_C9C9VSS_C11C11VSS_C13C13VSS_C15C15VSS_C17C17VSS_C19C19VSS_C21C21VSS_C23C23VSS_C25C25VSS_C27C27VSS_C29C29VSS_C31C31VSS_C33C33VSS_C35C35VSS_C37C37VSS_C39C39VSS_C41C41VSS_C43C43VSS_C45C45VSS_C47C47VSS_D1D1VSS_D2D2VSS_D3D3VSS_D5D5VSS_D7D7VSS_D9D9VSS_D11D11
VSS_D13D13VSS_D15D15VSS_D17D17VSS_D19D19VSS_D21D21VSS_D23D23VSS_D25D25VSS_D27D27VSS_D29D29VSS_D31D31VSS_D33D33VSS_D35D35VSS_D37D37VSS_D39D39VSS_D41D41VSS_D43D43VSS_D45D45VSS_D47D47VSS_D48D48VSS_D49D49VSS_E3E3VSS_E4E4VSS_E6E6VSS_E7E7VSS_E8E8VSS_E9E9VSS_E10E10VSS_E11E11VSS_E12E12VSS_E13E13VSS_E14E14VSS_E15E15VSS_E16E16VSS_E17E17VSS_E18E18VSS_E19E19VSS_E20E20VSS_E21E21VSS_E22E22VSS_E23E23VSS_E24E24VSS_E25E25VSS_E26E26VSS_E27E27VSS_E28E28VSS_E29E29VSS_E30E30VSS_E31E31VSS_E32E32VSS_E33E33VSS_E34E34VSS_E35E35VSS_E36E36VSS_E37E37VSS_E38E38VSS_E40E40VSS_E41E41VSS_E42E42VSS_E43E43VSS_E44E44VSS_E45E45VSS_E46E46VSS_E47E47VSS_F1F1VSS_F2F2VSS_F4F4VSS_F6F6VSS_F8F8VSS_F10F10VSS_F12F12VSS_F14F14VSS_F16F16VSS_F18F18VSS_F20F20VSS_F22F22VSS_F24F24VSS_F26F26VSS_F28F28VSS_E39E39VSS_E5E5C18860.1UFC020110%6.3VC19810.1UFC020110%6.3VC19411000PFC02015%16VC19040.1UFC020110%6.3VC19720.1UFC020110%6.3VC19321000PFC02015%16VC18980.1UFC020110%6.3VC19630.1UFC020110%6.3V
C18771000PFC02015%16VC19261UFC020120%4VC20020.1UFC020110%6.3V
C18901000PFC02015%16V
C19930.1UFC020110%6.3V
C18691UFC020120%4VC19140.1UFC020110%6.3VC19840.1UFC020110%6.3V
C18870.1UFC020110%6.3VC19820.1UFC020110%6.3VC19581000PFC02015%16VC19421000PFC02015%16VC19050.1UFC020110%6.3VC19730.1UFC020110%6.3VC19491000PFC02015%16VC19331000PFC02015%16VC19271UFC020120%4VC18990.1UFC020110%6.3VC19640.1UFC020110%6.3V
C18961000PFC02015%16V
C20030.1UFC020110%6.3V
C18741000PFC02015%16V



5
5
4
4
3
3
2
2
1
1
D D
C C
B B
A A
PEX_3_PWR_Cap_3(10/11)
Imax: 0.04A
Imax: 0.04A Imax: 0.04A Imax: 0.04A
Imax: 0.04A Imax: 0.04A Imax: 0.04A
Imax: 0.04A
Imax: 0.2A Imax: 0.1A
PCEPLL0_VDDA18_PEX3P1V8_PLL0_PEX3P1V8_PLL0_PEX3PCEPLL1_VDDA18_PEX3P1V8_PLL0_PEX3PCEPLL2_VDDA18_PEX3P1V8_PLL0_PEX3PCEPLL3_VDDA18_PEX3P1V8_PLL0_PEX3PCEPLL4_VDDA18_PEX3P1V8_PLL0_PEX3PCEPLL5_VDDA18_PEX3P1V8_PLL0_PEX3PCEPLL6_VDDA18_PEX3P1V8_PLL0_PEX3PCEPLL7_VDDA18_PEX3P1V8_PLL0_PEX3SYSPLL_VDDA18_PEX3P1V8_PLL0_PEX3P1V8_VDDA_PEX3
PCEPLL0_VDDA18_PEX3_RPCEPLL1_VDDA18_PEX3_RPCEPLL2_VDDA18_PEX3_RPCEPLL3_VDDA18_PEX3_RPCEPLL4_VDDA18_PEX3_RPCEPLL5_VDDA18_PEX3_RPCEPLL6_VDDA18_PEX3_RPCEPLL7_VDDA18_PEX3_RSYSPLL_VDDA18_PEX3_RP1V8_VDDA_PEX3_RSizeDoc NumberRevDate: SheetofReviewerDesignerDepartmentProject
Page TitleCCBU D58 257Tuesday, August 29, 2023<project_name><Designer> GRANDTETON_SWB_20230829058 PEX_3_PWR_Cap_3(10/11)<Reviewer>SizeDoc NumberRevDate: SheetofReviewerDesignerDepartmentProject
Page TitleCCBU D58 257Tuesday, August 29, 2023<project_name><Designer> GRANDTETON_SWB_20230829058 PEX_3_PWR_Cap_3(10/11)<Reviewer>SizeDoc NumberRevDate: SheetofReviewerDesignerDepartmentProject
Page TitleCCBU D58 257Tuesday, August 29, 2023<project_name><Designer> GRANDTETON_SWB_20230829058 PEX_3_PWR_Cap_3(10/11)<Reviewer>C35910.1UFC020110%6.3VC357522UFC0603_H4020%6.3VC356710UFC060320%6.3VL136HCB2012KF-601T20<Part Number>21 C35480.1UFC020110%6.3VR45940.51R45950.51C355247UFL138HCB2012KF-601T20<Part Number>21
C358522UFC0603_H4020%6.3VC358722UFC0603_H4020%6.3V
C35501UFC020120%4VC356110UFC060320%6.3VC35471UFC020120%4VC357710UFC060320%6.3VC35861UFC020120%4V
C35381UFC020120%4VC35510.1UFC020110%6.3V
R45960.51
C35450.1UFC020110%6.3VC35630.1UFC020110%6.3VC35681UFC020120%4VR45920.51R45900.51
C35881UFC020120%4VC35811UFC020120%4V
C354122UFC0603_H4020%6.3VC355522UFC0603_H4020%6.3VC357047UFC355447UFC35690.1UFC020110%6.3VC358447UF
R45890.51
C35781UFC020120%4VC35820.1UFC020110%6.3VL145HCB2012KF-601T20<Part Number>21
C355347UF
R45970.51C358910UFC060320%6.3VC35901UFC020120%4V
C354310UFC060320%6.3VL140HCB2012KF-601T20<Part Number>21C358347UFR45930.51L143HCB2012KF-601T20<Part Number>21C35790.1UFC020110%6.3VC35660.1UFC020110%6.3V
C359647UF
C353722UFC0603_H4020%6.3VC354910UFC060320%6.3VR45910.51L137HCB2012KF-601T20<Part Number>21
C358010UFC060320%6.3VL144HCB2012KF-601T20<Part Number>21 C355922UFC0603_H4020%6.3VC35761UFC020120%4VC35441UFC020120%4VC35581UFC020120%4VC35401UFC020120%4VC355722UFC0603_H4020%6.3VC357147UFC359210UFC060320%6.3VC35931UFC020120%4V
C35601UFC020120%4VC357322UFC0603_H4020%6.3VC356410UFC060320%6.3VC35561UFC020120%4VR45880.51C353922UFC0603_H4020%6.3VC35421UFC020120%4VL139HCB2012KF-601T20<Part Number>21
C35940.1UFC020110%6.3VL142HCB2012KF-601T20<Part Number>21 C35651UFC020120%4VC35741UFC020120%4VL141HCB2012KF-601T20<Part Number>21C357247UFC359547UF
C35621UFC020120%4VC354610UFC060320%6.3V



5
5
4
4
3
3
2
2
1
1
D D
C C
B B
A A
PEX_3_GND(11/11) SizeDoc NumberRevDate: SheetofReviewerDesignerDepartmentProject
Page TitleCCBU D59 257Tuesday, August 29, 2023<project_name><Designer> GRANDTETON_SWB_20230829059 PEX_3_GND(11/11)<Reviewer>SizeDoc NumberRevDate: SheetofReviewerDesignerDepartmentProject
Page TitleCCBU D59 257Tuesday, August 29, 2023<project_name><Designer> GRANDTETON_SWB_20230829059 PEX_3_GND(11/11)<Reviewer>SizeDoc NumberRevDate: SheetofReviewerDesignerDepartmentProject
Page TitleCCBU D59 257Tuesday, August 29, 2023<project_name><Designer> GRANDTETON_SWB_20230829059 PEX_3_GND(11/11)<Reviewer>
21/26PEX3U
SS26-0A0P-01
VSS_U30U30VSS_U31U31VSS_U32U32VSS_U33U33VSS_U34U34VSS_U35U35VSS_U37U37VSS_U40U40VSS_U41U41VSS_U42U42VSS_U45U45VSS_U48U48VSS_U49U49VSS_V3V3VSS_V4V4VSS_V5V5VSS_V6V6VSS_V7V7VSS_V10V10VSS_V11V11VSS_V12V12VSS_V13V13VSS_V15V15VSS_V34V34VSS_V36V36VSS_V37V37VSS_V38V38VSS_V40V40VSS_V43V43VSS_V44V44VSS_V45V45VSS_V46V46VSS_V47V47VSS_W1W1VSS_W2W2VSS_W5W5VSS_W8W8VSS_W9W9VSS_W10W10VSS_W11W11VSS_W12W12VSS_W13W13VSS_W14W14VSS_W15W15VSS_W16W16VSS_W17W17VSS_W18W18VSS_W19W19VSS_W20W20VSS_W21W21VSS_W22W22VSS_W23W23VSS_W24W24VSS_W25W25VSS_W26W26VSS_W27W27VSS_W28W28VSS_W29W29VSS_W30W30VSS_W31W31VSS_W32W32VSS_W33W33VSS_W34W34VSS_W36W36VSS_W37W37VSS_W40W40VSS_W41W41VSS_W42W42VSS_W45W45VSS_W48W48VSS_W49W49VSS_Y1Y1VSS_Y2Y2VSS_Y3Y3VSS_Y4Y4VSS_Y5Y5VSS_Y6Y6VSS_Y7Y7VSS_Y8Y8VSS_Y9Y9
VSS_Y10Y10VSS_Y11Y11VSS_Y13Y13VSS_Y15Y15VSS_Y34Y34VSS_Y36Y36VSS_Y37Y37VSS_Y38Y38VSS_Y40Y40VSS_Y44Y44VSS_Y45Y45VSS_Y46Y46VSS_Y47Y47VSS_AA3AA3VSS_AA4AA4VSS_AA5AA5VSS_AA6AA6VSS_AA7AA7VSS_AA8AA8VSS_AA9AA9VSS_AA11AA11VSS_AA14AA14VSS_AA16AA16VSS_AA17AA17VSS_AA18AA18VSS_AA19AA19VSS_AA20AA20VSS_AA21AA21VSS_AA22AA22VSS_AA23AA23VSS_AA24AA24VSS_AA25AA25VSS_AA26AA26VSS_AA27AA27VSS_AA28AA28VSS_AA29AA29VSS_AA30AA30VSS_AA31AA31VSS_AA32AA32VSS_AA33AA33VSS_AA36AA36VSS_AA38AA38VSS_AA40AA40VSS_AA41AA41VSS_AA42AA42VSS_AA45AA45VSS_AA48AA48VSS_AA49AA49VSS_AB1AB1VSS_AB2AB2VSS_AB3AB3VSS_AB6AB6VSS_AB9AB9VSS_AB11AB11VSS_AB15AB15VSS_AB34AB34VSS_AB36AB36VSS_AB37AB37VSS_AB38AB38VSS_AB39AB39VSS_AB40AB40VSS_AB43AB43VSS_AB44AB44VSS_AB45AB45VSS_AB46AB46VSS_AB47AB47VSS_AC3AC3VSS_AC4AC4VSS_AC5AC5VSS_AC6AC6VSS_AC9AC9VSS_AC11AC11VSS_AC14AC14VSS_AC16AC16VSS_AC18AC18VSS_AC20AC20VSS_AC22AC22VSS_AC24AC24VSS_AC26AC26
VSS_Y43Y4324/26PEX3X
SS26-0A0P-01
VSS_AR26AR26VSS_AR27AR27VSS_AR28AR28VSS_AR29AR29VSS_AR30AR30VSS_AR31AR31VSS_AR32AR32VSS_AR33AR33VSS_AR34AR34VSS_AR35AR35VSS_AR37AR37VSS_AR40AR40VSS_AR41AR41VSS_AR42AR42VSS_AR45AR45VSS_AR48AR48VSS_AR49AR49VSS_AT3AT3VSS_AT4AT4VSS_AT5AT5VSS_AT6AT6VSS_AT7AT7VSS_AT10AT10VSS_AT11AT11VSS_AT12AT12VSS_AT13AT13VSS_AT14AT14VSS_AT15AT15VSS_AT16AT16VSS_AT17AT17VSS_AT18AT18VSS_AT19AT19VSS_AT20AT20VSS_AT21AT21VSS_AT22AT22VSS_AT23AT23VSS_AT24AT24VSS_AT25AT25VSS_AT26AT26VSS_AT27AT27VSS_AT28AT28VSS_AT29AT29VSS_AT30AT30VSS_AT31AT31VSS_AT32AT32VSS_AT33AT33VSS_AT34AT34VSS_AT35AT35VSS_AT37AT37VSS_AT40AT40VSS_AT43AT43VSS_AT44AT44VSS_AT45AT45VSS_AT46AT46VSS_AT47AT47VSS_AU1AU1VSS_AU2AU2VSS_AU5AU5VSS_AU8AU8VSS_AU9AU9VSS_AU10AU10VSS_AU11AU11VSS_AU12AU12VSS_AU13AU13VSS_AU14AU14VSS_AU15AU15VSS_AU16AU16VSS_AU17AU17VSS_AU18AU18VSS_AU19AU19VSS_AU20AU20VSS_AU21AU21VSS_AU22AU22VSS_AU23AU23VSS_AU24AU24VSS_AU25AU25VSS_AU26AU26VSS_AU27AU27VSS_AU28AU28VSS_AU29AU29
VSS_AU30AU30VSS_AU31AU31VSS_AU32AU32VSS_AU33AU33VSS_AU34AU34VSS_AU35AU35VSS_AU36AU36VSS_AU37AU37VSS_AU40AU40VSS_AU41AU41VSS_AU42AU42VSS_AU45AU45VSS_AU48AU48VSS_AU49AU49VSS_AV3AV3VSS_AV4AV4VSS_AV5AV5VSS_AV6AV6VSS_AV7AV7VSS_AV10AV10VSS_AV11AV11VSS_AV20AV20VSS_AV24AV24VSS_AV40AV40VSS_AV43AV43VSS_AV44AV44VSS_AV45AV45VSS_AV46AV46VSS_AV47AV47VSS_AW1AW1VSS_AW2AW2VSS_AW5AW5VSS_AW8AW8VSS_AW9AW9VSS_AW10AW10VSS_AW11AW11VSS_AW20AW20VSS_AW24AW24VSS_AW40AW40VSS_AW41AW41VSS_AW42AW42VSS_AW45AW45VSS_AW48AW48VSS_AW49AW49VSS_AY3AY3VSS_AY4AY4VSS_AY5AY5VSS_AY6AY6VSS_AY7AY7VSS_AY8AY8VSS_AY9AY9VSS_AY10AY10VSS_AY11AY11VSS_AY12AY12VSS_AY13AY13VSS_AY14AY14VSS_AY15AY15VSS_AY16AY16VSS_AY17AY17VSS_AY18AY18VSS_AY19AY19VSS_AY20AY20VSS_AY21AY21VSS_AY22AY22VSS_AY23AY23VSS_AY24AY24VSS_AY25AY25VSS_AY26AY26VSS_AY27AY27VSS_AY28AY28VSS_AY29AY29VSS_AY30AY30VSS_AY31AY31VSS_AY32AY32VSS_AY33AY33VSS_AY34AY34VSS_AY35AY35VSS_AY36AY36VSS_AY37AY37VSS_AY38AY38
22/26PEX3V
SS26-0A0P-01
VSS_AC28AC28VSS_AC30AC30VSS_AC32AC32VSS_AC34AC34VSS_AC35AC35VSS_AC37AC37VSS_AC39AC39VSS_AC40AC40VSS_AC41AC41VSS_AC42AC42VSS_AC45AC45VSS_AC48AC48VSS_AC49AC49VSS_AD1AD1VSS_AD2AD2VSS_AD3AD3VSS_AD6AD6VSS_AD9AD9VSS_AD10AD10VSS_AD11AD11VSS_AD15AD15VSS_AD17AD17VSS_AD19AD19VSS_AD21AD21VSS_AD23AD23VSS_AD25AD25VSS_AD27AD27VSS_AD29AD29VSS_AD31AD31VSS_AD35AD35VSS_AD37AD37VSS_AD39AD39VSS_AD40AD40VSS_AD43AD43VSS_AD44AD44VSS_AD45AD45VSS_AD46AD46VSS_AD47AD47VSS_AE3AE3VSS_AE4AE4VSS_AE5AE5VSS_AE6AE6VSS_AE9AE9VSS_AE11AE11VSS_AE14AE14VSS_AE16AE16VSS_AE18AE18VSS_AE20AE20VSS_AE22AE22VSS_AE24AE24VSS_AE26AE26VSS_AE28AE28VSS_AE30AE30VSS_AE32AE32VSS_AE35AE35VSS_AE37AE37VSS_AE39AE39VSS_AE40AE40VSS_AE41AE41VSS_AE42AE42VSS_AE45AE45VSS_AE48AE48VSS_AE49AE49VSS_AF1AF1VSS_AF2AF2VSS_AF3AF3VSS_AF6AF6VSS_AF9AF9VSS_AF11AF11VSS_AF15AF15VSS_AF17AF17VSS_AF19AF19VSS_AF21AF21VSS_AF23AF23VSS_AF25AF25VSS_AF27AF27VSS_AF29AF29VSS_AF31AF31VSS_AF35AF35VSS_AF37AF37
VSS_AF39AF39VSS_AF40AF40VSS_AF43AF43VSS_AF44AF44VSS_AF45AF45VSS_AF46AF46VSS_AF47AF47VSS_AG3AG3VSS_AG4AG4VSS_AG5AG5VSS_AG6AG6VSS_AG9AG9VSS_AG10AG10VSS_AG11AG11VSS_AG14AG14VSS_AG16AG16VSS_AG18AG18VSS_AG20AG20VSS_AG22AG22VSS_AG24AG24VSS_AG26AG26VSS_AG28AG28VSS_AG30AG30VSS_AG32AG32VSS_AG34AG34VSS_AG35AG35VSS_AG37AG37VSS_AG39AG39VSS_AG40AG40VSS_AG41AG41VSS_AG42AG42VSS_AG45AG45VSS_AG48AG48VSS_AG49AG49VSS_AH1AH1VSS_AH2AH2VSS_AH3AH3VSS_AH6AH6VSS_AH9AH9VSS_AH11AH11VSS_AH15AH15VSS_AH34AH34VSS_AH35AH35VSS_AH36AH36VSS_AH37AH37VSS_AH38AH38VSS_AH39AH39VSS_AH40AH40VSS_AH43AH43VSS_AH44AH44VSS_AH45AH45VSS_AH46AH46VSS_AH47AH47VSS_AJ3AJ3VSS_AJ4AJ4VSS_AJ5AJ5VSS_AJ6AJ6VSS_AJ9AJ9VSS_AJ11AJ11VSS_AJ14AJ14VSS_AJ16AJ16VSS_AJ17AJ17VSS_AJ18AJ18VSS_AJ19AJ19VSS_AJ20AJ20VSS_AJ21AJ21VSS_AJ22AJ22VSS_AJ23AJ23VSS_AJ24AJ24VSS_AJ25AJ25VSS_AJ26AJ26VSS_AJ27AJ27VSS_AJ28AJ28VSS_AJ29AJ29VSS_AJ30AJ30VSS_AJ31AJ31VSS_AJ32AJ32VSS_AJ33AJ33VSS_AJ34AJ34VSS_AJ35AJ35
25/26PEX3Y
SS26-0A0P-01
VSS_AY39AY39VSS_AY40AY40VSS_AY41AY41VSS_AY42AY42VSS_AY43AY43VSS_AY44AY44VSS_AY45AY45VSS_AY46AY46VSS_AY47AY47VSS_BA1BA1VSS_BA2BA2VSS_BA3BA3VSS_BA5BA5VSS_BA7BA7VSS_BA9BA9VSS_BA11BA11VSS_BA13BA13VSS_BA15BA15VSS_BA17BA17VSS_BA19BA19VSS_BA21BA21VSS_BA23BA23VSS_BA25BA25VSS_BA27BA27VSS_BA29BA29VSS_BA31BA31VSS_BA33BA33VSS_BA35BA35VSS_BA37BA37VSS_BA39BA39VSS_BA41BA41VSS_BA43BA43VSS_BA45BA45VSS_BA47BA47VSS_BA48BA48VSS_BA49BA49VSS_BB3BB3VSS_BB5BB5VSS_BB7BB7VSS_BB9BB9VSS_BB11BB11VSS_BB13BB13VSS_BB15BB15VSS_BB17BB17VSS_BB19BB19VSS_BB21BB21VSS_BB23BB23VSS_BB25BB25VSS_BB27BB27VSS_BB29BB29VSS_BB31BB31VSS_BB33BB33VSS_BB35BB35VSS_BB37BB37VSS_BB39BB39VSS_BB41BB41VSS_BB43BB43VSS_BB45BB45VSS_BB47BB47VSS_BC1BC1VSS_BC2BC2VSS_BC4BC4VSS_BC6BC6VSS_BC8BC8VSS_BC10BC10VSS_BC12BC12VSS_BC14BC14VSS_BC16BC16VSS_BC18BC18VSS_BC20BC20VSS_BC22BC22VSS_BC24BC24VSS_BC26BC26VSS_BC28BC28VSS_BC30BC30VSS_BC32BC32VSS_BC34BC34VSS_BC36BC36VSS_BC38BC38VSS_BC40BC40
VSS_BC42BC42VSS_BC44BC44VSS_BC46BC46VSS_BC48BC48VSS_BC49BC49VSS_BD1BD1VSS_BD2BD2VSS_BD4BD4VSS_BD6BD6VSS_BD8BD8VSS_BD10BD10VSS_BD12BD12VSS_BD14BD14VSS_BD16BD16VSS_BD18BD18VSS_BD20BD20VSS_BD22BD22VSS_BD24BD24VSS_BD26BD26VSS_BD28BD28VSS_BD30BD30VSS_BD32BD32VSS_BD34BD34VSS_BD36BD36VSS_BD38BD38VSS_BD40BD40VSS_BD42BD42VSS_BD44BD44VSS_BD46BD46VSS_BD48BD48VSS_BD49BD49VSS_BE3BE3VSS_BE4BE4VSS_BE5BE5VSS_BE6BE6VSS_BE7BE7VSS_BE8BE8VSS_BE9BE9VSS_BE10BE10VSS_BE11BE11VSS_BE12BE12VSS_BE13BE13VSS_BE14BE14VSS_BE15BE15VSS_BE16BE16VSS_BE17BE17VSS_BE18BE18VSS_BE19BE19VSS_BE20BE20VSS_BE21BE21VSS_BE22BE22VSS_BE23BE23VSS_BE24BE24VSS_BE25BE25VSS_BE26BE26VSS_BE27BE27VSS_BE28BE28VSS_BE29BE29VSS_BE30BE30VSS_BE31BE31VSS_BE32BE32VSS_BE33BE33VSS_BE34BE34VSS_BE35BE35VSS_BE36BE36VSS_BE37BE37VSS_BE38BE38VSS_BE39BE39VSS_BE40BE40VSS_BE41BE41VSS_BE42BE42VSS_BE43BE43VSS_BE44BE44VSS_BE45BE45VSS_BE46BE46VSS_BE47BE47VSS_BF1BF1VSS_BF2BF2VSS_BF3BF3VSS_BF5BF5
20/26PEX3T
SS26-0A0P-01
VSS_M45M45VSS_M46M46VSS_M47M47VSS_N1N1VSS_N2N2VSS_N5N5VSS_N8N8VSS_N9N9VSS_N10N10VSS_N11N11VSS_N12N12VSS_N13N13VSS_N14N14VSS_N15N15VSS_N16N16VSS_N17N17VSS_N18N18VSS_N19N19VSS_N20N20VSS_N21N21VSS_N22N22VSS_N23N23VSS_N24N24VSS_N25N25VSS_N26N26VSS_N27N27VSS_N28N28VSS_N29N29VSS_N30N30VSS_N31N31VSS_N32N32VSS_N33N33VSS_N34N34VSS_N35N35VSS_N36N36VSS_N37N37VSS_N40N40VSS_N41N41VSS_N42N42VSS_N45N45VSS_N48N48VSS_N49N49VSS_P3P3VSS_P4P4VSS_P5P5VSS_P6P6VSS_P7P7VSS_P10P10VSS_P11P11VSS_P12P12VSS_P13P13VSS_P14P14VSS_P15P15VSS_P16P16VSS_P17P17VSS_P18P18VSS_P19P19VSS_P20P20VSS_P21P21VSS_P22P22VSS_P23P23VSS_P24P24VSS_P25P25VSS_P26P26VSS_P27P27VSS_P28P28VSS_P29P29VSS_P30P30VSS_P31P31VSS_P32P32VSS_P33P33VSS_P34P34VSS_P35P35VSS_P37P37VSS_P40P40VSS_P43P43VSS_P44P44VSS_P45P45VSS_P46P46VSS_P47P47
VSS_R1R1VSS_R2R2VSS_R5R5VSS_R8R8VSS_R9R9VSS_R10R10VSS_R11R11VSS_R12R12VSS_R13R13VSS_R14R14VSS_R15R15VSS_R16R16VSS_R17R17VSS_R18R18VSS_R19R19VSS_R20R20VSS_R21R21VSS_R22R22VSS_R23R23VSS_R24R24VSS_R25R25VSS_R26R26VSS_R27R27VSS_R28R28VSS_R29R29VSS_R30R30VSS_R31R31VSS_R32R32VSS_R33R33VSS_R34R34VSS_R35R35VSS_R37R37VSS_R40R40VSS_R41R41VSS_R42R42VSS_R45R45VSS_R48R48VSS_R49R49VSS_T3T3VSS_T4T4VSS_T5T5VSS_T6T6VSS_T7T7VSS_T10T10VSS_T11T11VSS_T12T12VSS_T13T13VSS_T15T15VSS_T34T34VSS_T37T37VSS_T40T40VSS_T43T43VSS_T44T44VSS_T45T45VSS_T46T46VSS_T47T47VSS_U1U1VSS_U2U2VSS_U5U5VSS_U8U8VSS_U9U9VSS_U10U10VSS_U11U11VSS_U12U12VSS_U13U13VSS_U15U15VSS_U16U16VSS_U17U17VSS_U18U18VSS_U19U19VSS_U20U20VSS_U21U21VSS_U22U22VSS_U23U23VSS_U24U24VSS_U25U25VSS_U26U26VSS_U27U27VSS_U28U28VSS_U29U29
26/26PEX3ZSS26-0A0P-01VSS_BF7BF7VSS_BF9BF9VSS_BF11BF11VSS_BF13BF13VSS_BF15BF15VSS_BF17BF17VSS_BF19BF19VSS_BF21BF21VSS_BF23BF23VSS_BF25BF25VSS_BF27BF27VSS_BF29BF29VSS_BF31BF31VSS_BF33BF33VSS_BF35BF35VSS_BF37BF37VSS_BF39BF39VSS_BF41BF41VSS_BF43BF43VSS_BF45BF45VSS_BF47BF47VSS_BF48BF48VSS_BF49BF49VSS_BG3BG3VSS_BG5BG5VSS_BG7BG7VSS_BG9BG9VSS_BG11BG11VSS_BG13BG13VSS_BG15BG15VSS_BG17BG17VSS_BG19BG19VSS_BG21BG21VSS_BG23BG23VSS_BG25BG25VSS_BG27BG27VSS_BG29BG29VSS_BG31BG31VSS_BG33BG33VSS_BG35BG35VSS_BG37BG37VSS_BG39BG39VSS_BG41BG41VSS_BG43BG43VSS_BG45BG45VSS_BG47BG47VSS_BH1BH1VSS_BH2BH2VSS_BH4BH4VSS_BH6BH6VSS_BH8BH8VSS_BH10BH10VSS_BH12BH12VSS_BH14BH14VSS_BH16BH16VSS_BH18BH18VSS_BH20BH20VSS_BH22BH22VSS_BH24BH24VSS_BH26BH26VSS_BH28BH28VSS_BH30BH30VSS_BH32BH32VSS_BH34BH34VSS_BH36BH36VSS_BH38BH38VSS_BH40BH40VSS_BH42BH42VSS_BH44BH44VSS_BH46BH46VSS_BH48BH48VSS_BH49BH49VSS_BJ2BJ2VSS_BJ4BJ4VSS_BJ6BJ6VSS_BJ8BJ8VSS_BJ10BJ10VSS_BJ12BJ12VSS_BJ14BJ14VSS_BJ16BJ16VSS_BJ18BJ18VSS_BJ20BJ20VSS_BJ22BJ22VSS_BJ24BJ24VSS_BJ26BJ26VSS_BJ28BJ28VSS_BJ30BJ30VSS_BJ32BJ32VSS_BJ34BJ34VSS_BJ36BJ36VSS_BJ38BJ38VSS_BJ40BJ40VSS_BJ42BJ42VSS_BJ44BJ44VSS_BJ46BJ46VSS_BJ48BJ48PLL_VSSA_AA12AA12PLL_VSSA_AB13AB13PLL_VSSA_AC12AC12PLL_VSSA_AD13AD13PLL_VSSA_AE12AE12PLL_VSSA_AF13AF13PLL_VSSA_AG12AG12PLL_VSSA_AH13AH13PLL_VSSA_AJ12AJ1223/26PEX3W
SS26-0A0P-01
VSS_AJ36AJ36VSS_AJ37AJ37VSS_AJ40AJ40VSS_AJ41AJ41VSS_AJ42AJ42VSS_AJ45AJ45VSS_AJ48AJ48VSS_AJ49AJ49VSS_AK1AK1VSS_AK2AK2VSS_AK3AK3VSS_AK6AK6VSS_AK8AK8VSS_AK9AK9VSS_AK11AK11VSS_AK13AK13VSS_AK15AK15VSS_AK34AK34VSS_AK36AK36VSS_AK37AK37VSS_AK40AK40VSS_AK43AK43VSS_AK44AK44VSS_AK45AK45VSS_AK46AK46VSS_AK47AK47VSS_AL1AL1VSS_AL2AL2VSS_AL3AL3VSS_AL4AL4VSS_AL5AL5VSS_AL6AL6VSS_AL7AL7VSS_AL8AL8VSS_AL9AL9VSS_AL10AL10VSS_AL11AL11VSS_AL12AL12VSS_AL13AL13VSS_AL16AL16VSS_AL17AL17VSS_AL18AL18VSS_AL19AL19VSS_AL20AL20VSS_AL21AL21VSS_AL22AL22VSS_AL23AL23VSS_AL24AL24VSS_AL25AL25VSS_AL26AL26VSS_AL27AL27VSS_AL28AL28VSS_AL29AL29VSS_AL30AL30VSS_AL31AL31VSS_AL32AL32VSS_AL33AL33VSS_AL34AL34VSS_AL36AL36VSS_AL37AL37VSS_AL40AL40VSS_AL41AL41VSS_AL42AL42VSS_AL45AL45VSS_AL48AL48VSS_AL49AL49VSS_AM3AM3VSS_AM4AM4VSS_AM5AM5VSS_AM6AM6VSS_AM7AM7VSS_AM10AM10VSS_AM11AM11VSS_AM13AM13VSS_AM15AM15VSS_AM34AM34VSS_AM36AM36VSS_AM37AM37VSS_AM40AM40VSS_AM43AM43
VSS_AM44AM44VSS_AM45AM45VSS_AM46AM46VSS_AM47AM47VSS_AN1AN1VSS_AN2AN2VSS_AN5AN5VSS_AN8AN8VSS_AN9AN9VSS_AN10AN10VSS_AN11AN11VSS_AN12AN12VSS_AN13AN13VSS_AN15AN15VSS_AN16AN16VSS_AN17AN17VSS_AN18AN18VSS_AN19AN19VSS_AN20AN20VSS_AN21AN21VSS_AN22AN22VSS_AN23AN23VSS_AN24AN24VSS_AN25AN25VSS_AN26AN26VSS_AN27AN27VSS_AN28AN28VSS_AN29AN29VSS_AN30AN30VSS_AN31AN31VSS_AN32AN32VSS_AN33AN33VSS_AN34AN34VSS_AN35AN35VSS_AN37AN37VSS_AN40AN40VSS_AN41AN41VSS_AN42AN42VSS_AN45AN45VSS_AN48AN48VSS_AN49AN49VSS_AP3AP3VSS_AP4AP4VSS_AP5AP5VSS_AP6AP6VSS_AP7AP7VSS_AP10AP10VSS_AP11AP11VSS_AP12AP12VSS_AP13AP13VSS_AP15AP15VSS_AP34AP34VSS_AP37AP37VSS_AP40AP40VSS_AP43AP43VSS_AP44AP44VSS_AP45AP45VSS_AP46AP46VSS_AP47AP47VSS_AR1AR1VSS_AR2AR2VSS_AR5AR5VSS_AR8AR8VSS_AR9AR9VSS_AR10AR10VSS_AR11AR11VSS_AR12AR12VSS_AR13AR13VSS_AR14AR14VSS_AR15AR15VSS_AR16AR16VSS_AR17AR17VSS_AR18AR18VSS_AR19AR19VSS_AR20AR20VSS_AR21AR21VSS_AR22AR22VSS_AR23AR23VSS_AR24AR24VSS_AR25AR25



5
5
4
4
3
3
2
2
1
1
D D
C C
B B
A A
CAD NOTE:NEAR PACKAGE EDGE
Co-Layout
PEX_3_PWR_FILTER
CAD NOTE:NEAR PACKAGE EDGE
CAD NOTE:BUCK CAP NEAR FILTERCo-Layout
CAD NOTE:BUCK CAP NEAR FILTER
DCR : 0.0021 ohm
P0V8_SERDES_VDDA_PEX3P0V8_PEX3P0V8_PEX3P1V25_SERDES_VDDPLL_PEX3P1V25_PEX3P1V25_PEX3SizeDoc NumberRevDate: SheetofReviewerDesignerDepartmentProject
Page TitleCCBU D60 257Tuesday, August 29, 2023<project_name><Designer> GRANDTETON_SWB_20230829060 PEX_3_PWR_FILTER<Reviewer>SizeDoc NumberRevDate: SheetofReviewerDesignerDepartmentProject
Page TitleCCBU D60 257Tuesday, August 29, 2023<project_name><Designer> GRANDTETON_SWB_20230829060 PEX_3_PWR_FILTER<Reviewer>SizeDoc NumberRevDate: SheetofReviewerDesignerDepartmentProject
Page TitleCCBU D60 257Tuesday, August 29, 2023<project_name><Designer> GRANDTETON_SWB_20230829060 PEX_3_PWR_FILTER<Reviewer>
R65430.51C43781UFC020120%4V0.01R6139NI2B1B2A1AC44041UFC020120%4V
R65350.51
C4413100UF20%4VC43911UFC020120%4V
C43641UFC020120%4V0.01R5795NI2B1B2A1AR65440.51R65360.51
C44051UFC020120%4V
C43791UFC020120%4VR65450.51R65510.51C43651UFC020120%4V0.01R5796NI2B1B2A1AC43921UFC020120%4V
R65370.51
L132BLM31SN500SN1L21R65590.51R65520.51R65460.51
C44061UFC020120%4V
R65380.51
C43931UFC020120%4VL133BLM31SN500SN1L21R65470.51R65600.51R65530.51
R65390.51
C44071UFC020120%4VC438047UFL77BLM31SN500SN1L21
R65610.51R65540.51R65480.51C436647UFR65400.51L78BLM31SN500SN1L21C438147UFC437247UFR65620.51R65550.51C436747UFC435847UF
C439447UFC438247UFC437347UFL130BLM31SN500SN1L21R65630.51R65560.510.01R6140NI2B1B2A1A
C436847UFC435947UF
C440847UFC439547UFC438347UFL131BLM31SN500SN1L21C438647UFC437447UFR65640.51
C436947UFC436047UF
0.01R6141NI2B1B2A1AC439647UFC438422UFC0603_H4020%6.3VC440947UFC438747UFC437547UF0.01R5797NI2B1B2A1AC440047UF
L75BLM31SN500SN1L21C437022UFC0603_H4020%6.3VC436147UF
C441047UFC439747UFC440147UFC438847UFC43761UFC020120%4VC438522UFC0603_H4020%6.3V0.01R5798NI2B1B2A1AL76BLM31SN500SN1L21C43621UFC020120%4VC437122UFC0603_H4020%6.3V
C441147UFC4398100UFC0805_H61_SEL20%4VC438947UFC440247UF
C43771UFC020120%4V0.01R6138NI2B1B2A1A
C43631UFC020120%4V
C4412100UFC0805_H61_SEL20%4VC440347UFC43901UFC020120%4VC4399100UF20%4V



5
5
4
4
3
3
2
2
1
1
D D
C C
B B
A A
BLANK SizeDoc NumberRevDate: SheetofReviewerDesignerDepartmentProject
Page TitleCCBU D61 257Tuesday, August 29, 2023<project_name><Designer> GRANDTETON_SWB_20230829061 BLANK<Reviewer>SizeDoc NumberRevDate: SheetofReviewerDesignerDepartmentProject
Page TitleCCBU D61 257Tuesday, August 29, 2023<project_name><Designer> GRANDTETON_SWB_20230829061 BLANK<Reviewer>SizeDoc NumberRevDate: SheetofReviewerDesignerDepartmentProject
Page TitleCCBU D61 257Tuesday, August 29, 2023<project_name><Designer> GRANDTETON_SWB_20230829061 BLANK<Reviewer>



5
5
4
4
3
3
2
2
1
1
D D
C C
B B
A A
PEX_STRAP SizeDoc NumberRevDate: SheetofReviewerDesignerDepartmentProject
Page TitleCCBU D62 257Tuesday, August 29, 2023<project_name><Designer> GRANDTETON_SWB_20230829062 PEX_STRAP<Reviewer>SizeDoc NumberRevDate: SheetofReviewerDesignerDepartmentProject
Page TitleCCBU D62 257Tuesday, August 29, 2023<project_name><Designer> GRANDTETON_SWB_20230829062 PEX_STRAP<Reviewer>SizeDoc NumberRevDate: SheetofReviewerDesignerDepartmentProject
Page TitleCCBU D62 257Tuesday, August 29, 2023<project_name><Designer> GRANDTETON_SWB_20230829062 PEX_STRAP<Reviewer>



5
5
4
4
3
3
2
2
1
1
D D
C C
B B
A A
L
Function
A Connected to B
DIR
B Connected to A
SN74AVC4T774PWR
H
OE
High-Z
L
H X
BIC Flash
BIC
BIC
BIC
Flash
Flash
Flash
CO-LayoutR462,R1023R463,R1024R464,R1025
R466,R1026R467,R1027R468,R1028
PEX_FLASH_LEVEL_SHIFTER
DVT_CHANGEDVT_CHANGEPVT2_BOM_CHANGEPVT2_BOM_CHANGE
PVT2_BOM_CHANGESPI_BIC1_CS0_R2_N [63]SPI_BIC1_CLK_R3 [63]SPI_BIC1_MOSI_R3 [63]SPI_BIC1_MISO_R3 [63]SEL_FLASH_PEX0_BUF_R[16,88]SEL_FLASH_PEX1_BUF_R[29,88]SEL_FLASH_PEX2_BUF_R[42,88]SEL_FLASH_PEX3_BUF_R[55,88]
SPI_BIC1_CS0_N[88]SPI_BIC1_CLK[88,93]SPI_BIC1_MOSI[88]SPI_BIC1_MISO[88,93]SPI_BIC1_CS0_R2_N [63]SPI_BIC1_CLK_R3 [63]SPI_BIC1_MOSI_R3 [63]SPI_BIC1_MISO_R3 [63]SPI_BIC1_CS0_R3_N [63]SPI_BIC1_CLK_R4 [63]SPI_BIC1_MOSI_R4 [63]SPI_BIC1_MISO_R4 [63]
SPI_BIC1_CS0_LS23_R1_N[42]SPI_BIC1_CLK_LS23_R1[42]SPI_BIC1_MOSI_LS23_R1[42]SPI_BIC1_MISO_LS23_R1[42]SPI_BIC1_CS0_LS23_R2_N[55]SPI_BIC1_CLK_LS23_R2[55]SPI_BIC1_MOSI_LS23_R2[55]SPI_BIC1_MISO_LS23_R2[55]SPI_BIC1_CS0_LS01_R1_N[16]SPI_BIC1_CLK_LS01_R1[16]SPI_BIC1_MOSI_LS01_R1[16]SPI_BIC1_MISO_LS01_R1[16]SPI_BIC1_CS0_LS01_R2_N[29]SPI_BIC1_CLK_LS01_R2[29]SPI_BIC1_MOSI_LS01_R2[29]SPI_BIC1_MISO_LS01_R2[29]SPI_BIC1_CS0_LS01_N_DIR1[63]SPI_BIC1_CLK_LS01_DIR2[63]SPI_BIC1_MOSI_LS01_DIR3[63]SPI_BIC1_MISO_LS01_DIR4[63]SPI_BIC1_LS01_EN_N[63]SPI_BIC1_LS01_EN_N [63]SPI_BIC1_CS0_LS01_N_DIR1 [63]SPI_BIC1_CLK_LS01_DIR2 [63]SPI_BIC1_MOSI_LS01_DIR3 [63]SPI_BIC1_MISO_LS01_DIR4 [63]SPI_BIC1_CS0_LS23_N_DIR1[63]SPI_BIC1_CLK_LS23_DIR2[63]SPI_BIC1_MOSI_LS23_DIR3[63]SPI_BIC1_MISO_LS23_DIR4[63]SPI_BIC1_LS23_EN_N[63]SPI_BIC1_CS0_R3_N [63]SPI_BIC1_CLK_R4 [63]SPI_BIC1_MOSI_R4 [63]SPI_BIC1_MISO_R4 [63]SPI_BIC1_CS0_LS23_N_DIR1 [63]SPI_BIC1_CLK_LS23_DIR2 [63]SPI_BIC1_MOSI_LS23_DIR3 [63]SPI_BIC1_MISO_LS23_DIR4 [63]SPI_BIC1_LS23_EN_N [63]SPI_BIC1_CLK_R5[63]SPI_BIC1_CLK_R2 [63]SPI_BIC1_MOSI_R5[63]SPI_BIC1_MOSI_R2 [63]SPI_BIC1_MISO_R2 [63]SPI_BIC1_MISO_R5 [63]SPI_BIC1_CLK_R5 [63]SPI_BIC1_MOSI_R5 [63]SPI_BIC1_MISO_R5[63]SPI_BIC1_CLK_R2 [63]SPI_BIC1_MOSI_R2 [63]SPI_BIC1_MISO_R2 [63]P3V3_AUXP3V3_AUXP1V8_PEXP3V3_AUXP1V8_PEXP1V8_PEXP3V3_AUXP1V8_PEX
P3V3_AUXP1V8_PEXP1V8_PEXSizeDoc NumberRevDate: SheetofReviewerDesignerDepartmentProject
Page TitleCCBU D63 257Tuesday, August 29, 2023<project_name><Designer> GRANDTETON_SWB_20230829063 PEX_FLASH_LEVEL_SHIFTER<Reviewer>SizeDoc NumberRevDate: SheetofReviewerDesignerDepartmentProject
Page TitleCCBU D63 257Tuesday, August 29, 2023<project_name><Designer> GRANDTETON_SWB_20230829063 PEX_FLASH_LEVEL_SHIFTER<Reviewer>SizeDoc NumberRevDate: SheetofReviewerDesignerDepartmentProject
Page TitleCCBU D63 257Tuesday, August 29, 2023<project_name><Designer> GRANDTETON_SWB_20230829063 PEX_FLASH_LEVEL_SHIFTER<Reviewer>
R1026 33 R0402-02011%NI
R3365 0 R0402-02015%
R665710KR0402-02015%SN74AVC4T774PWRU50DIR11DIR22A13A24A35A46DIR37DIR48OE9GND10B411B312B213B114VCCB15VCCA16U305CSN74LVC3G34DCTR6284R460 33 1%R469 0 R0402-02015%R3402 0 R0402-02015%R10354.7KR0402-02011%R3398 0 R0402-02015%
R472 33.2 1% R0402-0201R3393 33.2 1% R0402-0201R3287 0 R0402-02015%R10404.7KR0402-02011%R10294.7KR0402-02011%NIR3366 0 R0402-02015%
R464 0 R0402-02015%R462 0 R0402-02015%R3408 0 R0402-02015%R3399 0 R0402-02015%C20950.1UF10%16VC0402-0201R1023 0 R0402-02015%NIR461 0 R0402-02015%
R3369 0 R0402-02015%C21100.1UF10%16VC0402-0201R10324.7KR0402-02011%R10334.7KR0402-02011%
R458 33 1%
C21090.1UF10%16VC0402-0201
R468 0 R0402-02015%U305BSN74LVC3G34DCTR3584R466 0 R0402-02015%R3288 0 R0402-02015%R1024 0 R0402-02015%NIQ240DMN3042L-7GSDR3390 0 R0402-02015%R10364.7KR0402-02011%NIR3400 0 R0402-02015%R10374.7KR0402-02011%NI C20960.1UF10%16VC0402-0201R3394 0 R0402-02015%R3409 0 R0402-02015%R3367 0 R0402-02015%R3404 0 R0402-02015%R665810KR0402-02015%
R1025 0 R0402-02015%NIR470 0 R0402-02015%R1028 33 R0402-02011%NIC20930.1UF10%16VC0402-0201
C21080.1UF10%16VC0402-0201R3395 0 R0402-02015%R10384.7KR0402-02011%NIR3401 0 R0402-02015%Q241DMN3042L-7GSD
R3391 0 R0402-02015%R10304.7KR0402-02011%NIR3291 0 R0402-02015%R3396 0 R0402-02015%R3289 0 R0402-02015%R10394.7KR0402-02011%NI
C26290.1UF10%16VC0402-0201R3405 0 R0402-02015%R10414.7KR0402-02011%
R3403 51 5% R0402-0201U64SN74AUP1G32DBVR12453R1027 33 R0402-02011%NIR10344.7KR0402-02011%R3368 0 R0402-02015%SN74AVC4T774PWRU63DIR11DIR22A13A24A35A46DIR37DIR48OE9GND10B411B312B213B114VCCB15VCCA16
R463 0 R0402-02015%
R3397 0 R0402-02015%
R3392 0 R0402-02015%
R10424.7KR0402-02011%R3407 51 5% R0402-0201R10444.7KR0402-02011%NI
U305ASN74LVC3G34DCTR1784R467 0 R0402-02015%
R10434.7KR0402-02011%
R3290 0 R0402-02015%R459 33 1%R10314.7KR0402-02011%NIR465 0 R0402-02015%R3406 0 R0402-02015%R471 0 R0402-02015%U52SN74AUP1G32DBVR12453SPI_BIC1_CS0_LS01_NSPI_BIC1_CS0_R2_NSPI_BIC1_CLK_LS01SPI_BIC1_CLK_R3SPI_BIC1_MOSI_LS01SPI_BIC1_MOSI_R3SPI_BIC1_MISO_LS01SPI_BIC1_MISO_R3SPI_BIC1_LS01_EN_N
SPI_BIC1_CS0_LS23_NSPI_BIC1_CLK_LS23SPI_BIC1_MOSI_LS23SPI_BIC1_MISO_LS23SPI_BIC1_LS23_EN
SPI_BIC1_CS0_R_NSPI_BIC1_CS0_R1_NSPI_BIC1_CS0_R2_NSPI_BIC1_CLK_RSPI_BIC1_CLK_R1SPI_BIC1_CLK_R2SPI_BIC1_CLK_R3SPI_BIC1_MOSI_RSPI_BIC1_MOSI_R1SPI_BIC1_MOSI_R2SPI_BIC1_MOSI_R3SPI_BIC1_MISO_RSPI_BIC1_MISO_R1SPI_BIC1_MISO_R2SPI_BIC1_MISO_R3SPI_BIC1_CS0_R3_NSPI_BIC1_CLK_R4SPI_BIC1_MOSI_R4SPI_BIC1_MISO_R4SPI_BIC1_CS0_NSPI_BIC1_CLKSPI_BIC1_MOSISPI_BIC1_MISO
SPI_BIC1_CS0_LS23_R_NSPI_BIC1_CLK_LS23_RSPI_BIC1_MOSI_LS23_RSPI_BIC1_MISO_LS23_RSPI_BIC1_CS0_LS01_R_NSPI_BIC1_CLK_LS01_RSPI_BIC1_MOSI_LS01_RSPI_BIC1_MISO_LS01_RSPI_BIC1_LS01_EN_NSPI_BIC1_LS01_EN_R_NSPI_BIC1_CS0_LS01_N_DIR1SPI_BIC1_CLK_LS01_DIR2SPI_BIC1_MOSI_LS01_DIR3SPI_BIC1_MISO_LS01_DIR4SPI_BIC1_CS0_LS23_N_DIR1SPI_BIC1_CLK_LS23_DIR2SPI_BIC1_MOSI_LS23_DIR3SPI_BIC1_MISO_LS23_DIR4SPI_BIC1_LS23_EN_NSPI_BIC1_LS23_EN_R_NSPI_BIC1_CS0_R3_NSPI_BIC1_CLK_R4SPI_BIC1_MOSI_R4SPI_BIC1_MISO_R4
SPI_BIC1_CLK_R5SPI2_CLK_BUFSPI_BIC1_CLK_R2SPI_BIC1_MOSI_R5SPI2_DO_BUFSPI_BIC1_MOSI_R2SPI2_DI_BUFSPI_BIC1_MISO_R5SPI_BIC1_CLK_R5SPI_BIC1_MOSI_R5SPI_BIC1_MISO_R2SPI_BIC1_MISO_R5SPI_BIC1_CLK_R2SPI_BIC1_MOSI_R2SPI_BIC1_MISO_R2SPI_BIC1_LS01_EN



5
5
4
4
3
3
2
2
1
1
D D
C C
B B
A A
Reserved
PEX_SDB_DEBUG_UART
DVT_CHANGEOSC_SDB_IN[64]OSC_SDB_OUT [64]UART_PEX0_SDB_R_RX [67,122]UART_PEX0_SDB_BUF_TX [67]UART_PEX1_SDB_R_RX [67,122]UART_PEX1_SDB_BUF_TX [67]UART_PEX2_SDB_R_RX [67,122]UART_PEX2_SDB_BUF_TX [67]UART_PEX3_SDB_R_RX [67,122]UART_PEX3_SDB_BUF_TX [67]FT4232_SDB_EEPROM_CS[64]FT4232_SDB_EEPROM_SCL[64]FT4232_SDB_EEPROM_SDA[64]OSC_SDB_IN[64]OSC_SDB_OUT[64]FT4232_SDB_EEPROM_CS [64]FT4232_SDB_EEPROM_SCL [64]FT4232_SDB_EEPROM_SDA [64]USB2_FT4232_SDB_DN[70]USB2_FT4232_SDB_DP[70]RST_FT4232_R_N[65,116,122,123]P3V3_SDB_VPLLP3V3_AUXP3V3_SDB_VPHYP3V3_AUXP1V8_SDB_VCOREP1V8_SDB_VCOREP3V3_AUXP3V3_SDB_VPLLP3V3_AUXP3V3_SDB_VPHYP3V3_AUX
P3V3_AUXP3V3_AUXP1V8_SDB_VCORE
SizeDoc NumberRevDate: SheetofReviewerDesignerDepartmentProject
Page TitleCCBU D64 257Tuesday, August 29, 2023<project_name><Designer> GRANDTETON_SWB_20230829064 PEX_SDB_DEBUG_UART<Reviewer>SizeDoc NumberRevDate: SheetofReviewerDesignerDepartmentProject
Page TitleCCBU D64 257Tuesday, August 29, 2023<project_name><Designer> GRANDTETON_SWB_20230829064 PEX_SDB_DEBUG_UART<Reviewer>SizeDoc NumberRevDate: SheetofReviewerDesignerDepartmentProject
Page TitleCCBU D64 257Tuesday, August 29, 2023<project_name><Designer> GRANDTETON_SWB_20230829064 PEX_SDB_DEBUG_UART<Reviewer>U9793LC56BT-I/OTNI<Part Number>DO1VSS2DI3CLK4VCC6CS5
C25670.1UFX7R16V10%C0402-0201UART_BOM1R9270UART_BOM1
R914 0 R0402-02015%NIR9400UART_BOM1R912 0 R0402-02015%NI
C25680.1UFX7R16V10%C0402-0201UART_BOM1R9280UART_BOM1
R9152KR0402-02011%NI
C25720.1UFX7R16V10%C0402-0201UART_BOM1L4BLM18AG601SN1D0.5A L0603UART_BOM121R90910KR0402-02015%NIL5BLM18AG601SN1D0.5A L0603UART_BOM121 C25730.1UFX7R16V10%C0402-0201UART_BOM1
R913 0 R0402-02015%NIR91010KR0402-02015%NI
R90710MR06031%<Part Number>NI C25740.1UFX7R16V10%C0402-0201UART_BOM1
R91110KR0402-02015%NI
C25630.1UFX7R16V10%C0402-0201UART_BOM1C25800.1UFX7R16V10%C0402-0201<Part Number>UART_BOM1C257830PFC0402-02015%50V<Part Number>NPOUART_BOM1C25750.1UFX7R16V10%C0402-0201UART_BOM1
C25840.1UFX7R16V10%C0402-0201NIR5776 0 5%R0402-0201UART_BOM1C25820.1UFX7R16V10%C0402-0201<Part Number>UART_BOM1
C25644.7UF25V10%C0603X6SUART_BOM1C257930PFC0402-02015%50V<Part Number>NPOUART_BOM1C25814.7UF25V10%C0603<Part Number>X6SUART_BOM1FT4232HL-REELU70<Part Number>UART_BOM1DM7DP8REF6RESET#14EECS63EECLK62EEDATA61OSCI2OSCO3TEST13ADBUS016ADBUS117ADBUS218ADBUS319ADBUS421ADBUS522ADBUS623ADBUS724BDBUS026BDBUS127BDBUS228BDBUS329BDBUS430BDBUS532BDBUS633BDBUS734CDBUS038CDBUS139CDBUS240CDBUS341CDBUS443CDBUS544CDBUS645CDBUS746DDBUS048DDBUS152DDBUS253DDBUS354DDBUS455DDBUS557DDBUS658DDBUS759PWREN#60SUSPEND#36VCCIO356VCCIO242VCCIO131VCCIO020VCORE264VCORE137VCORE012VPLL9VPHY4VREGIN50VREGOUT49GND01GND15GND211GND315GND425GND535GND647GND751AGND10
C25760.1UFX7R16V10%C0402-0201UART_BOM1C25650.1UFX7R16V10%C0402-0201UART_BOM1Y312MHZ<Part Number>UART_BOM1X11G12G24X23C25834.7UF25V10%C0603<Part Number>X6SUART_BOM1
C25774.7UF25V10%C0603X6SUART_BOM1R90812K<Part Number>1%1/16WR0402-0201UART_BOM1R9390UART_BOM1C25660.1UFX7R16V10%C0402-0201UART_BOM1FT4232_SDB_REFFT4232_SDB_EEPROM_R_CSFT4232_SDB_EEPROM_R_SCLFT4232_SDB_EEPROM_R_SDAFT4232_SDB_EEPROM_DOUSB2_FT4232_SDB_DNUSB2_FT4232_SDB_DPRST_FT4232_SDB_R_NUART_PEX0_SDB_RXUART_PEX1_SDB_RXUART_PEX2_SDB_RXUART_PEX3_SDB_RX



5
5
4
4
3
3
2
2
1
1
D D
C C
B B
A A
Reserved
PEX_CLI_DEBUG_UART
DVT_CHANGEOSC_CLI_IN[65]OSC_CLI_OUT [65]UART_PEX0_CLI_R_RX [68,123]UART_PEX0_CLI_BUF_TX [68]UART_PEX1_CLI_R_RX [68,123]UART_PEX1_CLI_BUF_TX [68]USB2_FT4232_CLI_DN[70]USB2_FT4232_CLI_DP[70]UART_PEX2_CLI_R_RX [68,123]UART_PEX2_CLI_BUF_TX [68]UART_PEX3_CLI_R_RX [68,123]UART_PEX3_CLI_BUF_TX [68]FT4232_CLI_EEPROM_CS[65]FT4232_CLI_EEPROM_SCL[65]FT4232_CLI_EEPROM_SDA[65]OSC_CLI_IN[65]OSC_CLI_OUT[65]FT4232_CLI_EEPROM_CS [65]FT4232_CLI_EEPROM_SCL [65]FT4232_CLI_EEPROM_SDA [65]RST_FT4232_R_N[64,116,122,123]P3V3_AUXP3V3_AUXP1V8_CLI_VCOREP3V3_CLI_VPLLP3V3_AUXP3V3_CLI_VPHYP3V3_AUXP1V8_CLI_VCOREP1V8_CLI_VCOREP3V3_AUXP3V3_CLI_VPLLP3V3_AUXP3V3_CLI_VPHYP3V3_AUXSizeDoc NumberRevDate: SheetofReviewerDesignerDepartmentProject
Page TitleCCBU D65 257Tuesday, August 29, 2023<project_name><Designer> GRANDTETON_SWB_20230829065 PEX_CLI_DEBUG_UART<Reviewer>SizeDoc NumberRevDate: SheetofReviewerDesignerDepartmentProject
Page TitleCCBU D65 257Tuesday, August 29, 2023<project_name><Designer> GRANDTETON_SWB_20230829065 PEX_CLI_DEBUG_UART<Reviewer>SizeDoc NumberRevDate: SheetofReviewerDesignerDepartmentProject
Page TitleCCBU D65 257Tuesday, August 29, 2023<project_name><Designer> GRANDTETON_SWB_20230829065 PEX_CLI_DEBUG_UART<Reviewer>L7BLM18AG601SN1D0.5A L0603UART_BOM121R91910KR0402-02015%NIR924 0 R0402-02015%NI
C25900.1UFX7R16V10%C0402-0201UART_BOM1
R92010KR0402-02015%NI
C25910.1UFX7R16V10%C0402-0201UART_BOM1C25990.1UFX7R16V10%C0402-0201<Part Number>UART_BOM1R66410UART_BOM1
C26030.1UFX7R16V10%C0402-0201NIR9232KR0402-02011%NIC26010.1UFX7R16V10%C0402-0201<Part Number>UART_BOM1
C25920.1UFX7R16V10%C0402-0201UART_BOM1R66420UART_BOM1R91610MR06031%<Part Number>NIC26004.7UF25V10%C0603<Part Number>X6SUART_BOM1R66430UART_BOM1C25930.1UFX7R16V10%C0402-0201UART_BOM1C26024.7UF25V10%C0603<Part Number>X6SUART_BOM1C259730PFC0402-02015%50V<Part Number>NPOUART_BOM1C25850.1UFX7R16V10%C0402-0201UART_BOM1R66440UART_BOM1R91712K<Part Number>1%1/16WR0402-0201UART_BOM1U9993LC56BT-I/OTNI<Part Number>DO1VSS2DI3CLK4VCC6CS5
C25940.1UFX7R16V10%C0402-0201UART_BOM1C259830PFC0402-02015%50V<Part Number>NPOUART_BOM1C25864.7UF25V10%C0603X6SUART_BOM1
FT4232HL-REELU98<Part Number>UART_BOM1DM7DP8REF6RESET#14EECS63EECLK62EEDATA61OSCI2OSCO3TEST13ADBUS016ADBUS117ADBUS218ADBUS319ADBUS421ADBUS522ADBUS623ADBUS724BDBUS026BDBUS127BDBUS228BDBUS329BDBUS430BDBUS532BDBUS633BDBUS734CDBUS038CDBUS139CDBUS240CDBUS341CDBUS443CDBUS544CDBUS645CDBUS746DDBUS048DDBUS152DDBUS253DDBUS354DDBUS455DDBUS557DDBUS658DDBUS759PWREN#60SUSPEND#36VCCIO356VCCIO242VCCIO131VCCIO020VCORE264VCORE137VCORE012VPLL9VPHY4VREGIN50VREGOUT49GND01GND15GND211GND315GND425GND535GND647GND751AGND10R921 0 R0402-02015%NIR5775 0 5% R0402-0201UART_BOM1C25950.1UFX7R16V10%C0402-0201UART_BOM1Y412MHZ<Part Number>UART_BOM1X11G12G24X23 C25870.1UFX7R16V10%C0402-0201UART_BOM1C25964.7UF25V10%C0603X6SUART_BOM1C25880.1UFX7R16V10%C0402-0201UART_BOM1
R922 0 R0402-02015%NIL6BLM18AG601SN1D0.5A L0603UART_BOM121R91810KR0402-02015%NI
C25890.1UFX7R16V10%C0402-0201UART_BOM1UART_PEX0_CLI_RXUART_PEX1_CLI_RXUSB2_FT4232_CLI_DNUSB2_FT4232_CLI_DPUART_PEX2_CLI_RXFT4232_CLI_REFRST_FT4232_CLI_R_NUART_PEX3_CLI_RXFT4232_CLI_EEPROM_R_CSFT4232_CLI_EEPROM_R_SCLFT4232_CLI_EEPROM_R_SDAFT4232_CLI_EEPROM_DO



5
5
4
4
3
3
2
2
1
1
D D
C C
B B
A A
BLANK SizeDoc NumberRevDate: SheetofReviewerDesignerDepartmentProject
Page TitleCCBU D66 257Tuesday, August 29, 2023<project_name><Designer> GRANDTETON_SWB_20230829066 BLANK<Reviewer>SizeDoc NumberRevDate: SheetofReviewerDesignerDepartmentProject
Page TitleCCBU D66 257Tuesday, August 29, 2023<project_name><Designer> GRANDTETON_SWB_20230829066 BLANK<Reviewer>SizeDoc NumberRevDate: SheetofReviewerDesignerDepartmentProject
Page TitleCCBU D66 257Tuesday, August 29, 2023<project_name><Designer> GRANDTETON_SWB_20230829066 BLANK<Reviewer>



5
5
4
4
3
3
2
2
1
1
D D
C C
B B
A A
OPEN DRAIN
OPEN DRAIN
PEX_SDB_UART_LEVEL_SHIFTER
OPEN DRAIN
OPEN DRAIN
Design Note: 1. Level shifter2. Prevent power leakage
FT4232
FT4232
FT4232
FT4232
PEX
PEX
PEX
PEX
PVT2_BOM_CHANGEPVT2_BOM_CHANGEUART_PEX0_SDB_BUF_RX [15]UART_PEX1_SDB_BUF_RX [28]UART_PEX2_SDB_BUF_RX [41]UART_PEX3_SDB_BUF_RX [54]UART_PEX0_SDB_TX[15]UART_PEX1_SDB_TX[28]UART_PEX0_SDB_BUF_TX [64]UART_PEX1_SDB_BUF_TX [64]UART_PEX2_SDB_TX[41]UART_PEX3_SDB_TX[54]UART_PEX2_SDB_BUF_TX [64]UART_PEX3_SDB_BUF_TX [64]
UART_PEX0_SDB_R_RX[64,122]UART_PEX1_SDB_R_RX[64,122]UART_PEX2_SDB_R_RX[64,122]UART_PEX3_SDB_R_RX[64,122]UART_PEX1_SDB_BUF_R_TX [122]UART_PEX0_SDB_BUF_R_TX [122]UART_PEX2_SDB_BUF_R_TX [122]UART_PEX3_SDB_BUF_R_TX [122]
P3V3_AUXP1V8_PEXP1V8_PEXP3V3_AUXP3V3_AUXP1V8_PEXP1V8_PEXP3V3_AUXSizeDoc NumberRevDate: SheetofReviewerDesignerDepartmentProject
Page TitleCCBU D67 257Tuesday, August 29, 2023<project_name><Designer> GRANDTETON_SWB_20230829067 PEX_SDB_UART_LEVEL_SHIFTER<Reviewer>SizeDoc NumberRevDate: SheetofReviewerDesignerDepartmentProject
Page TitleCCBU D67 257Tuesday, August 29, 2023<project_name><Designer> GRANDTETON_SWB_20230829067 PEX_SDB_UART_LEVEL_SHIFTER<Reviewer>SizeDoc NumberRevDate: SheetofReviewerDesignerDepartmentProject
Page TitleCCBU D67 257Tuesday, August 29, 2023<project_name><Designer> GRANDTETON_SWB_20230829067 PEX_SDB_UART_LEVEL_SHIFTER<Reviewer>
R9374.7KR0402-02011%R9644.7KR0402-02011%C26050.1UF10%16VC0402-0201R94133R9264.7KR0402-02011%R93422U103SN74LVC2G07DCKR<Part Number>1A12A31Y62Y4GND2VCC5
C26040.1UF10%16VC0402-0201U101SN74LVC2G07DCKR<Part Number>1A12A31Y62Y4GND2VCC5R9360R9314.7KR0402-02011%R9700R9384.7KR0402-02011%R9434.7KR0402-02011%R9660C26060.1UF10%16VC0402-0201U102SN74LVC2G07DCKR<Part Number>1A12A31Y62Y4GND2VCC5R96522R0402-0201R9330 R9350U100SN74LVC2G07DCKR<Part Number>1A12A31Y62Y4GND2VCC5
R96922R0402-0201
R93033R9324.7KR0402-02011%R9254.7KR0402-02011%R94233C26070.1UF10%16VC0402-0201
R92933UART_PEX0_SDB_R_RXUART_PEX0_SDB_BUF_R_RXUART_PEX1_SDB_R_RXUART_PEX1_SDB_BUF_R_RXUART_PEX0_SDB_R_TXUART_PEX0_SDB_BUF_R_TXUART_PEX1_SDB_R_TXUART_PEX1_SDB_BUF_R_TXUART_PEX2_SDB_R_RXUART_PEX2_SDB_BUF_R_RXUART_PEX3_SDB_R_RXUART_PEX3_SDB_BUF_R_RXUART_PEX2_SDB_R_TXUART_PEX2_SDB_BUF_R_TXUART_PEX3_SDB_R_TXUART_PEX3_SDB_BUF_R_TXUART_PEX0_SDB_TXUART_PEX1_SDB_TXUART_PEX2_SDB_TXUART_PEX3_SDB_TXUART_PEX3_SDB_BUF_TXUART_PEX2_SDB_BUF_TXUART_PEX2_SDB_BUF_RXUART_PEX3_SDB_BUF_RXUART_PEX0_SDB_BUF_TXUART_PEX1_SDB_BUF_TXUART_PEX0_SDB_BUF_RXUART_PEX1_SDB_BUF_RX



5
5
4
4
3
3
2
2
1
1
D D
C C
B B
A A
PEX_CLI_UART_LEVEL_SHIFTER
Design Note: 1. Level shifter2. Prevent power leakage
FT4232
PEX
OPEN DRAIN
OPEN DRAIN
OPEN DRAIN
OPEN DRAIN
PEX
PEX
FT4232
FT4232
FT4232
PEX
PVT2_BOM_CHANGEPVT2_BOM_CHANGEPVT2_BOM_CHANGE
UART_PEX0_CLI_BUF_RX [15]UART_PEX1_CLI_BUF_RX [28]UART_PEX0_CLI_TX[15]UART_PEX0_CLI_BUF_TX [65]UART_PEX1_CLI_TX[28]UART_PEX1_CLI_BUF_TX [65]UART_PEX2_CLI_BUF_RX [41]UART_PEX3_CLI_BUF_RX [54]UART_PEX2_CLI_TX[41]UART_PEX2_CLI_BUF_TX [65]UART_PEX3_CLI_TX[54]UART_PEX3_CLI_BUF_TX [65]
UART_PEX0_CLI_R_RX[65,123]UART_PEX1_CLI_R_RX[65,123]UART_PEX2_CLI_R_RX[65,123]UART_PEX3_CLI_R_RX[65,123]UART_PEX0_CLI_BUF_R_TX [123]UART_PEX1_CLI_BUF_R_TX [123]UART_PEX2_CLI_BUF_R_TX [123]UART_PEX3_CLI_BUF_R_TX [123]
P3V3_AUXP1V8_PEXP1V8_PEXP3V3_AUXP3V3_AUXP1V8_PEXP1V8_PEXP3V3_AUXSizeDoc NumberRevDate: SheetofReviewerDesignerDepartmentProject
Page TitleCCBU D68 257Tuesday, August 29, 2023<project_name><Designer> GRANDTETON_SWB_20230829068 PEX_CLI_UART_LEVEL_SHIFTER<Reviewer>SizeDoc NumberRevDate: SheetofReviewerDesignerDepartmentProject
Page TitleCCBU D68 257Tuesday, August 29, 2023<project_name><Designer> GRANDTETON_SWB_20230829068 PEX_CLI_UART_LEVEL_SHIFTER<Reviewer>SizeDoc NumberRevDate: SheetofReviewerDesignerDepartmentProject
Page TitleCCBU D68 257Tuesday, August 29, 2023<project_name><Designer> GRANDTETON_SWB_20230829068 PEX_CLI_UART_LEVEL_SHIFTER<Reviewer>
R9714.7KR0402-02011%R99133R0402-0201R99322R0402-0201R99622R0402-0201
R98133R0402-0201C26110.1UF10%16VC0402-0201
R9724.7KR0402-02011%
R99822R0402-0201R9944.7KR0402-02011%U105SN74LVC2G07DCKR<Part Number>1A12A31Y62Y4GND2VCC5R9990R0402-0201R9954.7KR0402-02011%R9850R0402-0201C26100.1UF10%16VC0402-0201R9884.7KR0402-02011%U104SN74LVC2G07DCKR<Part Number>1A12A31Y62Y4GND2VCC5R98422R0402-0201R9894.7KR0402-02011%R98033R0402-0201R98622R0402-0201U107SN74LVC2G07DCKR<Part Number>1A12A31Y62Y4GND2VCC5C26090.1UF10%16VC0402-0201R9970R0402-0201R9824.7KR0402-02011%R9870R0402-0201R9834.7KR0402-02011%C26080.1UF10%16VC0402-0201U106SN74LVC2G07DCKR<Part Number>1A12A31Y62Y4GND2VCC5UART_PEX0_CLI_R_RXUART_PEX0_CLI_BUF_R_RXUART_PEX0_CLI_BUF_RXUART_PEX1_CLI_R_RXUART_PEX1_CLI_BUF_R_RXUART_PEX1_CLI_BUF_RXUART_PEX0_CLI_TXUART_PEX0_CLI_R_TXUART_PEX0_CLI_BUF_R_TXUART_PEX0_CLI_BUF_TXUART_PEX1_CLI_TXUART_PEX1_CLI_R_TXUART_PEX1_CLI_BUF_R_TXUART_PEX1_CLI_BUF_TXUART_PEX2_CLI_R_RXUART_PEX2_CLI_BUF_R_RXUART_PEX2_CLI_BUF_RXUART_PEX3_CLI_R_RXUART_PEX3_CLI_BUF_R_RXUART_PEX3_CLI_BUF_RXUART_PEX2_CLI_TXUART_PEX2_CLI_R_TXUART_PEX2_CLI_BUF_R_TXUART_PEX2_CLI_BUF_TXUART_PEX3_CLI_TXUART_PEX3_CLI_R_TXUART_PEX3_CLI_BUF_R_TXUART_PEX3_CLI_BUF_TX



5
5
4
4
3
3
2
2
1
1
D D
C C
B B
A A
BLANK SizeDoc NumberRevDate: SheetofReviewerDesignerDepartmentProject
Page TitleCCBU D69 257Tuesday, August 29, 2023<project_name><Designer> GRANDTETON_SWB_20230829069 BLANK<Reviewer>SizeDoc NumberRevDate: SheetofReviewerDesignerDepartmentProject
Page TitleCCBU D69 257Tuesday, August 29, 2023<project_name><Designer> GRANDTETON_SWB_20230829069 BLANK<Reviewer>SizeDoc NumberRevDate: SheetofReviewerDesignerDepartmentProject
Page TitleCCBU D69 257Tuesday, August 29, 2023<project_name><Designer> GRANDTETON_SWB_20230829069 BLANK<Reviewer>



5
5
4
4
3
3
2
2
1
1
D D
C C
B B
A A
H D Connected to Y
USB to UART for PEX Debug Jumper(1-2) : from Micro-USBJumper(2-3) : from FIODefault is Micro-USB
PI3USB103ZLE
FunctionInput
M Connected to YL
USB_HUB_I2C only for EEPROM.Remove I2C.
Port0   is to Debug port ( HOST )Port1,2 is to PEX
12M CystalMain:  BG6120000E02nd  : BG6120000B0 
PEX_USB_HUB
DVT_CHANGE
PVT_CHANGE
MP_CHANGEUSB2_MICRO_DN[70]USB2_MICRO_DP[70]PEX_USB2_SEL [70]PWRGD_P3V3_AUX_MUX_R_N[70]PEX_USB2_SEL[70]USB2_PEX_HUB_DP [70]USB2_MICRO_DN[70]USB2_PEX_HUB_DN [70]USB2_MICRO_DP[70]USB2_FIO_DN[211]USB2_FIO_DP[211]
USB2_FT4232_SDB_DP [64]USB2_FT4232_SDB_DN [64]USB2_FT4232_CLI_DP [65]USB2_FT4232_CLI_DN [65]USB2_PEX_HUB_DP [70]USB2_PEX_HUB_DN [70]PWRGD_P3V3_AUX_MUX_R_N [70]PWRGD_P3V3_AUX_R[118,121,221]RST_PEX_USB_HUB_R_N[87]PEX_USB_HUB_PSELF[70]PEX_USB_HUB_PSELF [70]USB2_FT4232_SDB_R_DP [122]USB2_FT4232_SDB_R_DN [122]USB2_FT4232_CLI_R_DP [123]USB2_FT4232_CLI_R_DN [123]
P3V3_AUXP3V3_AUXP3V3_AUXP3V3_AUXP3V3_AUXP3V3_AUXP3V3_PEX_USB_HUBP3V3_AUXSizeDoc NumberRevDate: SheetofReviewerDesignerDepartmentProject
Page TitleCCBU D70 257Tuesday, August 29, 2023<project_name><Designer> GRANDTETON_SWB_20230829070 PEX_USB_HUB<Reviewer>SizeDoc NumberRevDate: SheetofReviewerDesignerDepartmentProject
Page TitleCCBU D70 257Tuesday, August 29, 2023<project_name><Designer> GRANDTETON_SWB_20230829070 PEX_USB_HUB<Reviewer>SizeDoc NumberRevDate: SheetofReviewerDesignerDepartmentProject
Page TitleCCBU D70 257Tuesday, August 29, 2023<project_name><Designer> GRANDTETON_SWB_20230829070 PEX_USB_HUB<Reviewer>C26171UF25VX6S10%C0402-0201<Part Number>U110PI3USB103ZLE<Part Number>Y+1GND3M-4D-6OE#8VDD9SEL10Y-2M+5D+7
R628649.91%NIR544010K1/16W1%R0402-0201<Part Number>R544110K1/16W1%R0402-0201<Part Number>NIC26180.1UFX7R25V10%C0402-0201<Part Number>R543947K1/16W0.1%R0402-0201<Part Number>NIR1006 0R0402-0201 1/16WC26190.1UFX7R25V10%C0402-0201<Part Number>R6843 2K1/16W 1% R0402-0201
D
G
S
Q1242N7002KW<Part Number>DGSC26150.1UFX7R25V10%C0402-0201<Part Number>R1010 0 R0402-02015%C262218PFC0402-02015%50V<Part Number>R1021 10K 1/16W 1%R0402-0201 <Part Number>NI R628849.91%NI
J4_12<Part Number>1
R1008 0 R0402-02015%
R10021K1%R0402-0201C26120.1UFX7R16V10%C0402-0201<Part Number>
C26241UF<Part Number>C0402-020110%25VX6S
U108PRTR5V0U2X<Part Number>NIIO12GND1VCC4IO23C26200.1UFX7R25V10%C0402-0201<Part Number>R10184.7K 1% 1/16W R0402-0201NIC26211UF25VX6S10%C0402-0201<Part Number>R1022100K<Part Number>R0402-02011%1/16WC262318PFC0402-02015%50V<Part Number>U112GL852G-OHY60<Part Number>X110X211TEST||SCL18SDA26V527V3328AVDD5AVDD9AVDD14DVDD21THTHOVCUR1#||SMC25OVCUR2#||SMD24OVCUR3#20OVCUR4#19RESET#17PGANG23PSELF22RREF8DP02DM01DP14DM13DP27DM26DP313DM312DP416DM415R1017 0 R04025%UART_BOM1
J4SCONN3_TSM-103-01-S-SV-TR123 C26130.1UFX7R16V10%C0402-0201<Part Number>NI
R628549.9<Part Number>R04021%NI
R1001 0 R0402-02015%NIR1000 0 R0402-02015%NI1 2 3 4 5J54SCONN5_105133-0011NIVBUS1GND5D-2D+3ID4G1G1G2G2G3G3R10050R0402-02015%<Part Number>R1019 680<Part Number>1%R0402-0201R1013 0 R04025%UART_BOM1R10124.7K 1% 1/16W R0402-0201NIR1015 0 R04025%UART_BOM1R100910K1/16W1%R0402-0201<Part Number>C261410UFX6SC0402-020120%6.3V<Part Number>R628749.91%NIR10164.7K 1% 1/16W R0402-0201NIR1011 0 R04025%UART_BOM1Y512MHZX11G12G24X23C26160.1UFX7R25V10%C0402-0201<Part Number>R1007 0 R0402-02015%R10144.7K 1% 1/16W R0402-0201NI
R1003100K1/16W1%R0402-0201R10044.7K<Part Number>1%R0402-0201USB_VBUS_CONNUSB2_FT4232_MUX_D_DNUSB2_FT4232_MUX_D_DPPEX_USB2_SEL_CONN
PEX_USB_HUB_TESTPEX_USB_HUB_XINPEX_USB_HUB_XOUT_RPEX_USB_HUB_OVCUR4PEX_USB_HUB_OVCUR3PEX_USB_HUB_OVCUR2PEX_USB_HUB_OVCUR1USB2_FT4232_SDB_R_DPUSB2_FT4232_SDB_DPUSB2_FT4232_SDB_R_DNUSB2_FT4232_SDB_DNUSB2_FT4232_CLI_R_DPUSB2_FT4232_CLI_DPUSB2_FT4232_CLI_R_DNUSB2_FT4232_CLI_DNUSB2_PEX_HUB_R_DPUSB2_PEX_HUB_DPUSB2_PEX_HUB_R_DNUSB2_PEX_HUB_DNPEX_USB_HUB_RREFRST_PEX_USB_HUB_R_NPEX_USB_HUB_PSELFPEX_USB_HUB_PGANGPWRGD_P3V3_AUX_MUX_N
PEX_USB_HUB_PSELFPEX_USB_HUB_XOUT



5
5
4
4
3
3
2
2
1
1
D D
C C
B B
A A
BLANK SizeDoc NumberRevDate: SheetofReviewerDesignerDepartmentProject
Page TitleCCBU D71 257Tuesday, August 29, 2023<project_name><Designer> GRANDTETON_SWB_20230829071 BLANK<Reviewer>SizeDoc NumberRevDate: SheetofReviewerDesignerDepartmentProject
Page TitleCCBU D71 257Tuesday, August 29, 2023<project_name><Designer> GRANDTETON_SWB_20230829071 BLANK<Reviewer>SizeDoc NumberRevDate: SheetofReviewerDesignerDepartmentProject
Page TitleCCBU D71 257Tuesday, August 29, 2023<project_name><Designer> GRANDTETON_SWB_20230829071 BLANK<Reviewer>



5
5
4
4
3
3
2
2
1
1
D D
C C
B B
A A
I2C address: 0x42
I2C address: 0x40
SSD1
SSD0
NIC0
SSD2
SSD3
NIC1
PUSH-PULLINTERNAL WEAK PULL_UP
PUSH-PULLINTERNAL WEAK PULL_UP
PEX0_PCA9555
DVT_CHANGE
De-pop design, Due to doesn't follow BRCM SPEC pin definion.
PRSNT_SSD0_FPGA_R_N [117]SSD0_PEX_PWR_EN_R [117]RST_PEX_SSD0_PERST_R_N [117]SMB_PEX0_PCA9555_SDA[16,72]SMB_PEX0_PCA9555_SCL[16,72]SMB_PEX0_PCA9555_SDA[16,72]SMB_PEX0_PCA9555_SCL[16,72]PRSNT_SSD2_FPGA_R_N [117]SSD2_PEX_PWR_EN_R [117]RST_PEX_SSD2_PERST_R_N [117]PEX0_PCA9555_0_INT_N[72]PEX0_PCA9555_1_INT_N[72]PRSNT_SSD1_FPGA_R_N [117]SSD1_PEX_PWR_EN_R [117]RST_PEX_SSD1_PERST_R_N [117]PRSNT_NIC0_FPGA_R_N [116]NIC0_PEX_PWR_EN_R [116]RST_PEX_NIC0_PERST_R_N [116]PRSNT_SSD3_FPGA_R_N [117]SSD3_PEX_PWR_EN_R [117]RST_PEX_SSD3_PERST_R_N [117]PRSNT_NIC1_FPGA_R_N [116]NIC1_PEX_PWR_EN_R [116]RST_PEX_NIC1_PERST_R_N [116]PEX0_PCA9555_INT_R_N[15]PEX0_PCA9555_0_INT_N [72]PEX0_PCA9555_1_INT_N [72]P3V3_AUXP3V3_AUXP3V3_AUXP3V3_AUXP3V3_AUXP3V3_AUXP3V3_AUXP3V3_AUXP3V3_AUXP3V3_AUXP3V3_AUXP3V3_AUXP3V3_AUXP3V3_AUXP1V8_PEXP3V3_AUXP3V3_AUXP1V8_PEX
SizeDoc NumberRevDate: SheetofReviewerDesignerDepartmentProject
Page TitleCCBU D72 257Tuesday, August 29, 2023<project_name><Designer> GRANDTETON_SWB_20230829072 PEX0_PCA9555<Reviewer>SizeDoc NumberRevDate: SheetofReviewerDesignerDepartmentProject
Page TitleCCBU D72 257Tuesday, August 29, 2023<project_name><Designer> GRANDTETON_SWB_20230829072 PEX0_PCA9555<Reviewer>SizeDoc NumberRevDate: SheetofReviewerDesignerDepartmentProject
Page TitleCCBU D72 257Tuesday, August 29, 2023<project_name><Designer> GRANDTETON_SWB_20230829072 PEX0_PCA9555<Reviewer>R46384.7KR0402-02015%NIR46564.7KR0402-02015%NIR46374.7KR0402-02015%NIR46004.7KR0402-02011%1/16WNI
R4652 0 5%1/16WNI
R46152K1/16W1%R0402-0201NIC35970.1UFC0402-020116V10%X7RNIR4642 0 5%1/16WNI
R46044.7KR0402-02011%1/16WNI
R46554.7KR0402-02015%NI
R46112K1/16W1%R0402-0201NIR4628 0 5%1/16WNIR4617 0 5%1/16WNIR46014.7KR0402-02011%1/16WNIR46054.7KR0402-02011%1/16WNIR4625 0 5%1/16WNIR46204.7KR0402-02015%NI R4646 0 5%1/16WNI
R46024.7KR0402-02011%1/16WNI
R4643 0 5%1/16WNIR46162K1/16W1%<Part Number>R0402-0201NIR46064.7KR0402-02011%1/16WNI
U344PCA9555APWNIVDD24VSS12INT#1SDA23SCL22P0_04P0_15P0_26P0_37P0_48P0_59P0_610P0_711P1_013P1_114P1_215P1_316P1_417P1_518P1_619P1_720A021A12A23R46214.7KR0402-02015%NI R4629 0 5%1/16WNIR4631 0 5%1/16WNIR46034.7KR0402-02011%1/16W<Part Number>NI
R4647 0 5%1/16WNI
R46074.7KR0402-02011%1/16WNI
C35980.1UFC0402-020116V10%X7RNIR46224.7KR0402-02015%NIR46122K1/16W1%R0402-0201NIR4644 0 5%1/16WNI
R46084.7KR0402-02011%1/16WNIR4632 0 5%1/16WNIR4623 0 5%1/16WNIR46394.7KR0402-02015%NI
R46094.7KR0402-02011%1/16WNI
R4648 0 5%1/16WNIR4650 0 5%1/16WNIR46132K1/16W1%R0402-0201NIR46404.7KR0402-02015%NIR4610 0 5%1/16WR0402-0201NIR4633 0 5%1/16WNIR46354.7KR0402-02015%NIR46414.7KR0402-02015%NI
R45984.7KR0402-02011%1/16WNI
R4651 0 5%1/16WNIU343PCA9555APWNIVDD24VSS12INT#1SDA23SCL22P0_04P0_15P0_26P0_37P0_48P0_59P0_610P0_711P1_013P1_114P1_215P1_316P1_417P1_518P1_619P1_720A021A12A23R46142K1/16W1%R0402-0201NIR46364.7KR0402-02015%NIR4618 0 5%1/16WNIR45994.7KR0402-02011%1/16WNIR4627 0 5%1/16WNIR4624 0 5%1/16WNIR46544.7KR0402-02015%NIR46194.7KR0402-02015%NIRST_PEX_SSD0_PERST_R_NSSD0_PEX_PWR_EN_RRST_PEX_SSD1_PERST_R_NSSD1_PEX_PWR_EN_RRST_PEX_SSD2_PERST_R_NSSD2_PEX_PWR_EN_RRST_PEX_SSD3_PERST_R_NSSD3_PEX_PWR_EN_RRST_PEX_NIC0_PERST_R_NNIC0_PEX_PWR_EN_RRST_PEX_NIC1_PERST_R_NNIC1_PEX_PWR_EN_RPRSNT_SSD0_FPGA_PCA9555_NSSD0_PEX_PWR_ENRST_PEX_SSD0_PERST_NPCA9555_0_PEX0_A0PCA9555_0_PEX0_A1PCA9555_0_PEX0_A2PCA9555_1_PEX0_A0PCA9555_1_PEX0_A1PCA9555_1_PEX0_A2PRSNT_SSD0_FPGA_R_NSSD0_PEX_PWR_EN_RRST_PEX_SSD0_PERST_R_NPRSNT_SSD2_FPGA_PCA9555_NPRSNT_SSD2_FPGA_R_NSSD2_PEX_PWR_ENSSD2_PEX_PWR_EN_RRST_PEX_SSD2_PERST_NRST_PEX_SSD2_PERST_R_NPEX0_PCA9555_0_INT_NPEX0_PCA9555_1_INT_NPRSNT_SSD1_FPGA_PCA9555_NPRSNT_SSD1_FPGA_R_NSSD1_PEX_PWR_ENSSD1_PEX_PWR_EN_RRST_PEX_SSD1_PERST_NRST_PEX_SSD1_PERST_R_NPRSNT_NIC0_FPGA_PCA9555_NPRSNT_NIC0_FPGA_R_NNIC0_PEX_PWR_ENNIC0_PEX_PWR_EN_RRST_PEX_NIC0_PERST_NRST_PEX_NIC0_PERST_R_NPRSNT_SSD3_FPGA_PCA9555_NPRSNT_SSD3_FPGA_R_NSSD3_PEX_PWR_ENSSD3_PEX_PWR_EN_RRST_PEX_SSD3_PERST_NRST_PEX_SSD3_PERST_R_NPRSNT_NIC1_FPGA_PCA9555_NPRSNT_NIC1_FPGA_R_NNIC1_PEX_PWR_ENNIC1_PEX_PWR_EN_RRST_PEX_NIC1_PERST_NRST_PEX_NIC1_PERST_R_NPEX0_PCA9555_INT_N



5
5
4
4
3
3
2
2
1
1
D D
C C
B B
A A
I2C address: 0x42
I2C address: 0x40
SSD7
NIC3
NIC2
SSD5
SSD4
SSD6
PUSH-PULLINTERNAL WEAK PULL_UP
PUSH-PULLINTERNAL WEAK PULL_UP
PEX1_PCA9555
DVT_CHANGE
De-pop design, Due to doesn't follow BRCM SPEC pin definion.
PRSNT_SSD4_FPGA_R_N [117]SSD4_PEX_PWR_EN_R [117]RST_PEX_SSD4_PERST_R_N [117]SMB_PEX1_PCA9555_SDA[29,73]SMB_PEX1_PCA9555_SCL[29,73]SMB_PEX1_PCA9555_SDA[29,73]SMB_PEX1_PCA9555_SCL[29,73]PRSNT_SSD6_FPGA_R_N [117]SSD6_PEX_PWR_EN_R [117]RST_PEX_SSD6_PERST_R_N [117]PEX1_PCA9555_0_INT_N[73]PEX1_PCA9555_1_INT_N[73]PRSNT_SSD5_FPGA_R_N [117]SSD5_PEX_PWR_EN_R [117]RST_PEX_SSD5_PERST_R_N [117]PRSNT_NIC2_FPGA_R_N [116]NIC2_PEX_PWR_EN_R [116]RST_PEX_NIC2_PERST_R_N [116]PRSNT_SSD7_FPGA_R_N [118]SSD7_PEX_PWR_EN_R [118]RST_PEX_SSD7_PERST_R_N [118]PRSNT_NIC3_FPGA_R_N [116]NIC3_PEX_PWR_EN_R [116]RST_PEX_NIC3_PERST_R_N [116]PEX1_PCA9555_0_INT_N [73]PEX1_PCA9555_INT_R_N[28]PEX1_PCA9555_1_INT_N [73]P3V3_AUXP3V3_AUXP3V3_AUXP3V3_AUXP3V3_AUXP3V3_AUXP3V3_AUXP3V3_AUXP3V3_AUXP3V3_AUXP3V3_AUXP3V3_AUXP3V3_AUXP3V3_AUXP1V8_PEXP3V3_AUXP3V3_AUXP1V8_PEX
SizeDoc NumberRevDate: SheetofReviewerDesignerDepartmentProject
Page TitleCCBU D73 257Tuesday, August 29, 2023<project_name><Designer> GRANDTETON_SWB_20230829073 PEX1_PCA9555<Reviewer>SizeDoc NumberRevDate: SheetofReviewerDesignerDepartmentProject
Page TitleCCBU D73 257Tuesday, August 29, 2023<project_name><Designer> GRANDTETON_SWB_20230829073 PEX1_PCA9555<Reviewer>SizeDoc NumberRevDate: SheetofReviewerDesignerDepartmentProject
Page TitleCCBU D73 257Tuesday, August 29, 2023<project_name><Designer> GRANDTETON_SWB_20230829073 PEX1_PCA9555<Reviewer>
R46782K1/16W1%R0402-0201NIU345PCA9555APWNIVDD24VSS12INT#1SDA23SCL22P0_04P0_15P0_26P0_37P0_48P0_59P0_610P0_711P1_013P1_114P1_215P1_316P1_417P1_518P1_619P1_720A021A12A23 R46714.7KR0402-02011%1/16WNI
R47044.7KR0402-02015%NI R4714 0 5%1/16WNIR4711 0 5%1/16WNI
R46704.7KR0402-02011%1/16WNIR4688 0 5%1/16WNIR4692 0 5%1/16WNIR4694 0 5%1/16WNIR4673 0 5%1/16WR0402-0201NIR4686 0 5%1/16WNIR46762K1/16W1%R0402-0201NIR47004.7KR0402-02015%NI R4705 0 5%1/16WNIR46834.7KR0402-02015%NIR46614.7KR0402-02011%1/16WNI
R4715 0 5%1/16WNI
R46634.7KR0402-02011%1/16WNIR4695 0 5%1/16WNIR46752K1/16W1%R0402-0201NIR46742K1/16W1%R0402-0201NIR46724.7KR0402-02011%1/16WNIR4687 0 5%1/16WNIR47194.7KR0402-02015%NI
R4680 0 5%1/16WNIR4709 0 5%1/16WNIC36000.1UFC0402-020116V10%X7RNI
R46684.7KR0402-02011%1/16WNI
R47174.7KR0402-02015%NI
R46624.7KR0402-02011%1/16WNI
U346PCA9555APWNIVDD24VSS12INT#1SDA23SCL22P0_04P0_15P0_26P0_37P0_48P0_59P0_610P0_711P1_013P1_114P1_215P1_316P1_417P1_518P1_619P1_720A021A12A23R4681 0 5%1/16WNIR46792K1/16W1%<Part Number>R0402-0201NIR46844.7KR0402-02015%NIR47014.7KR0402-02015%NI R4696 0 5%1/16WNIR46772K1/16W1%R0402-0201NIR4707 0 5%1/16WNIR4710 0 5%1/16WNI
R46674.7KR0402-02011%1/16WNIR46994.7KR0402-02015%NI R4690 0 5%1/16WNIR46854.7KR0402-02015%NIR46984.7KR0402-02015%NIR46824.7KR0402-02015%NI R4706 0 5%1/16WNI
R46644.7KR0402-02011%1/16WNI
R47034.7KR0402-02015%NIR47024.7KR0402-02015%NIC35990.1UFC0402-020116V10%X7RNIR46664.7KR0402-02011%1/16W<Part Number>NI
R4713 0 5%1/16WNIR4691 0 5%1/16WNIR47184.7KR0402-02015%NI
R46654.7KR0402-02011%1/16WNIR46694.7KR0402-02011%1/16WNIRST_PEX_SSD4_PERST_R_NSSD4_PEX_PWR_EN_RRST_PEX_SSD5_PERST_R_NSSD5_PEX_PWR_EN_RRST_PEX_SSD6_PERST_R_NSSD6_PEX_PWR_EN_RRST_PEX_SSD7_PERST_R_NSSD7_PEX_PWR_EN_RRST_PEX_NIC2_PERST_R_NNIC2_PEX_PWR_EN_RRST_PEX_NIC3_PERST_R_NNIC3_PEX_PWR_EN_RPRSNT_SSD4_FPGA_PCA9555_NSSD4_PEX_PWR_ENRST_PEX_SSD4_PERST_NPCA9555_0_PEX1_A0PCA9555_0_PEX1_A1PCA9555_0_PEX1_A2PCA9555_1_PEX1_A0PCA9555_1_PEX1_A1PCA9555_1_PEX1_A2PRSNT_SSD4_FPGA_R_NSSD4_PEX_PWR_EN_RRST_PEX_SSD4_PERST_R_NPRSNT_SSD6_FPGA_PCA9555_NPRSNT_SSD6_FPGA_R_NSSD6_PEX_PWR_ENSSD6_PEX_PWR_EN_RRST_PEX_SSD6_PERST_NRST_PEX_SSD6_PERST_R_NPEX1_PCA9555_0_INT_NPEX1_PCA9555_1_INT_NPRSNT_SSD5_FPGA_PCA9555_NPRSNT_SSD5_FPGA_R_NSSD5_PEX_PWR_ENSSD5_PEX_PWR_EN_RRST_PEX_SSD5_PERST_NRST_PEX_SSD5_PERST_R_NPRSNT_NIC2_FPGA_PCA9555_NPRSNT_NIC2_FPGA_R_NNIC2_PEX_PWR_ENNIC2_PEX_PWR_EN_RRST_PEX_NIC2_PERST_NRST_PEX_NIC2_PERST_R_NPRSNT_SSD7_FPGA_PCA9555_NPRSNT_SSD7_FPGA_R_NSSD7_PEX_PWR_ENSSD7_PEX_PWR_EN_RRST_PEX_SSD7_PERST_NRST_PEX_SSD7_PERST_R_NPRSNT_NIC3_FPGA_PCA9555_NPRSNT_NIC3_FPGA_R_NNIC3_PEX_PWR_ENNIC3_PEX_PWR_EN_RRST_PEX_NIC3_PERST_NRST_PEX_NIC3_PERST_R_NPEX1_PCA9555_INT_N



5
5
4
4
3
3
2
2
1
1
D D
C C
B B
A A
I2C address: 0x42
I2C address: 0x40
SSD9
SSD11
SSD8
NIC5
SSD10
NIC4
PUSH-PULLINTERNAL WEAK PULL_UP
PUSH-PULLINTERNAL WEAK PULL_UP
PEX2_PCA9555
DVT_CHANGE
De-pop design, Due to doesn't follow BRCM SPEC pin definion.
PRSNT_SSD8_FPGA_R_N [118]SSD8_PEX_PWR_EN_R [118]RST_PEX_SSD8_PERST_R_N [118]SMB_PEX2_PCA9555_SDA[42,74]SMB_PEX2_PCA9555_SCL[42,74]SMB_PEX2_PCA9555_SDA[42,74]SMB_PEX2_PCA9555_SCL[42,74]PRSNT_SSD10_FPGA_R_N [118]SSD10_PEX_PWR_EN_R [118]RST_PEX_SSD10_PERST_R_N [118]PEX2_PCA9555_0_INT_N[74]PEX2_PCA9555_1_INT_N[74]PRSNT_SSD9_FPGA_R_N [118]SSD9_PEX_PWR_EN_R [118]RST_PEX_SSD9_PERST_R_N [118]PRSNT_NIC4_FPGA_R_N [116]NIC4_PEX_PWR_EN_R [116]RST_PEX_NIC4_PERST_R_N [116]PRSNT_SSD11_FPGA_R_N [118]SSD11_PEX_PWR_EN_R [118]RST_PEX_SSD11_PERST_R_N [118]PRSNT_NIC5_FPGA_R_N [116]NIC5_PEX_PWR_EN_R [116]RST_PEX_NIC5_PERST_R_N [116]
PEX2_PCA9555_0_INT_N [74]PEX2_PCA9555_INT_R_N[41]PEX2_PCA9555_1_INT_N [74]P3V3_AUXP3V3_AUXP3V3_AUXP3V3_AUXP3V3_AUXP3V3_AUXP3V3_AUXP3V3_AUXP3V3_AUXP3V3_AUXP3V3_AUXP3V3_AUXP3V3_AUXP3V3_AUXP3V3_AUXP3V3_AUXP1V8_PEXP1V8_PEX
SizeDoc NumberRevDate: SheetofReviewerDesignerDepartmentProject
Page TitleCCBU D74 257Tuesday, August 29, 2023<project_name><Designer> GRANDTETON_SWB_20230829074 PEX2_PCA9555<Reviewer>SizeDoc NumberRevDate: SheetofReviewerDesignerDepartmentProject
Page TitleCCBU D74 257Tuesday, August 29, 2023<project_name><Designer> GRANDTETON_SWB_20230829074 PEX2_PCA9555<Reviewer>SizeDoc NumberRevDate: SheetofReviewerDesignerDepartmentProject
Page TitleCCBU D74 257Tuesday, August 29, 2023<project_name><Designer> GRANDTETON_SWB_20230829074 PEX2_PCA9555<Reviewer>
R4759 0 5%1/16WNIR47402K1/16W1%R0402-0201NIR47392K1/16W1%R0402-0201NIR4773 0 5%1/16WNI
R47354.7KR0402-02011%1/16WNIR4750 0 5%1/16WNIR47824.7KR0402-02015%NIC36020.1UFC0402-020116V10%X7RNI
R47314.7KR0402-02011%1/16WNI
R47674.7KR0402-02015%NIR47804.7KR0402-02015%NI
R47254.7KR0402-02011%1/16WNIR4753 0 5%1/16WNIU348PCA9555APWNIVDD24VSS12INT#1SDA23SCL22P0_04P0_15P0_26P0_37P0_48P0_59P0_610P0_711P1_013P1_114P1_215P1_316P1_417P1_518P1_619P1_720A021A12A23R47442K1/16W1%<Part Number>R0402-0201NIR47644.7KR0402-02015%NIR47474.7KR0402-02015%NIR47422K1/16W1%R0402-0201NIR4770 0 5%1/16WNIR4774 0 5%1/16WNIR4776 0 5%1/16WNI
R47304.7KR0402-02011%1/16WNIR47624.7KR0402-02015%NI R4754 0 5%1/16WNIR47614.7KR0402-02015%NIR47464.7KR0402-02015%NI R4769 0 5%1/16WNIR4777 0 5%1/16WNI
R47274.7KR0402-02011%1/16WNI
R47664.7KR0402-02015%NIC36010.1UFC0402-020116V10%X7RNIR47294.7KR0402-02011%1/16W<Part Number>NIR47484.7KR0402-02015%NIR4755 0 5%1/16WNIR4757 0 5%1/16WNIR47814.7KR0402-02015%NI
R4736 0 5%1/16WR0402-0201NIR47284.7KR0402-02011%1/16WNIR47324.7KR0402-02011%1/16WNIR47432K1/16W1%R0402-0201NIU347PCA9555APWNIVDD24VSS12INT#1SDA23SCL22P0_04P0_15P0_26P0_37P0_48P0_59P0_610P0_711P1_013P1_114P1_215P1_316P1_417P1_518P1_619P1_720A021A12A23R4778 0 5%1/16WNI
R47344.7KR0402-02011%1/16WNI
R47654.7KR0402-02015%NI
R47334.7KR0402-02011%1/16WNIR4758 0 5%1/16WNIR4751 0 5%1/16WNIR47412K1/16W1%R0402-0201NIR4737 0 5%1/16WNI R4749 0 5%1/16WNIR47634.7KR0402-02015%NI R4772 0 5%1/16WNIR4768 0 5%1/16WNIR47454.7KR0402-02015%NIR47244.7KR0402-02011%1/16WNIR4738 0 5%1/16WNIR47264.7KR0402-02011%1/16WNIRST_PEX_SSD8_PERST_R_NSSD8_PEX_PWR_EN_RRST_PEX_SSD9_PERST_R_NSSD9_PEX_PWR_EN_RRST_PEX_SSD10_PERST_R_NSSD10_PEX_PWR_EN_RRST_PEX_SSD11_PERST_R_NSSD11_PEX_PWR_EN_RRST_PEX_NIC4_PERST_R_NNIC4_PEX_PWR_EN_RRST_PEX_NIC5_PERST_R_NNIC5_PEX_PWR_EN_RPRSNT_SSD8_FPGA_PCA9555_NSSD8_PEX_PWR_ENRST_PEX_SSD8_PERST_NPCA9555_0_PEX2_A0PCA9555_0_PEX2_A1PCA9555_0_PEX2_A2PCA9555_1_PEX2_A0PCA9555_1_PEX2_A1PCA9555_1_PEX2_A2PRSNT_SSD8_FPGA_R_NSSD8_PEX_PWR_EN_RRST_PEX_SSD8_PERST_R_NPRSNT_SSD10_FPGA_PCA9555_NPRSNT_SSD10_FPGA_R_NSSD10_PEX_PWR_ENSSD10_PEX_PWR_EN_RRST_PEX_SSD10_PERST_NRST_PEX_SSD10_PERST_R_NPEX2_PCA9555_0_INT_NPEX2_PCA9555_1_INT_NPRSNT_SSD9_FPGA_PCA9555_NPRSNT_SSD9_FPGA_R_NSSD9_PEX_PWR_ENSSD9_PEX_PWR_EN_RRST_PEX_SSD9_PERST_NRST_PEX_SSD9_PERST_R_NPRSNT_NIC4_FPGA_PCA9555_NPRSNT_NIC4_FPGA_R_NNIC4_PEX_PWR_ENNIC4_PEX_PWR_EN_RRST_PEX_NIC4_PERST_NRST_PEX_NIC4_PERST_R_NPRSNT_SSD11_FPGA_PCA9555_NPRSNT_SSD11_FPGA_R_NSSD11_PEX_PWR_ENSSD11_PEX_PWR_EN_RRST_PEX_SSD11_PERST_NRST_PEX_SSD11_PERST_R_NPRSNT_NIC5_FPGA_PCA9555_NPRSNT_NIC5_FPGA_R_NNIC5_PEX_PWR_ENNIC5_PEX_PWR_EN_RRST_PEX_NIC5_PERST_NRST_PEX_NIC5_PERST_R_NPEX2_PCA9555_INT_N



5
5
4
4
3
3
2
2
1
1
D D
C C
B B
A A
I2C address: 0x42
I2C address: 0x40
Change to PCA9555, check SPEC
SSD13
SSD15
SSD12
NIC7
SSD14
NIC6
PUSH-PULLINTERNAL WEAK PULL_UP
PUSH-PULLINTERNAL WEAK PULL_UP
PEX3_PCA9555
DVT_CHANGE
De-pop design, Due to doesn't follow BRCM SPEC pin definion.
PRSNT_SSD12_FPGA_R_N [118]SSD12_PEX_PWR_EN_R [118]RST_PEX_SSD12_PERST_R_N [118]SMB_PEX3_PCA9555_SDA[55,75]SMB_PEX3_PCA9555_SCL[55,75]SMB_PEX3_PCA9555_SDA[55,75]SMB_PEX3_PCA9555_SCL[55,75]PRSNT_SSD14_FPGA_R_N [118]SSD14_PEX_PWR_EN_R [118]RST_PEX_SSD14_PERST_R_N [118]PEX3_PCA9555_0_INT_N[75]PEX3_PCA9555_1_INT_N[75]PRSNT_SSD13_FPGA_R_N [118]SSD13_PEX_PWR_EN_R [118]RST_PEX_SSD13_PERST_R_N [118]PRSNT_NIC6_FPGA_R_N [118]NIC6_PEX_PWR_EN_R [118]RST_PEX_NIC6_PERST_R_N [118]PRSNT_SSD15_FPGA_R_N [118]SSD15_PEX_PWR_EN_R [118]RST_PEX_SSD15_PERST_R_N [118]PRSNT_NIC7_FPGA_R_N [118]NIC7_PEX_PWR_EN_R [118]RST_PEX_NIC7_PERST_R_N [118]PEX3_PCA9555_0_INT_N [75]PEX3_PCA9555_INT_R_N[54]PEX3_PCA9555_1_INT_N [75]P3V3_AUXP3V3_AUXP3V3_AUXP3V3_AUXP3V3_AUXP3V3_AUXP3V3_AUXP3V3_AUXP3V3_AUXP3V3_AUXP3V3_AUXP3V3_AUXP3V3_AUXP3V3_AUXP3V3_AUXP3V3_AUXP1V8_PEXP1V8_PEX
SizeDoc NumberRevDate: SheetofReviewerDesignerDepartmentProject
Page TitleCCBU D75 257Tuesday, August 29, 2023<project_name><Designer> GRANDTETON_SWB_20230829075 PEX3_PCA9555<Reviewer>SizeDoc NumberRevDate: SheetofReviewerDesignerDepartmentProject
Page TitleCCBU D75 257Tuesday, August 29, 2023<project_name><Designer> GRANDTETON_SWB_20230829075 PEX3_PCA9555<Reviewer>SizeDoc NumberRevDate: SheetofReviewerDesignerDepartmentProject
Page TitleCCBU D75 257Tuesday, August 29, 2023<project_name><Designer> GRANDTETON_SWB_20230829075 PEX3_PCA9555<Reviewer>
R4799 0 5%1/16WR0402-0201NIR48244.7KR0402-02015%NIR48114.7KR0402-02015%NI R4841 0 5%1/16WNIR4832 0 5%1/16WNI
R47904.7KR0402-02011%1/16WNI
R48304.7KR0402-02015%NIR4821 0 5%1/16WNIR48294.7KR0402-02015%NIC36030.1UFC0402-020116V10%X7RNIR47924.7KR0402-02011%1/16W<Part Number>NI
R48444.7KR0402-02015%NI
R47914.7KR0402-02011%1/16WNI
R4835 0 5%1/16WNI
R47954.7KR0402-02011%1/16WNIR4807 0 5%1/16WNI R48062K1/16W1%R0402-0201NIU349PCA9555APWNIVDD24VSS12INT#1SDA23SCL22P0_04P0_15P0_26P0_37P0_48P0_59P0_610P0_711P1_013P1_114P1_215P1_316P1_417P1_518P1_619P1_720A021A12A23 R47974.7KR0402-02011%1/16WNI
R48284.7KR0402-02015%NIR4805 0 5%1/16WNIR4822 0 5%1/16WNIR47964.7KR0402-02011%1/16WNIR4814 0 5%1/16WNIR4836 0 5%1/16WNIR4812 0 5%1/16WNIR48022K1/16W1%R0402-0201NIR48264.7KR0402-02015%NIR48104.7KR0402-02015%NIR4831 0 5%1/16WNI
R47874.7KR0402-02011%1/16WNIR4816 0 5%1/16WNIR48084.7KR0402-02015%NIR47894.7KR0402-02011%1/16WNI
R4837 0 5%1/16WNIR48012K1/16W1%R0402-0201NIR4839 0 5%1/16WNIR48002K1/16W1%R0402-0201NIR47984.7KR0402-02011%1/16WNIR4813 0 5%1/16WNIR48454.7KR0402-02015%NI R4817 0 5%1/16WNIC36040.1UFC0402-020116V10%X7RNI
R47944.7KR0402-02011%1/16WNI
R48434.7KR0402-02015%NI
R47884.7KR0402-02011%1/16WNI
U350PCA9555APWNIVDD24VSS12INT#1SDA23SCL22P0_04P0_15P0_26P0_37P0_48P0_59P0_610P0_711P1_013P1_114P1_215P1_316P1_417P1_518P1_619P1_720A021A12A23R48042K1/16W1%<Part Number>R0402-0201NIR48274.7KR0402-02015%NIR48094.7KR0402-02015%NI R4840 0 5%1/16WNI
R48032K1/16W1%R0402-0201NIR4833 0 5%1/16WNIR4818 0 5%1/16WNIR47934.7KR0402-02011%1/16WNIR4820 0 5%1/16WNIR48254.7KR0402-02015%NI RST_PEX_SSD12_PERST_R_NSSD12_PEX_PWR_EN_RRST_PEX_SSD13_PERST_R_NSSD13_PEX_PWR_EN_RRST_PEX_SSD14_PERST_R_NSSD14_PEX_PWR_EN_RRST_PEX_SSD15_PERST_R_NSSD15_PEX_PWR_EN_RRST_PEX_NIC6_PERST_R_NNIC6_PEX_PWR_EN_RRST_PEX_NIC7_PERST_R_NNIC7_PEX_PWR_EN_RPRSNT_SSD12_FPGA_PCA9555_NSSD12_PEX_PWR_ENRST_PEX_SSD12_PERST_NPCA9555_0_PEX3_A0PCA9555_0_PEX3_A1PCA9555_0_PEX3_A2PCA9555_1_PEX3_A0PCA9555_1_PEX3_A1PCA9555_1_PEX3_A2PRSNT_SSD12_FPGA_R_NSSD12_PEX_PWR_EN_RRST_PEX_SSD12_PERST_R_NPRSNT_SSD14_FPGA_PCA9555_NPRSNT_SSD14_FPGA_R_NSSD14_PEX_PWR_ENSSD14_PEX_PWR_EN_RRST_PEX_SSD14_PERST_NRST_PEX_SSD14_PERST_R_NPEX3_PCA9555_0_INT_NPEX3_PCA9555_1_INT_NPRSNT_SSD13_FPGA_PCA9555_NPRSNT_SSD13_FPGA_R_NSSD13_PEX_PWR_ENSSD13_PEX_PWR_EN_RRST_PEX_SSD13_PERST_NRST_PEX_SSD13_PERST_R_NPRSNT_NIC6_FPGA_PCA9555_NPRSNT_NIC6_FPGA_R_NNIC6_PEX_PWR_ENNIC6_PEX_PWR_EN_RRST_PEX_NIC6_PERST_NRST_PEX_NIC6_PERST_R_NPRSNT_SSD15_FPGA_PCA9555_NPRSNT_SSD15_FPGA_R_NSSD15_PEX_PWR_ENSSD15_PEX_PWR_EN_RRST_PEX_SSD15_PERST_NRST_PEX_SSD15_PERST_R_NPRSNT_NIC7_FPGA_PCA9555_NPRSNT_NIC7_FPGA_R_NNIC7_PEX_PWR_ENNIC7_PEX_PWR_EN_RRST_PEX_NIC7_PERST_NRST_PEX_NIC7_PERST_R_NPEX3_PCA9555_INT_N



5
5
4
4
3
3
2
2
1
1
D D
C C
B B
A A
USB_HUB_CoLayout_TI
BOM CHANGE
BOM CHANGE
BOM CHANGE
BOM CHANGE
DVT_CHANGEUSB2_MB_BMC_DP[91,133]USB2_MB_BMC_DN[91,133]USB2_BIC_DP [86,91]USB2_BIC_DN [86,91]USB2_GPU_HMC_DP [91,128]USB2_GPU_HMC_DN [91,128]RST_BIC_USB_HUB_R_N[87,91,93]P3V3_USB_HUB
P3V3_USB_8042
P1V2_AUXP3V3_USB_8042P1V2_USB_8042P1V2_USB_8042P3V3_USB_8042P3V3_USB_8042P5V_AUXP3V3_USB_8042P3V3_AUXP1V2_USB_8042P3V3_USB_HUBP3V3_USB_HUB
SizeDoc NumberRevDate: SheetofReviewerDesignerDepartmentProject
Page TitleCCBU D76 257Tuesday, August 29, 2023<project_name><Designer> GRANDTETON_SWB_20230829076 BLANK<Reviewer>SizeDoc NumberRevDate: SheetofReviewerDesignerDepartmentProject
Page TitleCCBU D76 257Tuesday, August 29, 2023<project_name><Designer> GRANDTETON_SWB_20230829076 BLANK<Reviewer>SizeDoc NumberRevDate: SheetofReviewerDesignerDepartmentProject
Page TitleCCBU D76 257Tuesday, August 29, 2023<project_name><Designer> GRANDTETON_SWB_20230829076 BLANK<Reviewer>C446018PFC0402-02015%50V<Part Number>USB_BOM22/2U442BTUSB8042AIRGCRUSB_BOM2VDD_1313SDA||SMBDAT37VDD_2828VDD33_1616VDD33_3434VDD33_5252FULLPWRMGMTz||FULLAUTOz||SMBA1||SS_UP40GANGED||SMBA2||HS_UP42SCL||SMBCLK38SMBUSz||SS_SUSPEND39VDD33_6363VDD_5151AUTOENz||HS_SUSPEND45VDD_88VDD_55VDD_5757VDD_2121VDD_3131XO61XI62
Q250DMN3042L-7<Part Number>USB_BOM2GSDR674849.9<Part Number>R0402-02011%NI R68424.7KR0402-0201USB_BOM2
L151BLM21PG221SN1DUSB_BOM221C44760.1UF10%25VC0402-0201X7RUSB_BOM2R6740 4.7K 1%1/16W R0402-0201NI Y924MHZ<Part Number>USB_BOM2X11G12G24X23
R6731 0 5% R0402USB_BOM2R67394.7KR0402-0201NI
C44610.1UF10%25VC0402-0201X7RUSB_BOM2Q251NTR1P02LT1G<Part Number>USB_BOM2DSGR6756 4.7K 1%1/16W R0402-0201NI C44710.1UF10%25VC0402-0201X7RUSB_BOM2R675810K1%R0402-0201<Part Number>USB_BOM2R67454.7KR0402-0201USB_BOM2
R675390.9K1%<Part Number>R0402-0201USB_BOM2
R67464.7KR0402-0201NI
R6732 0 5% R0402USB_BOM2R6741 4.7K 1%1/16W R0402-0201NI1/2U442A
TUSB8042AIRGCR<Part Number>USB_BOM2
USB_SSRXM_UP59USB_SSRXM_DN215USB_SSRXP_DN214USB_SSTXP_DN211USB_SSTXM_DN212USB_DM_DN318USB_SSTXM_DN320USB_SSTXP_UP55USB_DM_UP54USB_SSRXM_DN323USB_DP_DN424USB_DP_DN317USB_SSRXP_UP58USB_DP_DN29USB_SSRXP_DN16USB_SSTXP_DN426USB_DM_DN12USB_DM_DN425USB_SSRXP_DN429USB_SSRXM_DN430USB_SSRXP_DN322TH_VSSTH
USB_DP_UP53USB_SSTXM_UP56USB_DP_DN11USB_SSRXM_DN17USB_SSTXP_DN13USB_SSTXM_DN14USB_DM_DN210USB_SSTXP_DN319USB_SSTXM_DN427
USB_VBUS48PWRCTL1||BATEN136PWRCTL2||BATEN235PWRCTL3||BATEN333PWRCTL4||BATEN432PWRCTL_POL41GRSTz50OVERCUR1z46OVERCUR2z47OVERCUR3z44OVERCUR4z43TEST49USB_R164NC_160
R675410K1%<Part Number>R0402-0201USB_BOM2C44670.1UF10%25VC0402-0201X7RUSB_BOM2C44620.1UF10%25VC0402-0201X7RUSB_BOM2R6742 4.7K 1%1/16W R0402-0201NI C44720.1UF10%25VC0402-0201X7RUSB_BOM2C446510UF10%25VC0805_H61X6SUSB_BOM2
R67364.7KR0402-0201USB_BOM2
C44630.1UF10%25VC0402-0201X7RUSB_BOM2R674410K1%R0402-0201<Part Number>USB_BOM2R6743 4.7K 1%1/16W R0402-0201NIC44640.1UF10%25VC0402-0201X7RUSB_BOM2C44680.1UF10%25VC0402-0201X7RUSB_BOM2C44730.1UF10%25VC0402-0201X7RUSB_BOM2R675910K1%R0402-0201<Part Number>NIL150BLM21PG221SN1DUSB_BOM221R6727 0 5% R0402USB_BOM2C44690.1UF10%25VC0402-0201X7RUSB_BOM2R6757 0 5%R0402-0201USB_BOM2C44751UFX6S10%25VC0402-0201USB_BOM2R675149.9<Part Number>R0402-02011%NIR67379.53K1%R0402-0201USB_BOM2R6733 0 5% R0402USB_BOM2C447410UF10%25VC0805_H61X6SUSB_BOM2
R6735 1M1%R0402-0201<Part Number>USB_BOM2
R6728 0 5% R0402USB_BOM2R6734 0 5% R0402USB_BOM2R674749.9<Part Number>R0402-02011%NIR675249.9<Part Number>R0402-02011%NIC445918PFC0402-02015%50V<Part Number>USB_BOM2
R6755 4.7K 1%1/16W R0402-0201NI C44700.1UF10%25VC0402-0201X7RUSB_BOM2USB2_BIC_USB8042_DPUSB2_BIC_USB8042_DNUSB2_GPU_HMC_USB8042_DNUSB2_GPU_HMC_USB8042_DPBIC_USB_8042_HUB_XOUTBIC_USB_8042_HUB_XINBIC_USB_8042_HUB_R1BIC_USB_8042_HUB_TESTBIC_USB_8042_HUB_HS_SUSPENDBIC_USB_8042_HUB_OVCUR1BIC_USB_8042_HUB_OVCUR2BIC_USB_8042_HUB_OVCUR3BIC_USB_8042_HUB_OVCUR4BIC_USB_8042_HUB_GRSTzBIC_USB_8042_HUB_GANGEDBIC_USB_8042_HUB_FULLPWRMGMTZ
USB2_MB_BMC_USB8042_DNUSB2_MB_BMC_USB8042_DPBIC_USB_8042_HUB_VBUSBIC_USB_8042_HUB_PWRCTL3BIC_USB_8042_HUB_PWRCTL2PG12_USB_HUB_N



5
5
4
4
3
3
2
2
1
1
D D
C C
B B
A A
BLANK SizeDoc NumberRevDate: SheetofReviewerDesignerDepartmentProject
Page TitleCCBU D77 257Tuesday, August 29, 2023<project_name><Designer> GRANDTETON_SWB_20230829077 BLANK<Reviewer>SizeDoc NumberRevDate: SheetofReviewerDesignerDepartmentProject
Page TitleCCBU D77 257Tuesday, August 29, 2023<project_name><Designer> GRANDTETON_SWB_20230829077 BLANK<Reviewer>SizeDoc NumberRevDate: SheetofReviewerDesignerDepartmentProject
Page TitleCCBU D77 257Tuesday, August 29, 2023<project_name><Designer> GRANDTETON_SWB_20230829077 BLANK<Reviewer>



5
5
4
4
3
3
2
2
1
1
D D
C C
B B
A A
CAD NOTE:PLACE 10UF CAP CLOSE TO FERRITE BEAD
PLACE EACH 0.1UF CAP AT LESS THAN 150  MILS FROM RESPECTIVE PWR PIN
SMBUS ADDRESS: 0XD2
FM_CLK_CK440_SS_EN
SPREAD OFF0
1
M -0.25% SPREAD
-0.5% SPREAD
CL = 8 pF
CLOCK_GEN_CK440
PVT_CHANGE
PVT2_BOM_CHANGEFM_CK440_MXCK_25M_100M[78]PD_CK440_SBI_CLK[78]PD_CK440_SBI_DATA_IN[78]PU_CK440_SHFT_LD_N[78]CLK_CK440_SMB_ADDR0[78]CLK_CK440_SMB_ADDR1[78]FM_CLK_CK440_SS_EN[78]CLK_BUFFER_DB2000QL_OE0_N[78]FM_CLK_EN_R[78,79,80,81,82,83,84,118]XTAL_CK440_25M_XIN[78]XTAL_CK440_25M_XOUT[78]FM_CK440Q_DEV_25M_EN[78]
XTAL_CK440_25M_XOUT [78]XTAL_CK440_25M_XIN [78]
CLK_100M_CK440Q_0_DB2000QL_R_DP [79]CLK_100M_CK440Q_0_DB2000QL_R_DN [79]CLK_100M_CK440Q_1_DB800ZL_R_DP [80]CLK_100M_CK440Q_1_DB800ZL_R_DN [80]CLK_100M_CK440Q_2_DB800ZL_R_DP [81]CLK_100M_CK440Q_2_DB800ZL_R_DN [81]FM_CK440Q_DEV_25M_EN [78]CLK_BUFFER_DB2000QL_OE0_N [78]FM_CLK_CK440_SS_EN [78]PD_CK440_SBI_DATA_IN [78]PD_CK440_SBI_CLK [78]FM_CLK_EN_R [78,79,80,81,82,83,84,118]PU_CK440_SHFT_LD_N [78]FM_CK440_MXCK_25M_100M [78]CLK_CK440_SMB_ADDR0 [78]CLK_CK440_SMB_ADDR1 [78]CLK_BUFFER_9ZXL0851E_0_7_OE1_N [78]CLK_BUFFER_9ZXL0851E_8_15_OE2_N [78]SMB_CLK_ISO_R_SCL_R1[99]SMB_CLK_ISO_R_SDA[79,80,82,83,99]CLK_BUFFER_9ZXL0851E_0_7_OE1_N[78]CLK_BUFFER_9ZXL0851E_8_15_OE2_N[78]
P3V3P3V3_CLK_GEN_VDD_CK440P3V3_CLK_GEN_VDDA100M_CK440P3V3P3V3_CLK_GEN_VDDXTAL_CK440P3V3_CLK_GEN_VDDA25M_CK440P3V3P3V3_CLK_GEN_VDDMXCK_CK440P3V3_CLK_GEN_VDDPT_CK440P3V3_CLK_GEN_VDD_CK440P3V3_CLK_GEN_VDDA100M_CK440P3V3_CLK_GEN_VDDA25M_CK440P3V3_CLK_GEN_VDDMXCK_CK440P3V3_CLK_GEN_VDDPT_CK440P3V3_CLK_GEN_VDDXTAL_CK440P3V3P3V3
P3V3
SizeDoc NumberRevDate: SheetofReviewerDesignerDepartmentProject
Page TitleCCBU D78 257Tuesday, August 29, 2023<project_name><Designer> GRANDTETON_SWB_20230829078 CLOCK_GEN_CK440<Reviewer>SizeDoc NumberRevDate: SheetofReviewerDesignerDepartmentProject
Page TitleCCBU D78 257Tuesday, August 29, 2023<project_name><Designer> GRANDTETON_SWB_20230829078 CLOCK_GEN_CK440<Reviewer>SizeDoc NumberRevDate: SheetofReviewerDesignerDepartmentProject
Page TitleCCBU D78 257Tuesday, August 29, 2023<project_name><Designer> GRANDTETON_SWB_20230829078 CLOCK_GEN_CK440<Reviewer>
R10704.75KR0402-02011%R104811%R0603_H24<Part Number>C26320.047UFX7RC0402-020110%25V<Part Number>R10504.75KR0402-02011%NIR10614.75KR0402-02011%2/2U113B9SQ440NQQI8NC_B22B22NC_B20B20NC_B18B18NC_B16B16NC_B13B13NC_B7B7NC_B5B5NC_B3B3NC_B2B2NC_A15A15NC_B24B24NC_B25B25NC_B26B26NC_B28B28NC_B30B30NC_B31B31NC_B33B33NC_B34B34NC_B36B36NC_B37B37NC_B39B39NC_B41B41NC_B44B44R1081 4.75K R0402-0201
C26510.047UFX7RC0402-020110%25V<Part Number>L8FCM2012KF-601T<Part Number>L080521
R1075 0 5% R0402-0201R10674.75KR0402-02011%C26330.047UFX7RC0402-020110%25V<Part Number>R10624.75KR0402-02011%R10604.75KR0402-02011%C26350.047UFX7RC0402-020110%25V<Part Number>C263810UFX6SC060320%6.3V<Part Number>1/2U113A9SQ440NQQI825M1#A2EPADC1GNDXTALA14SMB_ADR1_triB9SBI_CLKA54SHFT_LD#B42OE2#A29OE3#A26OE4#B19OE1#A30OE5#B1525M0#A425M0A525M1A325M2#A5525M2A5625MPGA1100M0#A33100M0A34100M1#A31100M1A32100M2#A27100M2A28100M3#A24100M3A25100M4#A22100M4A23100M5#A20100M5A21100M6#A18100M6A19GNDSB10MXCK0#A51MXCK0A52MXCK1#A49MXCK1A50MXCK2#A47MXCK2A48MXCK3#A45MXCK3A46MXCK4#A43MXCK4A44MXCK5#A41MXCK5A42MXCK6#A39MXCK6A40MXCK7#A37MXCK7A38MXCK8#A35MXCK8A36MXCK_SEL_100M#B38NVGNDB12OE0#B27OE6#B14PFT_IN#A9PFT_INA8PFT_LOST#B4PFT_OUT#A7PFT_OUTA6PWRGD||PWRDN#A17SBI_INB43SBI_OUTA53SCLKA10SMBDATTAB8SMB_ADR0_triA11SS_EN_triA16VDDA25MB1VDDA100MB17VDDPTB6VDDXTALA12XIN_CLKINA13XOUTB11VDDMXCK_B29B29VDDMXCK_B32B32VDDMXCK_B35B35VDDMXCK_B40B40VDD100M_B21B21VDD100M_B23B23R10634.75KR0402-02011%R10584.75KR0402-02011%NIR1076 0 5% R0402-0201R1071 0 5% R0402-0201C26480.047UFX7RC0402-020110%25V<Part Number>R10644.75KR0402-02011%C26391UFX6SC0402-020110%25V<Part Number>Y625MHZ<Part Number>FL2500498X11G12G24X23R10564.75KR0402-02011%
R107710K1/16W1%R0402-0201
C26368.2PF0.1P50VC0402-0201<Part Number>NP0C264410UFX6SC060320%6.3V<Part Number>R10514.75KR0402-02011%NIR10654.75KR0402-02011%NIC26490.047UFX7RC0402-020110%25V<Part Number>R1465 33 1% R0402-0201
C26400.047UFX7RC0402-020110%25V<Part Number>R1072 0 5% R0402-0201R10684.75KR0402-02011%R10524.75KR0402-02011%NIR104611%R0603_H24<Part Number>
R1078 4.75K R0402-0201
C26451UFX6SC0402-020110%25V<Part Number>R1466 0 5% R0402-0201
C26410.047UFX7RC0402-020110%25V<Part Number>R10534.75KR0402-02011%NIR10494.75KR0402-02011%NIR10664.75KR0402-02011%L9FCM2012KF-601T<Part Number>L080521C26460.047UFX7RC0402-020110%25V<Part Number>
C26520.1UFX7RC0402-020110%25V<Part Number>NIR1073 0 5% R0402-0201C263710PFNPO50V2%<Part Number>C0402-0201R1045 0<Part Number>R0402-0201C263410UFX6SC060320%6.3V<Part Number>R10544.75KR0402-02011%NIC264210UFX6SC060320%6.3V<Part Number>C263010UFX6SC060320%6.3V<Part Number>
R1079 4.75K R0402-0201R10594.75KR0402-02011%R104711%R0603_H24<Part Number>C26470.047UFX7RC0402-020110%25V<Part Number>R10574.75KR0402-02011%NIR10554.75KR0402-02011%NIC26430.047UFX7RC0402-020110%25V<Part Number>C26311UFX6SC0402-020110%25V<Part Number>L10FCM2012KF-601T<Part Number>L080521 R1074 0 5% R0402-0201R1080 4.75K R0402-0201
C265010UFX6SC060320%6.3V<Part Number>R10694.75KR0402-02011%FM_CK440_MXCK_25M_100MPD_CK440_SBI_CLKPD_CK440_SBI_DATA_INPU_CK440_SHFT_LD_NTP_CK440_SBI_DATA_OUTCLK_CK440_SMB_ADDR0CLK_CK440_SMB_ADDR1FM_CLK_CK440_SS_ENCLK_BUFFER_DB2000QL_OE0_NPU_CLK_PFT_LOST_NTP_CLK_PFT_IN_DPTP_CLK_PFT_IN_DNFM_CLK_EN_RXTAL_CK440_25M_XINXTAL_CK440_25M_XOUTFM_CK440Q_DEV_25M_EN
XTAL_CK440_25M_R_XINXTAL_CK440_25M_XINXTAL_CK440_25M_XOUT
CLK_100M_CK440Q_0_DB2000QL_DPCLK_100M_CK440Q_0_DB2000QL_R_DPCLK_100M_CK440Q_0_DB2000QL_DNCLK_100M_CK440Q_0_DB2000QL_R_DNCLK_100M_CK440Q_1_DB800ZL_DPCLK_100M_CK440Q_1_DB800ZL_R_DPCLK_100M_CK440Q_1_DB800ZL_DNCLK_100M_CK440Q_1_DB800ZL_R_DNCLK_100M_CK440Q_2_DB800ZL_DPCLK_100M_CK440Q_2_DB800ZL_R_DPCLK_100M_CK440Q_2_DB800ZL_DNCLK_100M_CK440Q_2_DB800ZL_R_DNTP_CLK_CK440_PFT_OUT_DPTP_CLK_CK440_PFT_OUT_DN
FM_CK440Q_DEV_25M_ENCLK_BUFFER_DB2000QL_OE0_NFM_CLK_CK440_SS_ENPD_CK440_SBI_DATA_INPD_CK440_SBI_CLKFM_CLK_EN_RPU_CK440_SHFT_LD_NFM_CK440_MXCK_25M_100MCLK_CK440_SMB_ADDR0CLK_CK440_SMB_ADDR1CLK_GEN_CK440_OE3_NCLK_GEN_CK440_OE4_NCLK_GEN_CK440_OE5_NCLK_GEN_CK440_OE6_NCLK_BUFFER_9ZXL0851E_0_7_OE1_NCLK_BUFFER_9ZXL0851E_8_15_OE2_NSMB_CK440_CLK_SCLSMB_CK440_CLK_SDACLK_BUFFER_9ZXL0851E_0_7_OE1_NCLK_BUFFER_9ZXL0851E_8_15_OE2_N



5
5
4
4
3
3
2
2
1
1
D D
C C
B B
A A
LOW OE PINS AND SMBUSENABLE BITS CONTROL OUTPUTS
SIDE-BAND INTERFACECONTROLS OUTPUT ENABLESHIGH
VSBEN MODE
CAD NOTEPLACE ALL 0.1UF CAP NEAR CHIP PIN
ADDRESS:0XDA
100 ohm Impedance
CLOCK_BUFFER_DB2000QL
DVT_CHANGECLK_100M_DB2000QL_PEX0_S1_R_DP [14]CLK_100M_DB2000QL_PEX0_S1_R_DN [14]CLK_100M_DB2000QL_PEX1_S1_R_DP [27]CLK_100M_DB2000QL_PEX1_S1_R_DN [27]CLK_100M_DB2000QL_PEX2_S1_R_DP [40]CLK_100M_CK440Q_0_DB2000QL_R_DP[78]CLK_100M_DB2000QL_PEX2_S1_R_DN [40]CLK_100M_CK440Q_0_DB2000QL_R_DN[78]CLK_100M_DB2000QL_PEX3_S1_R_DP [53]CLK_100M_DB2000QL_PEX3_S1_R_DN [53]FM_DB2000QL_SMB_SA1[79]FM_DB2000QL_SMB_SA0[79]CLK_100M_DB2000QL_NIC0_R_DP [168]CLK_100M_DB2000QL_NIC0_R_DN [168]CLK_100M_DB2000QL_NIC1_R_DP [171]FM_DB2000QL_VSBEN[79]CLK_100M_DB2000QL_NIC1_R_DN [171]CLK_100M_DB2000QL_NIC2_R_DP [174]CLK_100M_DB2000QL_NIC2_R_DN [174]CLK_100M_DB2000QL_NIC3_R_DP [177]CLK_100M_DB2000QL_NIC3_R_DN [177]CLK_100M_DB2000QL_NIC4_R_DP [180]CLK_100M_DB2000QL_NIC4_R_DN [180]CLK_100M_DB2000QL_NIC5_R_DP [183]CLK_100M_DB2000QL_NIC5_R_DN [183]CLK_100M_DB2000QL_NIC6_R_DP [186]CLK_100M_DB2000QL_NIC6_R_DN [186]CLK_100M_DB2000QL_NIC7_R_DP [189]CLK_100M_DB2000QL_NIC7_R_DN [189]FM_DB2000QL_SMB_SA1 [79]FM_DB2000QL_SMB_SA0 [79]FM_DB2000QL_VSBEN [79]CLK_100M_DB2000QL_GPU_REF0_R_DP [128]CLK_100M_DB2000QL_GPU_REF0_R_DN [128]CLK_100M_DB2000QL_GPU_REF1_R_DP [128]CLK_100M_DB2000QL_GPU_REF1_R_DN [128]CLK_100M_DB2000QL_GPU_REF2_R_DP [128]CLK_100M_DB2000QL_GPU_REF2_R_DN [128]SMB_CLK_ISO_R_SDA[78,80,82,83,99]SMB_CLK_ISO_R_SCL[80,82,83,99]FM_CLK_EN_R[78,80,81,82,83,84,118]
NIC0_CLK_EN_R_N[116]NIC1_CLK_EN_R_N[116]NIC2_CLK_EN_R_N[116]NIC3_CLK_EN_R_N[116]NIC4_CLK_EN_R_N[116]NIC5_CLK_EN_R_N[116]NIC6_CLK_EN_R_N[116]NIC7_CLK_EN_R_N[116]NIC0_CLK_EN_BUF_R_N [79]NIC1_CLK_EN_BUF_R_N [79]NIC2_CLK_EN_BUF_R_N [79]NIC3_CLK_EN_BUF_R_N [79]NIC4_CLK_EN_BUF_R_N [79]NIC5_CLK_EN_BUF_R_N [79]NIC6_CLK_EN_BUF_R_N [79]NIC7_CLK_EN_BUF_R_N [79]NIC0_CLK_EN_BUF_R_N[79]NIC1_CLK_EN_BUF_R_N[79]NIC2_CLK_EN_BUF_R_N[79]NIC3_CLK_EN_BUF_R_N[79]NIC4_CLK_EN_BUF_R_N[79]NIC5_CLK_EN_BUF_R_N[79]NIC6_CLK_EN_BUF_R_N[79]NIC7_CLK_EN_BUF_R_N[79]
P3V3P3V3_DB2000QL_FB_VDDP3V3_DB2000QL_VDDAP3V3_DB2000QL_VDDRP3V3_DB2000QL_VDDP3V3_DB2000QL_VDDP3V3_DB2000QL_VDDAP3V3_DB2000QL_VDDRP3V3P3V3
P3V3_AUXP3V3
SizeDoc NumberRevDate: SheetofReviewerDesignerDepartmentProject
Page TitleCCBU D79 257Tuesday, August 29, 2023<project_name><Designer> GRANDTETON_SWB_20230829079 CLOCK_BUFFER_DB2000QL<Reviewer>SizeDoc NumberRevDate: SheetofReviewerDesignerDepartmentProject
Page TitleCCBU D79 257Tuesday, August 29, 2023<project_name><Designer> GRANDTETON_SWB_20230829079 CLOCK_BUFFER_DB2000QL<Reviewer>SizeDoc NumberRevDate: SheetofReviewerDesignerDepartmentProject
Page TitleCCBU D79 257Tuesday, August 29, 2023<project_name><Designer> GRANDTETON_SWB_20230829079 CLOCK_BUFFER_DB2000QL<Reviewer>
C26610.1UFX7RC0402-020110%25V<Part Number>C45000.1UF25V10%X6SR66744.7K1%
R1108 0 5% R0402-0201R1103 0 5% R0402-0201
R10822.21%R0603<Part Number>C44500.1UF10%16VR1092 7.5 1% R0402-0201R1098 0 5% R0402-0201R1113 0 5% R0402-0201
U439SN74LVC2G07DCKR<Part Number>1A12A31Y62Y4GND2VCC5C45010.1UF25V10%X6SC265510UFX6SC060320%6.3V<Part Number>R666533R0402-0201R1467 0 5% R0402-0201R1089 7.5 1% R0402-0201R1094 0 5% R0402-0201U114
9QXL2001BNHGI8<Part Number>DIF_IN#H1NC12J2NC1B3NC10G2DIF15A5DIF17A1DIF18#D1vCKPWRGD_PD#M6EPADTHNC8F2NC11G11NC14K2NC15L6NC13J11DIF0J1DIF0#K1DIF1L1DIF1#M1DIF10D12DIF10#C12DIF11B12DIF12#A10DIF12A11DIF13#A8DIF14A7DIF14#A6DIF15#A4DIF16A3DIF16#A2DIF18C1DIF_ING1DIF11#A12DIF13A9DIF17#B1NC9F11NC7D11NC16L7NC17L3NC18L9NC2B5NC3B7NC4B9NC5C2NC6D2DIF2M2DIF2#M3DIF3M4DIF3#M5DIF4M7DIF4#M8DIF5M9DIF5#M10DIF6M11DIF6#M12DIF7L12DIF7#K12DIF8J12DIF8#H12DIF9G12DIF9#F12vSBENE2vOE5#||DATAL8vOE6#||CLKL10vOE7#K11vOE8#H11vOE9#E12vOE10#||SHFT_LD#E11vOE11#C11vOE12#B10SMBCLKL5SMBDATL4VDDA3.3B6VDDO3.3_B2B2VDDO3.3_B11B11VDDO3.3_L2L2VDDO3.3_L11L11VDDR3.3H2^vSADR0_triB4^vSADR1_triB8DIF19E1DIF19#F1
U441SN74LVC2G07DCKR<Part Number>1A12A31Y62Y4GND2VCC5R666633R0402-0201R1099 0 5% R0402-0201C26560.1UFX6SC0402-020110%25V<Part Number>R66694.7K1%R66754.7K1%
R1468 0 5% R0402-0201R1114 0 5% R0402-0201R11254.75KR0402-02011%
R66704.7K1%
R1109 0 5% R0402-0201
R66764.7K1%R1090 7.5 1% R0402-0201R1095 0 5% R0402-0201R666733R0402-0201
R11204.75KR0402-02011%R1087 7.5 1% R0402-0201C44490.1UF10%16VC44950.1UF25V10%X6SR1105 0 5% R0402-0201R1100 0 5% R0402-0201C265710UFX6SC060320%6.3V<Part Number>R666833R0402-0201R1115 0 5% R0402-0201
R666133R0402-0201
R11214.75KR0402-02011%NI R1110 0 5% R0402-0201
U438SN74LVC2G07DCKR<Part Number>1A12A31Y62Y4GND2VCC5C44960.1UF25V10%X6SR1091 7.5 1% R0402-0201R66714.7K1%
R1096 0 5% R0402-0201R666233R0402-0201C26580.1UFX7RC0402-020110%25V<Part Number>R1106 0 5% R0402-0201R11224.75KR0402-02011%R1101 0 5% R0402-0201U440SN74LVC2G07DCKR<Part Number>1A12A31Y62Y4GND2VCC5C44510.1UF10%16VR1088 7.5 1% R0402-0201R66724.7K1%C44970.1UF25V10%X6SC265310UFX6SC060320%6.3V<Part Number>
R1116 0 5% R0402-0201
R10832.21%R0603<Part Number>
R11234.75KR0402-02011%
C26590.1UFX7RC0402-020110%25V<Part Number>C44940.1UF25V10%X6SC44980.1UF25V10%X6SC44480.1UF10%16VR666333R0402-0201R1097 0 5% R0402-0201C26540.1UFX6SC0402-020110%25V<Part Number>
R1107 0 5% R0402-0201R1102 0 5% R0402-0201C26600.1UFX7RC0402-020110%25V<Part Number>R1117 0 5% R0402-0201C44990.1UF25V10%X6SR1085 7.5 1% R0402-0201R666433R0402-0201R66734.7K1%
R1112 0 5% R0402-0201R11244.75KR0402-02011%NIR1084 7.5 1% R0402-0201L11BLM18SG331TN1D<Part Number>L060321L12BLM18SG331TN1D<Part Number>L060321 CLK_100M_DB2000QL_PEX0_S1_DPCLK_100M_DB2000QL_PEX0_S1_DNCLK_100M_DB2000QL_PEX1_S1_DPCLK_100M_DB2000QL_PEX1_S1_DNCLK_100M_DB2000QL_PEX2_S1_DPCLK_100M_CK440Q_0_DB2000QL_R_DPCLK_100M_DB2000QL_PEX2_S1_DNCLK_100M_CK440Q_0_DB2000QL_R_DNCLK_100M_DB2000QL_PEX3_S1_DPCLK_100M_DB2000QL_PEX3_S1_DNFM_DB2000QL_SMB_SA1FM_DB2000QL_SMB_SA0SMB_BMC_9QXL2001_SDASMB_BMC_9QXL2001_SCLCLK_100M_DB2000QL_NIC0_DPCLK_100M_DB2000QL_NIC0_DNCLK_100M_DB2000QL_NIC1_DPFM_DB2000QL_VSBENCLK_100M_DB2000QL_NIC1_DNCLK_100M_DB2000QL_NIC2_DPCLK_100M_DB2000QL_NIC2_DNCLK_100M_DB2000QL_NIC3_DPCLK_100M_DB2000QL_NIC3_DNCLK_100M_DB2000QL_NIC4_DPCLK_100M_DB2000QL_NIC4_DNCLK_100M_DB2000QL_NIC5_DPCLK_100M_DB2000QL_NIC5_DNCLK_100M_DB2000QL_NIC6_DPCLK_100M_DB2000QL_NIC6_DNNIC0_CLK_EN_BUF_R_NCLK_100M_DB2000QL_NIC7_DPCLK_100M_DB2000QL_NIC7_DNFM_DB2000QL_SMB_SA1FM_DB2000QL_SMB_SA0FM_DB2000QL_VSBEN
CLK_100M_DB2000QL_PEX0_S1_R_DPCLK_100M_DB2000QL_PEX0_S1_R_DNCLK_100M_DB2000QL_PEX1_S1_R_DPCLK_100M_DB2000QL_PEX1_S1_R_DNCLK_100M_DB2000QL_PEX2_S1_R_DPCLK_100M_DB2000QL_PEX2_S1_R_DNCLK_100M_DB2000QL_PEX3_S1_R_DPCLK_100M_DB2000QL_PEX3_S1_R_DNCLK_100M_DB2000QL_NIC0_R_DPCLK_100M_DB2000QL_NIC0_R_DNCLK_100M_DB2000QL_NIC1_R_DPCLK_100M_DB2000QL_NIC1_R_DNCLK_100M_DB2000QL_NIC2_R_DPCLK_100M_DB2000QL_NIC2_R_DNCLK_100M_DB2000QL_NIC3_R_DPCLK_100M_DB2000QL_NIC3_R_DNCLK_100M_DB2000QL_NIC4_R_DPCLK_100M_DB2000QL_NIC4_R_DNCLK_100M_DB2000QL_NIC5_R_DPCLK_100M_DB2000QL_NIC5_R_DNCLK_100M_DB2000QL_NIC6_R_DPCLK_100M_DB2000QL_NIC6_R_DNCLK_100M_DB2000QL_NIC7_R_DPCLK_100M_DB2000QL_NIC7_R_DNCLK_100M_DB2000QL_GPU_REF0_DPCLK_100M_DB2000QL_GPU_REF0_R_DPCLK_100M_DB2000QL_GPU_REF0_DNCLK_100M_DB2000QL_GPU_REF0_R_DNCLK_100M_DB2000QL_GPU_REF1_DPCLK_100M_DB2000QL_GPU_REF1_R_DPCLK_100M_DB2000QL_GPU_REF1_DNCLK_100M_DB2000QL_GPU_REF1_R_DNCLK_100M_DB2000QL_GPU_REF2_DPCLK_100M_DB2000QL_GPU_REF2_R_DPCLK_100M_DB2000QL_GPU_REF2_DNCLK_100M_DB2000QL_GPU_REF2_R_DNNIC1_CLK_EN_BUF_R_NNIC2_CLK_EN_BUF_R_NNIC3_CLK_EN_BUF_R_NNIC4_CLK_EN_BUF_R_NNIC5_CLK_EN_BUF_R_NNIC6_CLK_EN_BUF_R_NNIC7_CLK_EN_BUF_R_NFM_CLK_EN_R
NIC0_CLK_EN_BUF_NNIC1_CLK_EN_BUF_NNIC4_CLK_EN_BUF_NNIC5_CLK_EN_BUF_NNIC6_CLK_EN_BUF_NNIC7_CLK_EN_BUF_NNIC2_CLK_EN_BUF_NNIC3_CLK_EN_BUF_N



5
5
4
4
3
3
2
2
1
1
D D
C C
B B
A A
U115, U116 SMBus Address: 0xD8
CLOCK_BUFFER_9ZXL0851E(1/2)
DVT_CHANGECLK_100M_DB800ZL_SSD0_R_DP [194]CLK_100M_DB800ZL_SSD0_R_DN [194]CLK_100M_DB800ZL_SSD1_R_DP [194]CLK_100M_DB800ZL_SSD1_R_DN [194]CLK_100M_DB800ZL_SSD2_R_DP [195]CLK_100M_DB800ZL_SSD2_R_DN [195]CLK_100M_DB800ZL_SSD3_R_DP [195]CLK_100M_DB800ZL_SSD3_R_DN [195]CLK_100M_DB800ZL_SSD4_R_DP [196]CLK_100M_DB800ZL_SSD4_R_DN [196]CLK_100M_DB800ZL_SSD5_R_DP [196]CLK_100M_DB800ZL_SSD5_R_DN [196]CLK_100M_CK440Q_1_DB800ZL_R_DP[78]CLK_100M_CK440Q_1_DB800ZL_R_DN[78]CLK_100M_DB800ZL_SSD6_R_DP [197]CLK_100M_DB800ZL_SSD6_R_DN [197]CLK_100M_DB800ZL_SSD7_R_DP [197]CLK_100M_DB800ZL_SSD7_R_DN [197]PU_9ZXL0851_0_7_HBW[80]PU_9ZXL0851_0_7_100M[80]SSD7_CLK_EN_R_N [115]SSD6_CLK_EN_R_N [115]SSD5_CLK_EN_R_N [115]SSD4_CLK_EN_R_N [115]SSD2_CLK_EN_R_N [115]SSD3_CLK_EN_R_N [115]SSD1_CLK_EN_R_N [115]SSD0_CLK_EN_R_N [115]SMB_CLK_ISO_R_SDA[78,79,82,83,99]SMB_CLK_ISO_R_SCL[79,82,83,99]PU_9ZXL0851_0_7_HBW[80]PU_9ZXL0851_0_7_100M[80]FM_CLK_EN_R[78,79,81,82,83,84,118]
P3V3P3V3_VDD_9ZXL0851_0_7P3V3_VDDAR_9ZXL0851_0_7P3V3P3V3P3V3_VDDAR_9ZXL0851_0_7P3V3_VDD_9ZXL0851_0_7SizeDoc NumberRevDate: SheetofReviewerDesignerDepartmentProject
Page TitleCCBU D80 257Tuesday, August 29, 2023<project_name><Designer> GRANDTETON_SWB_20230829080 CLOCK_BUFFER_9ZXL0851E(1/2)<Reviewer>SizeDoc NumberRevDate: SheetofReviewerDesignerDepartmentProject
Page TitleCCBU D80 257Tuesday, August 29, 2023<project_name><Designer> GRANDTETON_SWB_20230829080 CLOCK_BUFFER_9ZXL0851E(1/2)<Reviewer>SizeDoc NumberRevDate: SheetofReviewerDesignerDepartmentProject
Page TitleCCBU D80 257Tuesday, August 29, 2023<project_name><Designer> GRANDTETON_SWB_20230829080 CLOCK_BUFFER_9ZXL0851E(1/2)<Reviewer>
C26720.1UF16VX7R10%C0402-0201C26690.1UF16VX7R10%C0402-0201
R1143 0 5% R0402-0201R113410KNIR0402-02015%R1139 0 5% R0402-0201R1470 0 5% R0402-0201
C266210UF16VX7R10%C0805_H61
R1148 0 5% R0402-0201U1159ZXL0851EKILFT<Part Number>VDDR3VDD110VDD215VDD319VDD427VDD534VDD638VDD742VDDA44FBOUT_NC9FBOUT_NC#8DIF_IN4DIF_IN#5SMBDAT6^CKPWRGD_PD#1^100M_133M#47SMBCLK7^HIBW_BYPM_LOBW#48DIF_013DIF_0#14DIF_116DIF_1#17DIF_221DIF_2#22DIF_325DIF_3#26DIF_428DIF_4#29DIF_532DIF_5#33DIF_635DIF_6#36DIF_739DIF_7#40VOE6#37VOE7#41NC220VOE5#31VOE3#24VOE1#18VOE0#11VOE4#30VOE2#23NC112NC343NC445NC546GNDR2TH_GND49R1144 0 5% R0402-0201
C26630.1UF16VX7R10%C0402-0201R113010K1/16W5%R0402-0201R1140 0 5% R0402-0201R1136 0 5% R0402-0201R1149 0 5% R0402-0201
C26640.1UF16VX7R10%C0402-0201
R1145 0 5% R0402-0201R113110KR0402-02015%R1128 1 R0603_H241%C26650.1UF16VX7R10%C0402-0201
R1141 0 5% R0402-0201R1137 0 5% R0402-0201R1150 0 5% R0402-0201
C26660.1UF16VX7R10%C0402-0201
R1146 0 5% R0402-0201
L13BLM18AG601SN1D21C26701UF10VX7R10%C0603C26670.1UF16VX7R10%C0402-0201
R1469 0 5% R0402-0201R1151 0 5% R0402-0201R1147 0 5% R0402-0201R1138 0 5% R0402-0201C26710.1UF16VX7R10%C0402-0201R1142 0 5% R0402-0201
C26680.1UF16VX7R10%C0402-0201R113310K1/16W5%R0402-0201CLK_100M_DB800ZL_SSD0_DPCLK_100M_DB800ZL_SSD0_DNCLK_100M_DB800ZL_SSD1_DPCLK_100M_DB800ZL_SSD1_DNCLK_100M_DB800ZL_SSD2_DPCLK_100M_DB800ZL_SSD2_DNCLK_100M_DB800ZL_SSD3_DPCLK_100M_DB800ZL_SSD3_DNCLK_100M_DB800ZL_SSD4_DPCLK_100M_DB800ZL_SSD4_DNCLK_100M_DB800ZL_SSD5_DPCLK_100M_DB800ZL_SSD5_DNCLK_100M_CK440Q_1_DB800ZL_R_DPCLK_100M_CK440Q_1_DB800ZL_R_DNCLK_100M_DB800ZL_SSD6_DPCLK_100M_DB800ZL_SSD6_DNCLK_100M_DB800ZL_SSD7_DPCLK_100M_DB800ZL_SSD7_DNPU_9ZXL0851_0_7_HBWPU_9ZXL0851_0_7_100MCLK_100M_DB800ZL_SSD0_R_DPCLK_100M_DB800ZL_SSD0_R_DNCLK_100M_DB800ZL_SSD1_R_DPCLK_100M_DB800ZL_SSD1_R_DNCLK_100M_DB800ZL_SSD2_R_DPCLK_100M_DB800ZL_SSD2_R_DNCLK_100M_DB800ZL_SSD3_R_DPCLK_100M_DB800ZL_SSD3_R_DNCLK_100M_DB800ZL_SSD4_R_DPCLK_100M_DB800ZL_SSD4_R_DNCLK_100M_DB800ZL_SSD5_R_DPCLK_100M_DB800ZL_SSD5_R_DNCLK_100M_DB800ZL_SSD6_R_DPCLK_100M_DB800ZL_SSD6_R_DNCLK_100M_DB800ZL_SSD7_R_DPCLK_100M_DB800ZL_SSD7_R_DNSMB_BMC_9ZXL0851_0_7_SDASMB_BMC_9ZXL0851_0_7_SCLSSD0_CLK_EN_R_NSSD7_CLK_EN_R_NSSD6_CLK_EN_R_NSSD5_CLK_EN_R_NSSD4_CLK_EN_R_NSSD2_CLK_EN_R_NSSD3_CLK_EN_R_NSSD1_CLK_EN_R_NFM_CLK_EN_R



5
5
4
4
3
3
2
2
1
1
D D
C C
B B
A A
U115, U116 SMBus Address: 0xD8
INTERNAL PUBY VCCB
RESERVED BY-PASS
CLOCK_BUFFER_9ZXL0851E(2/2)
DVT_CHANGE
DVT_CHANGEPVT2_BOM_CHANGECLK_100M_DB800ZL_SSD8_R_DP [198]CLK_100M_DB800ZL_SSD8_R_DN [198]CLK_100M_DB800ZL_SSD9_R_DP [198]CLK_100M_DB800ZL_SSD9_R_DN [198]CLK_100M_DB800ZL_SSD10_R_DP [199]CLK_100M_DB800ZL_SSD10_R_DN [199]CLK_100M_DB800ZL_SSD11_R_DP [199]CLK_100M_DB800ZL_SSD11_R_DN [199]CLK_100M_DB800ZL_SSD12_R_DP [200]CLK_100M_DB800ZL_SSD12_R_DN [200]CLK_100M_DB800ZL_SSD13_R_DP [200]CLK_100M_DB800ZL_SSD13_R_DN [200]CLK_100M_CK440Q_2_DB800ZL_R_DP[78]CLK_100M_CK440Q_2_DB800ZL_R_DN[78]CLK_100M_DB800ZL_SSD14_R_DP [201]CLK_100M_DB800ZL_SSD14_R_DN [201]CLK_100M_DB800ZL_SSD15_R_DP [201]CLK_100M_DB800ZL_SSD15_R_DN [201]PU_9ZXL0851_8_15_HBW[81]PU_9ZXL0851_8_15_100M[81]SMB_BMC_9ZXL0851_8_15_SDA[81]SMB_BMC_9ZXL0851_8_15_SCL[81]PU_9ZXL0851_8_15_HBW[81]PU_9ZXL0851_8_15_100M[81]SSD15_CLK_EN_R_N [117]SSD14_CLK_EN_R_N [117]SSD13_CLK_EN_R_N [117]SSD12_CLK_EN_R_N [117]SSD10_CLK_EN_R_N [117]SSD11_CLK_EN_R_N [117]SSD9_CLK_EN_R_N [117]SSD8_CLK_EN_R_N [117]FM_CLK_EN_R[78,79,80,82,83,84,118]
SMB_BIC_I2C6_MUX_FRU_R_SCL[99,104]SMB_BMC_9ZXL0851_8_15_SCL [81]SMB_BIC_I2C6_MUX_FRU_R_SDA[99,104]SMB_BMC_9ZXL0851_8_15_SDA [81]SMB_BMC_9FGL0451E_S3_SCL [84]SMB_BMC_9FGL0451E_S3_SDA [84]P3V3P3V3_VDD_9ZXL0851_8_15P3V3_VDDAR_9ZXL0851_8_15P3V3_VDDAR_9ZXL0851_8_15P3V3_VDD_9ZXL0851_8_15P3V3P3V3P3V3P3V3_AUX
SizeDoc NumberRevDate: SheetofReviewerDesignerDepartmentProject
Page TitleCCBU D81 257Tuesday, August 29, 2023<project_name><Designer> GRANDTETON_SWB_20230829081 CLOCK_BUFFER_9ZXL0851E(2/2)<Reviewer>SizeDoc NumberRevDate: SheetofReviewerDesignerDepartmentProject
Page TitleCCBU D81 257Tuesday, August 29, 2023<project_name><Designer> GRANDTETON_SWB_20230829081 CLOCK_BUFFER_9ZXL0851E(2/2)<Reviewer>SizeDoc NumberRevDate: SheetofReviewerDesignerDepartmentProject
Page TitleCCBU D81 257Tuesday, August 29, 2023<project_name><Designer> GRANDTETON_SWB_20230829081 CLOCK_BUFFER_9ZXL0851E(2/2)<Reviewer>R1182 0 5% R0402-0201
C26830.1UF16VX7R10%C0402-0201C39920.1UF10%16VC0402-0201R351210KNIR0402-02015%C26780.1UF16VX7R10%C0402-0201U1169ZXL0851EKILFT<Part Number>VDDR3VDD110VDD215VDD319VDD427VDD534VDD638VDD742VDDA44FBOUT_NC9FBOUT_NC#8DIF_IN4DIF_IN#5SMBDAT6^CKPWRGD_PD#1^100M_133M#47SMBCLK7^HIBW_BYPM_LOBW#48DIF_013DIF_0#14DIF_116DIF_1#17DIF_221DIF_2#22DIF_325DIF_3#26DIF_428DIF_4#29DIF_532DIF_5#33DIF_635DIF_6#36DIF_739DIF_7#40VOE6#37VOE7#41NC220VOE5#31VOE3#24VOE1#18VOE0#11VOE4#30VOE2#23NC112NC343NC445NC546GNDR2TH_GND49R1178 0 5% R0402-0201R1471 51 5%C39930.1UF10%16VC0402-0201R1174 0 5% R0402-0201R1183 0 5% R0402-0201
C26790.1UF16VX7R10%C0402-0201R1170 0 5% R0402-0201R1179 0 5% R0402-0201R1162 1 R0603_H241%C26800.1UF16VX7R10%C0402-0201R6263 0 R0402-02015%NIU420PCA9617ADPEN5VCCA1VCCB8SCLA2SDAA3SDAB6SCLB7GND4R350810K1/16W5%R0402-0201R1175 0 5% R0402-0201R1171 0 5% R0402-0201R1184 0 5% R0402-0201
R1472 51 5%R350910KR0402-02015%R6264 0 R0402-02015%NIC267310UF16VX7R10%C0805_H61
R1180 0 5% R0402-0201R6384 51 5%C26740.1UF16VX7R10%C0402-0201
R1185 0 5% R0402-0201
R6385 51 5%R1181 0 5% R0402-0201R1172 0 5% R0402-0201R1176 0 5% R0402-0201
C26750.1UF16VX7R10%C0402-0201R62592.2K5%R0402-0201R62584.7KR0402-02015% NIC26811UF10VX7R10%C0603R62602.2K5%R0402-0201C26760.1UF16VX7R10%C0402-0201
R1177 0 5% R0402-0201R1173 0 5% R0402-0201C26820.1UF16VX7R10%C0402-0201R351110K1/16W5%R0402-0201C26770.1UF16VX7R10%C0402-0201L14BLM18AG601SN1D21
CLK_100M_DB800ZL_SSD8_DPCLK_100M_DB800ZL_SSD8_R_DPCLK_100M_DB800ZL_SSD8_DNCLK_100M_DB800ZL_SSD8_R_DNCLK_100M_DB800ZL_SSD9_DPCLK_100M_DB800ZL_SSD9_R_DPCLK_100M_DB800ZL_SSD9_DNCLK_100M_DB800ZL_SSD9_R_DNCLK_100M_DB800ZL_SSD10_DPCLK_100M_DB800ZL_SSD10_R_DPCLK_100M_DB800ZL_SSD10_DNCLK_100M_DB800ZL_SSD10_R_DNCLK_100M_DB800ZL_SSD11_DPCLK_100M_DB800ZL_SSD11_R_DPCLK_100M_DB800ZL_SSD11_DNCLK_100M_DB800ZL_SSD11_R_DNCLK_100M_DB800ZL_SSD12_DPCLK_100M_DB800ZL_SSD12_R_DPCLK_100M_DB800ZL_SSD12_DNCLK_100M_DB800ZL_SSD12_R_DNCLK_100M_DB800ZL_SSD13_DPCLK_100M_DB800ZL_SSD13_R_DPCLK_100M_DB800ZL_SSD13_DNCLK_100M_DB800ZL_SSD13_R_DNCLK_100M_CK440Q_2_DB800ZL_R_DPCLK_100M_CK440Q_2_DB800ZL_R_DNCLK_100M_DB800ZL_SSD14_DPCLK_100M_DB800ZL_SSD14_R_DPCLK_100M_DB800ZL_SSD14_DNCLK_100M_DB800ZL_SSD14_R_DNCLK_100M_DB800ZL_SSD15_DPCLK_100M_DB800ZL_SSD15_R_DPCLK_100M_DB800ZL_SSD15_DNCLK_100M_DB800ZL_SSD15_R_DNPU_9ZXL0851_8_15_HBWPU_9ZXL0851_8_15_100MSMB_BMC_9ZXL0851_8_15_SDASMB_BMC_9ZXL0851_8_15_SCLSSD15_CLK_EN_R_NSSD14_CLK_EN_R_NSSD13_CLK_EN_R_NSSD12_CLK_EN_R_NSSD10_CLK_EN_R_NSSD11_CLK_EN_R_NSSD9_CLK_EN_R_NSSD8_CLK_EN_R_NFM_CLK_EN_R
SMB_ISO_CB_SCLSMB_ISO_CB_SDACB_ISO_EN



5
5
4
4
3
3
2
2
1
1
D D
C C
B B
A A
CAD NOTE:PLACE 10UF CAP CLOSE TO FERRITE BEAD
PLACE EACH 0.1UF CAP AT LESS THAN 150  MILS FROM RESPECTIVE PWR PIN
SMBUS ADDRESS: 0XD6
-0.5% SPREAD1
M
SPREAD OFF
-0.25% SPREAD
0
FM_CLK_CK440_SS_EN
CLOCK_GEN_CK440_PEX
PVT_CHANGEXTAL_CK440_PEX_25M_XIN [82]XTAL_CK440_PEX_25M_XOUT [82]FM_CK440_PEX_DEV_25M_EN [82]PEX_REF_CLK_GEN_EN_N [82]CK440_PEX_SS_EN [82]PD_CK440_PEX_SBI_DATA_IN [82]PD_CK440_PEX_SBI_CLK [82]FM_CLK_EN_R [78,79,80,81,82,83,84,118]PU_CK440_PEX_SHFT_LD_N [82]FM_CK440_PEX_MXCK_25M_100M [82]CLK_CK440_PEX_SMB_ADDR0 [82]CLK_CK440_PEX_SMB_ADDR1 [82]FM_CK440_PEX_MXCK_25M_100M[82]PD_CK440_PEX_SBI_CLK[82]PD_CK440_PEX_SBI_DATA_IN[82]PU_CK440_PEX_SHFT_LD_N[82]SMB_CLK_ISO_R_SCL[79,80,83,99]SMB_CLK_ISO_R_SDA[78,79,80,83,99]CLK_CK440_PEX_SMB_ADDR0[82]CLK_CK440_PEX_SMB_ADDR1[82]CK440_PEX_SS_EN[82]PEX_REF_CLK_GEN_EN_N[82]FM_CLK_EN_R[78,79,80,81,82,83,84,118]XTAL_CK440_PEX_25M_XIN[82]XTAL_CK440_PEX_25M_XOUT[82]FM_CK440_PEX_DEV_25M_EN[82]CLK_100M_PEX0_REF_R_DP [14]CLK_100M_PEX0_REF_R_DN [14]CLK_100M_PEX1_REF_R_DP [27]CLK_100M_PEX1_REF_R_DN [27]CLK_100M_PEX2_REF_R_DP [40]CLK_100M_PEX2_REF_R_DN [40]CLK_100M_PEX3_REF_R_DP [53]CLK_100M_PEX3_REF_R_DN [53]
P3V3P3V3_CLK_GEN_VDD_CK440_PEXP3V3_CLK_GEN_VDDA100M_CK440_PEXP3V3P3V3_CLK_GEN_VDDXTAL_CK440_PEXP3V3_CLK_GEN_VDDA25M_CK440_PEXP3V3P3V3P3V3_CLK_GEN_VDDMXCK_CK440_PEXP3V3_CLK_GEN_VDDPT_CK440_PEXP3V3_CLK_GEN_VDDXTAL_CK440_PEXP3V3_CLK_GEN_VDDPT_CK440_PEXP3V3_CLK_GEN_VDDMXCK_CK440_PEXP3V3_CLK_GEN_VDDA25M_CK440_PEXP3V3_CLK_GEN_VDDA100M_CK440_PEXP3V3_CLK_GEN_VDD_CK440_PEXP3V3P3V3SizeDoc NumberRevDate: SheetofReviewerDesignerDepartmentProject
Page TitleCCBU D82 257Tuesday, August 29, 2023<project_name><Designer> GRANDTETON_SWB_20230829082 CLOCK_GEN_CK440_PEX<Reviewer>SizeDoc NumberRevDate: SheetofReviewerDesignerDepartmentProject
Page TitleCCBU D82 257Tuesday, August 29, 2023<project_name><Designer> GRANDTETON_SWB_20230829082 CLOCK_GEN_CK440_PEX<Reviewer>SizeDoc NumberRevDate: SheetofReviewerDesignerDepartmentProject
Page TitleCCBU D82 257Tuesday, August 29, 2023<project_name><Designer> GRANDTETON_SWB_20230829082 CLOCK_GEN_CK440_PEX<Reviewer>
R418611%R0603_H24<Part Number>
R4217 0 5% R0402-0201
C279310UFX6SC060320%6.3V<Part Number>
R421910K1/16W1%R0402-0201R42074.75KR0402-02011%1/2U117A9SQ440NQQI825M1#A2EPADC1GNDXTALA14SMB_ADR1_triB9SBI_CLKA54SHFT_LD#B42OE2#A29OE3#A26OE4#B19OE1#A30OE5#B1525M0#A425M0A525M1A325M2#A5525M2A5625MPGA1100M0#A33100M0A34100M1#A31100M1A32100M2#A27100M2A28100M3#A24100M3A25100M4#A22100M4A23100M5#A20100M5A21100M6#A18100M6A19GNDSB10MXCK0#A51MXCK0A52MXCK1#A49MXCK1A50MXCK2#A47MXCK2A48MXCK3#A45MXCK3A46MXCK4#A43MXCK4A44MXCK5#A41MXCK5A42MXCK6#A39MXCK6A40MXCK7#A37MXCK7A38MXCK8#A35MXCK8A36MXCK_SEL_100M#B38NVGNDB12OE0#B27OE6#B14PFT_IN#A9PFT_INA8PFT_LOST#B4PFT_OUT#A7PFT_OUTA6PWRGD||PWRDN#A17SBI_INB43SBI_OUTA53SCLKA10SMBDATTAB8SMB_ADR0_triA11SS_EN_triA16VDDA25MB1VDDA100MB17VDDPTB6VDDXTALA12XIN_CLKINA13XOUTB11VDDMXCK_B29B29VDDMXCK_B32B32VDDMXCK_B35B35VDDMXCK_B40B40VDD100M_B21B21VDD100M_B23B23C28010.047UFX7RC0402-020110%25V<Part Number>R419811%R0603_H24<Part Number>R41904.75KR0402-02011%NIC27900.047UFX7RC0402-020110%25V<Part Number>R42084.75KR0402-02011%C27941UFX6SC0402-020110%25V<Part Number>R41914.75KR0402-02011%C28020.047UFX7RC0402-020110%25V<Part Number>R1205 7.5 1% R0402-0201
Y725MHZFL2500498<Part Number>X11G12G24X23C27918.2PF0.1P50VC0402-0201<Part Number>NP0R1207 7.5 1% R0402-0201L80FCM2012KF-601T<Part Number>L080521 R42094.75KR0402-02011%2/2U117B9SQ440NQQI8NC_B22B22NC_B20B20NC_B18B18NC_B16B16NC_B13B13NC_B7B7NC_B5B5NC_B3B3NC_B2B2NC_A15A15NC_B24B24NC_B25B25NC_B26B26NC_B28B28NC_B30B30NC_B31B31NC_B33B33NC_B34B34NC_B36B36NC_B37B37NC_B39B39NC_B41B41NC_B44B44R41924.75KR0402-02011%NIC27950.047UFX7RC0402-020110%25V<Part Number>C28030.047UFX7RC0402-020110%25V<Part Number>R42104.75KR0402-02011%R418711%R0603_H24<Part Number>C279210PFNPO50V2%<Part Number>C0402-0201
R4221 4.75K R0402-0201R1206 7.5 1% R0402-0201
R4185 0<Part Number>R0402-0201R41934.75KR0402-02011%NIR1208 7.5 1% R0402-0201R1209 7.5 1% R0402-0201R4218 0 5% R0402-0201
C27960.047UFX7RC0402-020110%25V<Part Number>C278510UFX6SC060320%6.3V<Part Number>R42014.75KR0402-02011%C28040.047UFX7RC0402-020110%25V<Part Number>R41944.75KR0402-02011%NI
R4222 4.75K R0402-0201R42024.75KR0402-02011%NIC279710UFX6SC060320%6.3V<Part Number>C27861UFX6SC0402-020110%25V<Part Number>C280510UFX6SC060320%6.3V<Part Number>R1210 7.5 1% R0402-0201R41954.75KR0402-02011%NIR42034.75KR0402-02011%C27980.047UFX7RC0402-020110%25V<Part Number>C27870.047UFX7RC0402-020110%25V<Part Number>
C28070.1UFX7RC0402-020110%25V<Part Number>NIR4223 4.75K R0402-0201
C28060.047UFX7RC0402-020110%25V<Part Number>R41964.75KR0402-02011%NIR1211 7.5 1% R0402-0201R42044.75KR0402-02011%C27880.047UFX7RC0402-020110%25V<Part Number>C279910UFX6SC060320%6.3V<Part Number>R41974.75KR0402-02011%NIL79FCM2012KF-601T<Part Number>L080521 R42054.75KR0402-02011%NIR1212 7.5 1% R0402-0201C28001UFX6SC0402-020110%25V<Part Number>C278910UFX6SC060320%6.3V<Part Number>L81FCM2012KF-601T<Part Number>L080521 R42064.75KR0402-02011%XTAL_CK440_PEX_25M_R_XINXTAL_CK440_PEX_25M_XINXTAL_CK440_PEX_25M_XOUTFM_CK440_PEX_DEV_25M_ENPEX_REF_CLK_GEN_EN_NCK440_PEX_SS_ENPD_CK440_PEX_SBI_DATA_INPD_CK440_PEX_SBI_CLKFM_CLK_EN_RPU_CK440_PEX_SHFT_LD_NFM_CK440_PEX_MXCK_25M_100MCLK_CK440_PEX_SMB_ADDR0CLK_CK440_PEX_SMB_ADDR1FM_CK440_PEX_MXCK_25M_100MPD_CK440_PEX_SBI_CLKPD_CK440_PEX_SBI_DATA_INTP_CK440_PEX_SBI_DATA_OUTPU_CK440_PEX_SHFT_LD_NSMB_CK440_PEX_CLK_SCLSMB_CK440_PEX_CLK_SDACLK_CK440_PEX_SMB_ADDR0CLK_CK440_PEX_SMB_ADDR1CK440_PEX_SS_ENPEX_REF_CLK_GEN_EN_NPEX_REF_CLK_GEN_EN_NPEX_REF_CLK_GEN_EN_NCLK_GEN_CK440_PEX_OE4_NCLK_GEN_CK440_PEX_OE5_NCLK_GEN_CK440_PEX_OE6_NPU_CK440_PEX_PFT_LOST_NTP_CK440_PEX_PFT_IN_DPTP_CK440_PEX_PFT_IN_DNTP_CLK_CK440_PEX_PFT_OUT_DPFM_CLK_EN_RTP_CLK_CK440_PEX_PFT_OUT_DNXTAL_CK440_PEX_25M_XINXTAL_CK440_PEX_25M_XOUTFM_CK440_PEX_DEV_25M_ENCLK_100M_PEX0_REF_DPCLK_100M_PEX0_REF_R_DPCLK_100M_PEX0_REF_DNCLK_100M_PEX0_REF_R_DNCLK_100M_PEX1_REF_DPCLK_100M_PEX1_REF_R_DPCLK_100M_PEX1_REF_DNCLK_100M_PEX1_REF_R_DNCLK_100M_PEX2_REF_DPCLK_100M_PEX2_REF_R_DPCLK_100M_PEX2_REF_DNCLK_100M_PEX2_REF_R_DNCLK_100M_PEX3_REF_DPCLK_100M_PEX3_REF_R_DPCLK_100M_PEX3_REF_DNCLK_100M_PEX3_REF_R_DNPEX_REF_CLK_GEN_EN_N



5
5
4
4
3
3
2
2
1
1
D D
C C
B B
A A
Layout notes.1.Route power from bead through bulk capacitor pad then through 0.1uF capacitor pad and then to through  clock chip Vdd pad.2.Do not share ground vias. One ground pin one ground via.
SMBUS ADDRESS: 0XDE
9FGL HAS INTERNAL PULL-DOWNRESISTORS IN OE_N PINS
CLOCK_BUFFER_9ZXL0451E_S0
SMB_9ZXL0451E_ADDR0 [83]CLK_100M_MB_0_DP[133]CLK_100M_MB_0_R_DP [83]CLK_100M_MB_0_DN[133]CLK_100M_MB_0_R_DN [83]CLK_100M_DB800ZL_PEX0_S0_R_DP [14]CLK_100M_DB800ZL_PEX0_S0_R_DN [14]CLK_100M_DB800ZL_PEX1_S0_R_DP [27]CLK_100M_DB800ZL_PEX1_S0_R_DN [27]CLK_100M_DB800ZL_PEX2_S0_R_DP [40]CLK_100M_DB800ZL_PEX2_S0_R_DN [40]CLK_100M_DB800ZL_PEX3_S0_R_DP [53]CLK_100M_DB800ZL_PEX3_S0_R_DN [53]CLK_100M_MB_0_R_DP[83]CLK_100M_MB_0_R_DN[83]PEX_REF_CLK_BUFFER_EN_N [83]SMB_9ZXL0451E_ADDR0[83]PU_9ZXL0451E_HBW [83]PU_9ZXL0451E_HBW [83]SMB_CLK_ISO_R_SDA[78,79,80,82,99]SMB_CLK_ISO_R_SCL[79,80,82,99]FM_CLK_EN_R[78,79,80,81,82,84,118]PEX_REF_CLK_BUFFER_EN_N [83]P3V3P3V3_CLK_BUFFER_9ZXL0451E_VZX3P3P3V3_CLK_BUFFER_9ZXL0451E_VZX3P3AP3V3P3V3P3V3_CLK_BUFFER_9ZXL0451E_VZX3P3P3V3_CLK_BUFFER_9ZXL0451E_VZX3P3AP3V3_CLK_BUFFER_9ZXL0451E_VZX3P3AP3V3
SizeDoc NumberRevDate: SheetofReviewerDesignerDepartmentProject
Page TitleCCBU D83 257Tuesday, August 29, 2023<project_name><Designer> GRANDTETON_SWB_20230829083 CLOCK_BUFFER_9ZXL0451E_S0<Reviewer>SizeDoc NumberRevDate: SheetofReviewerDesignerDepartmentProject
Page TitleCCBU D83 257Tuesday, August 29, 2023<project_name><Designer> GRANDTETON_SWB_20230829083 CLOCK_BUFFER_9ZXL0451E_S0<Reviewer>SizeDoc NumberRevDate: SheetofReviewerDesignerDepartmentProject
Page TitleCCBU D83 257Tuesday, August 29, 2023<project_name><Designer> GRANDTETON_SWB_20230829083 CLOCK_BUFFER_9ZXL0451E_S0<Reviewer>
C26990.1UFX6SC0402-020110%25V<Part Number>C27020.1UFX6SC0402-020110%25V<Part Number>C27000.1UFX6SC0402-020110%25V<Part Number>
R1230 7.5 1% R0402-0201R121805% R0402-0201<Part Number>R1231 7.5 1% R0402-0201
C270110UFX6SC0805_H6110%25V<Part Number>R121905% R0402-0201<Part Number>R1232 7.5 1% R0402-0201
C269510UFX6SC0805_H6110%25V<Part Number>C27030.1UFX6SC0402-020110%25V<Part Number>R122010K1/16W5%R0402-0201R42284.75KR0402-02011%NIC26960.1UFX6SC0402-020110%25V<Part Number>R12244.75KR0402-02011%NIR1475 0 5% R0402-0201R42274.75K1/16W1%R0402-0201R122310K1/16W5%R0402-0201C26970.1UFX6SC0402-020110%25V<Part Number>
R1225 7.5 1% R0402-02019ZXL0451EKILFTU118DIF_IN3DIF_IN#4VDDR2VDD325VDD429FBOUT_NC9vOE0#15vOE3#26SMBDAT6NC111FBOUT_NC#8SMBCLK7VDD221^CKPWRGD_PD#1DIF0#14DIF013vOE1#18DIF1#20DIF222vOE2#24DIF2#23DIF3#28NC010VDDA31VDD116^HIBW_BYPM_LOBW#32EPAD_GND33DIF119DIF327VDD012NC330NC217vSADR0_tri5R1227 7.5 1% R0402-0201R12214.75KR0402-02011%R1476 33 1% R0402-0201
L16MMZ2012S601AT<Part Number>L080521C26980.1UFX6SC0402-020110%25V<Part Number>
R1226 7.5 1% R0402-0201
R121411%R0603_H24<Part Number>
R1228 7.5 1% R0402-0201R1229 7.5 1% R0402-0201SMB_9ZXL0451E_ADDR0CLK_100M_MB_0_DPCLK_100M_MB_0_R_DPCLK_100M_MB_0_DNCLK_100M_MB_0_R_DNCLK_100M_DB800ZL_PEX0_S0_DPCLK_100M_DB800ZL_PEX0_S0_R_DPCLK_100M_DB800ZL_PEX0_S0_DNCLK_100M_DB800ZL_PEX0_S0_R_DNCLK_100M_DB800ZL_PEX1_S0_DPCLK_100M_DB800ZL_PEX1_S0_R_DPCLK_100M_DB800ZL_PEX1_S0_DNCLK_100M_DB800ZL_PEX1_S0_R_DNCLK_100M_DB800ZL_PEX2_S0_DPCLK_100M_DB800ZL_PEX2_S0_R_DPCLK_100M_DB800ZL_PEX2_S0_DNCLK_100M_DB800ZL_PEX2_S0_R_DNCLK_100M_DB800ZL_PEX3_S0_DPCLK_100M_DB800ZL_PEX3_S0_R_DPCLK_100M_DB800ZL_PEX3_S0_DNCLK_100M_DB800ZL_PEX3_S0_R_DNCLK_100M_MB_0_R_DPCLK_100M_MB_0_R_DNPEX_REF_CLK_BUFFER_EN_NSMB_9ZXL0451E_ADDR0PU_9ZXL0451E_HBWSMB_BMC_9FGL0451E_SDASMB_BMC_9FGL0451E_SCLFM_CLK_EN_RPEX_REF_CLK_BUFFER_EN_N



5
5
4
4
3
3
2
2
1
1
D D
C C
B B
A A
9FGL HAS INTERNAL PULL-DOWNRESISTORS IN OE_N PINS
SMBUS ADDRESS: 0XDE
Layout notes.1.Route power from bead through bulk capacitor pad then through 0.1uF capacitor pad and then to through  clock chip Vdd pad.2.Do not share ground vias. One ground pin one ground via.
CLOCK_BUFFER_9ZXL0451E_S3
CLK_100M_MB_1_DP[133]CLK_100M_MB_1_R_DP [84]CLK_100M_MB_1_DN[133]CLK_100M_MB_1_R_DN [84]PEX_S3_REF_CLK_BUFFER_EN_N [84]PU_9ZXL0451E_S3_HBW [84]SMB_9ZXL0451E_S3_ADDR0 [84]PU_9ZXL0451E_S3_HBW [84]CLK_100M_DB800ZL_PEX0_S3_R_DP [14]CLK_100M_DB800ZL_PEX0_S3_R_DN [14]CLK_100M_MB_1_R_DP[84]CLK_100M_DB800ZL_PEX1_S3_R_DP [27]CLK_100M_MB_1_R_DN[84]CLK_100M_DB800ZL_PEX1_S3_R_DN [27]CLK_100M_DB800ZL_PEX2_S3_R_DP [40]SMB_9ZXL0451E_S3_ADDR0[84]CLK_100M_DB800ZL_PEX2_S3_R_DN [40]CLK_100M_DB800ZL_PEX3_S3_R_DP [53]SMB_BMC_9FGL0451E_S3_SDA[81]CLK_100M_DB800ZL_PEX3_S3_R_DN [53]SMB_BMC_9FGL0451E_S3_SCL[81]FM_CLK_EN_R[78,79,80,81,82,83,118]PEX_S3_REF_CLK_BUFFER_EN_N [84]
P3V3P3V3_CLK_BUFFER_9ZXL0451E_S3_VZX3P3P3V3_CLK_BUFFER_9ZXL0451E_S3_VZX3P3AP3V3P3V3P3V3P3V3_CLK_BUFFER_9ZXL0451E_S3_VZX3P3AP3V3_CLK_BUFFER_9ZXL0451E_S3_VZX3P3AP3V3_CLK_BUFFER_9ZXL0451E_S3_VZX3P3SizeDoc NumberRevDate: SheetofReviewerDesignerDepartmentProject
Page TitleCCBU D84 257Tuesday, August 29, 2023<project_name><Designer> GRANDTETON_SWB_20230829084 CLOCK_BUFFER_9ZXL0451E_S3<Reviewer>SizeDoc NumberRevDate: SheetofReviewerDesignerDepartmentProject
Page TitleCCBU D84 257Tuesday, August 29, 2023<project_name><Designer> GRANDTETON_SWB_20230829084 CLOCK_BUFFER_9ZXL0451E_S3<Reviewer>SizeDoc NumberRevDate: SheetofReviewerDesignerDepartmentProject
Page TitleCCBU D84 257Tuesday, August 29, 2023<project_name><Designer> GRANDTETON_SWB_20230829084 CLOCK_BUFFER_9ZXL0451E_S3<Reviewer>
R636705% R0402-0201<Part Number>R6377 7.5 1% R0402-0201R63714.75K1/16W1%R0402-0201R6382 7.5 1% R0402-0201
C41830.1UFX6SC0402-020110%25V<Part Number>R637210K1/16W5%R0402-0201C417610UFX6SC0805_H6110%25V<Part Number>C41840.1UFX6SC0402-020110%25V<Part Number>
R6378 7.5 1% R0402-0201R63734.75KR0402-02011%NIC41770.1UFX6SC0402-020110%25V<Part Number>
R6374 7.5 1% R0402-0201R63684.75KR0402-02011%NIC41780.1UFX6SC0402-020110%25V<Part Number>
R6379 7.5 1% R0402-0201R636910K1/16W5%R0402-0201L149MMZ2012S601AT<Part Number>L080521
R6375 7.5 1% R0402-0201
C41790.1UFX6SC0402-020110%25V<Part Number>R63704.75KR0402-02011%R636511%R0603_H24<Part Number>C41800.1UFX6SC0402-020110%25V<Part Number>
R6380 7.5 1% R0402-0201R6376 7.5 1% R0402-0201R636605% R0402-0201<Part Number>C41810.1UFX6SC0402-020110%25V<Part Number>C418210UFX6SC0805_H6110%25V<Part Number>
9ZXL0451EKILFTU424DIF_IN3DIF_IN#4VDDR2VDD325VDD429FBOUT_NC9vOE0#15vOE3#26SMBDAT6NC111FBOUT_NC#8SMBCLK7VDD221^CKPWRGD_PD#1DIF0#14DIF013vOE1#18DIF1#20DIF222vOE2#24DIF2#23DIF3#28NC010VDDA31VDD116^HIBW_BYPM_LOBW#32EPAD_GND33DIF119DIF327VDD012NC330NC217vSADR0_tri5CLK_100M_MB_1_DPCLK_100M_MB_1_R_DPCLK_100M_MB_1_DNCLK_100M_MB_1_R_DNPEX_S3_REF_CLK_BUFFER_EN_NPU_9ZXL0451E_S3_HBWSMB_9ZXL0451E_S3_ADDR0CLK_100M_DB800ZL_PEX0_S3_DPCLK_100M_DB800ZL_PEX0_S3_R_DPCLK_100M_DB800ZL_PEX0_S3_DNCLK_100M_DB800ZL_PEX0_S3_R_DNCLK_100M_MB_1_R_DPCLK_100M_DB800ZL_PEX1_S3_DPCLK_100M_DB800ZL_PEX1_S3_R_DPCLK_100M_MB_1_R_DNCLK_100M_DB800ZL_PEX1_S3_DNCLK_100M_DB800ZL_PEX1_S3_R_DNCLK_100M_DB800ZL_PEX2_S3_DPCLK_100M_DB800ZL_PEX2_S3_R_DPSMB_9ZXL0451E_S3_ADDR0CLK_100M_DB800ZL_PEX2_S3_DNCLK_100M_DB800ZL_PEX2_S3_R_DNCLK_100M_DB800ZL_PEX3_S3_DPCLK_100M_DB800ZL_PEX3_S3_R_DPSMB_BMC_9FGL0451E_S3_SDACLK_100M_DB800ZL_PEX3_S3_DNCLK_100M_DB800ZL_PEX3_S3_R_DNSMB_BMC_9FGL0451E_S3_SCLFM_CLK_EN_RPEX_S3_REF_CLK_BUFFER_EN_N



5
5
4
4
3
3
2
2
1
1
D D
C C
B B
A A
BOARD_TYPE
DVT_CHANGE
ITEM BIC NET NAME VENSORS VOLTAGE(V)
HSC
VR
ADC
RESERVED
RESERVED
RESERVED
HSC_TYPE_ADC_R
VR_TYPE_ADC_R
ADC_TYPE_ADC_R
BOARD_TYPE_0_ADC_R
BOARD_TYPE_1_ADC_R
BOARD_TYPE_1_ADC_R
MPS
LTC4282
LTC4287
RENESAS
INFINEON
MPS
RENESAS
TI
RESERVED
RESERVED
RESERVED
0
1
1.5
0
0.5
1
0
0.5
0
0
0
ITEM
USB_HUB
PART NUMBER VENDER BOM OPTION
UARTBRIDGE
GL852G-OHY60 GSL USB_BOM1
TUSB8042AIRGCR TI USB_BOM2
FT4232HL-REEL FTI UART_BOM1
CP2108-B03-GMR
HEADER
FTI UART_BOM2
UART_BOM3(NA)
COMP LT6700CS6-1#TRPBF
AP331AWG-7
LIN
DDS
COMP_BOM1
COMP_BOM2
CSOUT
WR04X000PTR WTC CSOUT_BOM1
LT6700CS6-1#TRPBF LIN
AP331AWG-7 DDS
CSOUT_BOM2
CSOUT_BOM3
CS35602FB00CS32322FB03VR_TYPE_ADC_RNARENESASINFINEONMPSR6821 Partnumber ValueNA56K ohm23.2K ohmPVT_CHANGEPVT_CHANGEHSC_TYPE_ADC_R[85,86,213]HSC_TYPE_ADC_R [85,86,213]BOARD_TYPE_0_ADC_R [86]BOARD_TYPE_1_ADC_R [86]BOARD_TYPE_2_ADC_R [86]VR_TYPE_ADC_R [86]ADC_TYPE_ADC_R [86]P3V3_AUXP3V3_AUXP3V3_AUXP3V3_AUXP3V3_AUXP12V_AUX
SizeDoc NumberRevDate: SheetofReviewerDesignerDepartmentProject
Page TitleCCBU D85 257Tuesday, August 29, 2023<project_name><Designer> GRANDTETON_SWB_20230829085 BLANK<Reviewer>SizeDoc NumberRevDate: SheetofReviewerDesignerDepartmentProject
Page TitleCCBU D85 257Tuesday, August 29, 2023<project_name><Designer> GRANDTETON_SWB_20230829085 BLANK<Reviewer>SizeDoc NumberRevDate: SheetofReviewerDesignerDepartmentProject
Page TitleCCBU D85 257Tuesday, August 29, 2023<project_name><Designer> GRANDTETON_SWB_20230829085 BLANK<Reviewer>
C44880.1UFC0402-0201NIR681610KR0402-02015%R6714100K1/16W1%R0402-0201<Part Number>C44900.1UFC0402-0201NI C44580.1UFC0402-0201NIR681710KR0402-02015%R682110KR0402-02015%NIR681310KR0402-02015%NI R681510KR0402-02015%NIC44890.1UFC0402-0201NIC44870.1UFC0402-0201NIR682010KR0402-02015%R682310KR0402-02015%NIR682210KR0402-02015%NIC44910.1UFC0402-0201NIR681810KR0402-02015%R681410KR0402-02015%NIR681910KR0402-02015%



5
5
4
4
3
3
2
2
1
1
D D
C C
B B
A A
CONFIG6
SKU
CONFIG4
ID2
0
0
Board ID
ID1 ID0
0
0
0
0
Internal ADC Reference Voltage Selection00b: 2.5V01b: 1.2V10b: External Voltage (1.55v to 2.7v)11b: External Voltage (0.9v to 1.65v)
BIC_1
CONFIG9
CONFIG3
00 0
00 0
MP_CHANGE
PVT_CHANGE
RESERVE
PRSNT_NIC0_R_N[116,170]PRSNT_NIC1_R_N[116,173]PRSNT_NIC2_R_N[116,176]PRSNT_NIC3_R_N[116,179]PRSNT_NIC4_R_N[116,182]PRSNT_NIC5_R_N[116,185]PRSNT_NIC6_R_N[116,188]PRSNT_NIC7_R_N[116,191]PRSNT_SSD0_R_N[115,194,202]PRSNT_SSD1_R_N[115,194,202]PRSNT_SSD2_R_N[115,195,202]PRSNT_SSD3_R_N[115,195,202]PRSNT_SSD4_R_N[115,196,202]PRSNT_SSD5_R_N[115,196,202]PRSNT_SSD6_R_N[115,197,202]PRSNT_SSD7_R_N[115,197,202]PRSNT_SSD8_R_N[117,198,203]PRSNT_SSD9_R_N[117,198,203]PRSNT_SSD10_R_N[117,199,203]PRSNT_SSD11_R_N[117,199,203]PRSNT_SSD12_R_N[117,200,203]PRSNT_SSD13_R_N[117,200,203]PRSNT_SSD14_R_N[117,201,203]PRSNT_SSD15_R_N[117,201,203]SSD0_PWRDIS_BIC_R [86,117]SSD1_PWRDIS_BIC_R [86,117]SSD2_PWRDIS_BIC_R [86,117]SSD3_PWRDIS_BIC_R [86,117]SSD4_PWRDIS_BIC_R [86,117]SSD5_PWRDIS_BIC_R [86,117]SSD6_PWRDIS_BIC_R [86,117]SSD7_PWRDIS_BIC_R [86,118]SSD8_PWRDIS_BIC_R [86,118]SSD9_PWRDIS_BIC_R [86,118]SSD10_PWRDIS_BIC_R [86,118]SSD11_PWRDIS_BIC_R [86,118]SSD12_PWRDIS_BIC_R [86,118]SSD13_PWRDIS_BIC_R [86,118]SSD14_PWRDIS_BIC_R [86,118]SSD15_PWRDIS_BIC_R [86,118]NIC0_MAIN_PWR_BIC_EN_R[116]NIC1_MAIN_PWR_BIC_EN_R[116]NIC2_MAIN_PWR_BIC_EN_R[116]NIC3_MAIN_PWR_BIC_EN_R[116]NIC4_MAIN_PWR_BIC_EN_R[116]NIC5_MAIN_PWR_BIC_EN_R[116]NIC6_MAIN_PWR_BIC_EN_R[118]NIC7_MAIN_PWR_BIC_EN_R[118]REV_ID0 [86]REV_ID1 [86]REV_ID2 [86]BOARD_ID0 [86]BOARD_ID1 [86]BOARD_ID2 [86]HSC_D_OC_BUF_R_N [118,213,215]HSC_UV_R_N [118,215]REV_ID0[86]REV_ID1[86]REV_ID2[86]BOARD_ID0[86]BOARD_ID1[86]BOARD_ID2[86]BIC_FORCE_THROTTLE_R_N [86,115]USB2_BIC_DP[76,91]USB2_BIC_DN[76,91]P12V_AUX_SCALED[100]P5V_AUX_SCALED[100]HSC_TIMER_R_N [86,118]HSC_TIMER_R_N[86,118]BIC_FORCE_THROTTLE_R_N[86,115]PRSNT_DBV2_SLIMSAS_R [211]
SSD0_PWRDIS_BIC_R [86,117]SSD1_PWRDIS_BIC_R [86,117]SSD2_PWRDIS_BIC_R [86,117]SSD3_PWRDIS_BIC_R [86,117]SSD4_PWRDIS_BIC_R [86,117]SSD5_PWRDIS_BIC_R [86,117]SSD6_PWRDIS_BIC_R [86,117]SSD7_PWRDIS_BIC_R [86,118]SSD8_PWRDIS_BIC_R [86,118]SSD9_PWRDIS_BIC_R [86,118]SSD10_PWRDIS_BIC_R [86,118]SSD11_PWRDIS_BIC_R [86,118]SSD12_PWRDIS_BIC_R [86,118]SSD13_PWRDIS_BIC_R [86,118]SSD14_PWRDIS_BIC_R [86,118]SSD15_PWRDIS_BIC_R [86,118]
P3V3_AUX_SCALED[100]P1V2_AUX_SCALED[100]P3V3_SCALED[100]RST_PEX_MUX_R_N [95]P1V8_PLL0_PEX0_SCALED[100]P1V8_PLL0_PEX1_SCALED[100]P1V8_PLL0_PEX2_SCALED[100]P1V8_PLL0_PEX3_SCALED[100]HSC_TYPE_ADC_R[85,213]VR_TYPE_ADC_R[85]ADC_TYPE_ADC_R[85]BOARD_TYPE_0_ADC_R[85]BOARD_TYPE_1_ADC_R[85]BOARD_TYPE_2_ADC_R[85]P3V3_AUXP3V3_AUXP1V2_BIC_USB2AV12P3V3_BIC_USB2AV33P3V3_BIC_ADCAV33P1V2_BIC_ADCVREFREXT0P1V2_BIC_ADCVREFREXT1P3V3_AUXSizeDoc NumberRevDate: SheetofReviewerDesignerDepartmentProject
Page TitleCCBU D86 257Tuesday, August 29, 2023<project_name><Designer> GRANDTETON_SWB_20230829086 BIC_1<Reviewer>SizeDoc NumberRevDate: SheetofReviewerDesignerDepartmentProject
Page TitleCCBU D86 257Tuesday, August 29, 2023<project_name><Designer> GRANDTETON_SWB_20230829086 BIC_1<Reviewer>SizeDoc NumberRevDate: SheetofReviewerDesignerDepartmentProject
Page TitleCCBU D86 257Tuesday, August 29, 2023<project_name><Designer> GRANDTETON_SWB_20230829086 BIC_1<Reviewer>
R4548 100R4524 0 R0402-02015%R4515 0 R0402-02015%R4541 0 R0402-02015%R4521 0 R0402-02015%R4525 0 R0402-02015%R4551 1KNIR4549 100R4542 0 R0402-02015%
R6195 4.7K 5% R0402-0201
R4538 0 R0402-02015%
R6183 4.7K 5% R0402-0201
R676049.91%NI
R6190 4.7K 5% R0402-0201R4544 1KNIR5910 0 R0402-02015%R4526 0 R0402-02015%R6186 4.7K 5% R0402-0201R4516 0 R0402-02015%
R676149.9<Part Number>R0402-02011%NIR4539 0 R0402-02015%R4543 0 R0402-02015%
R6184 4.7K 5% R0402-0201R4527 0 R0402-02015%
R4852 49.9K R0402-02011%
R6196 4.7K 5% R0402-0201R4552 1KNIR4517 0 R0402-02015%R6191 4.7K 5% R0402-0201R6187 4.7K 5% R0402-0201
R4536 0 R0402-02015%R5912 4.7K 5% R0402-0201R4528 0 R0402-02015%
C3614 0.01UF10% 25VX7R
R6185 4.7K 5% R0402-0201R4545 1KNIR4853 49.9K R0402-02011%R4556 0 R0402-02015%R4529 0 R0402-02015%R4553 100NIR6188 4.7K 5% R0402-0201R6197 4.7K 5% R0402-0201R6192 4.7K 5% R0402-0201
C3617 0.01UF10% 25VX7RC36150.01UFR6361 0 R0402-02015%R4546 1KNIR4554 1001/6AST1030A1-GPU5AGPIOA0||PWM8||SALT1N4GPIOA1||PWM9||SALT2P4GPIOA2||PWM10||SALT3P1GPIOA3||PWM11||SALT4P5GPIOA4||PWM12||SALT5P2GPIOA5||PWM13||SALT6P3GPIOA6||PWM14||SALT7R1GPIOA7||PWM15||SALT8R2GPIOB0||TACH12||SALT9T1GPIOB1||TACH13||SALT10R3GPIOB2||TACH14||NCTS2T2GPIOB3||TACH15||NDCD2T3GPIOB4||TXD9||NDSR2N5GPIOB5||RXD9||NRI2P6GPIOB6||TXD10||NDTR2M5GPIOB7||RXD10||NRTS2R4GPIOC0||TXD11||THRUIN0R5GPIOC1||RXD11||THRUOUT0T4GPIOC2||TXD12||THRUIN1P7GPIOC3||RXD12||THRUOUT1N6GPIOC4||TXD13||THRUIN2P8GPIOC5||RXD13||THRUOUT2T5GPIOC6||THRUIN3R6GPIOC7||THRUOUT3T6GPIOD0R7GPIOD1||MDC1T7GPIOD2||MDIO1R8GPIOD3||MAC11LINKT8GPIOD4||RGMII1TXCKK1GPIOD5||RGMII1TXCTL||LPCPD#L3GPIOD6||RGMII1TXD0||LPCPME#L4GPIOD7||RGMII1TXD1||SIOPWREQ#M4GPIOE0||RGMII1TXD2||LPCSMI#L2GPIOE1||RGMII1TXD3||SIOS3#L1GPIOE2||RGMII1RXCK||SIOS5#M3GPIOE3||RGMII1RXCTL||SIOONCTRL#M2GPIOE4||RGMII1RXD0||SIOPBI#M1GPIOE5||RGMII1RXD1||SIOPWRGDN3GPIOE6||RGMII1RXD2||SIOPBO#N2GPIOE7||RGMII1RXD3||SIOSCI#N1R6189 4.7K 5% R0402-0201
R5911 4.7K 5% R0402-0201
R6193 4.7K 5% R0402-0201R4518 0 R0402-02015%R4537 0 R0402-02015%2/6AST1030A1-GPU5BPWM0||GPIOF0T9PWM1||GPIOF1P9PWM2||GPIOF2R9PWM3||GPIOF3T10PWM4||GPIOF4R10PWM5||GPIOF5P10PWM6||GPIOF6T11PWM7||GPIOF7N11TACH0||GPIOG0R11TACH1||GPIOG1T12TACH2||GPIOG2R12TACH3||GPIOG3T13TACH4||GPIOG4P11TACH5||GPIOG5R13TACH6||GPIOG6T14TACH7||GPIOG7T15TACH8||GPIOH0R14TACH9||GPIOH1M12TACH10||GPIOH2N12TACH11||GPIOH3P14USB2PE4USB2NF4ADC0||GPIOT0B2ADC1||GPIOT1B1ADC2||GPIOT2C1ADC3||GPIOT3D3ADC4||GPIOT4C2ADC5||GPIOT5D1ADC6||GPIOT6D2ADC7||GPIOT7E3ADCVREFP0E2ADCVREFN0E1ADCVREFEXT0F2ADCREXT0F1ADC15||GPIOU7H2ADC14||GPIOU6H1ADC13||GPIOU5J4ADC12||GPIOU4J2ADC11||GPIOU3J1ADC10||GPIOU2K3ADC9||GPIOU1K4ADC8||GPIOU0K2ADCVREFP1J3ADCVREFN1H3ADCREXT1G2ADCVREFEXT1G1ADCAV33BK5USB2AV12E5USB2AV33F5ADCAV33AJ5
R4522 0 R0402-02015%R4555 100R4514 0 R0402-02015%R6646 0 R0402-02015%R4547 100C3616 0.01UF10% 25VX7RC36180.01UF
R4519 0 R0402-02015%R4550 1KR4523 0 R0402-02015%R4540 0 R0402-02015%C3619 0.01UFC0402_OCTAGONXA10% 25VX7R<Part Number>
R6182 4.7K 5% R0402-0201R6194 4.7K 5% R0402-0201R4520 0 R0402-02015%SSD0_PWRDIS_BICPRSNT_NIC0_R_NPRSNT_NIC1_R_NPRSNT_NIC2_R_NPRSNT_NIC3_R_NPRSNT_NIC4_R_NPRSNT_NIC5_R_NPRSNT_NIC6_R_NPRSNT_NIC7_R_NPRSNT_SSD0_R_NPRSNT_SSD1_R_NPRSNT_SSD2_R_NPRSNT_SSD3_R_NPRSNT_SSD4_R_NPRSNT_SSD5_R_NPRSNT_SSD6_R_NPRSNT_SSD7_R_NPRSNT_SSD8_R_NPRSNT_SSD9_R_NPRSNT_SSD10_R_NPRSNT_SSD11_R_NPRSNT_SSD12_R_NPRSNT_SSD13_R_NPRSNT_SSD14_R_NPRSNT_SSD15_R_NSSD1_PWRDIS_BICSSD2_PWRDIS_BICSSD3_PWRDIS_BICSSD4_PWRDIS_BICSSD5_PWRDIS_BICSSD6_PWRDIS_BICSSD7_PWRDIS_BICSSD8_PWRDIS_BICSSD9_PWRDIS_BICSSD10_PWRDIS_BICSSD11_PWRDIS_BICSSD12_PWRDIS_BICSSD13_PWRDIS_BICSSD14_PWRDIS_BICSSD15_PWRDIS_BICSSD0_PWRDIS_BIC_RSSD1_PWRDIS_BIC_RSSD2_PWRDIS_BIC_RSSD3_PWRDIS_BIC_RSSD4_PWRDIS_BIC_RSSD5_PWRDIS_BIC_RSSD6_PWRDIS_BIC_RSSD7_PWRDIS_BIC_RSSD8_PWRDIS_BIC_RSSD9_PWRDIS_BIC_RSSD10_PWRDIS_BIC_RSSD11_PWRDIS_BIC_RSSD12_PWRDIS_BIC_RSSD13_PWRDIS_BIC_RSSD14_PWRDIS_BIC_RSSD15_PWRDIS_BIC_RNIC0_MAIN_PWR_BIC_ENNIC1_MAIN_PWR_BIC_ENNIC2_MAIN_PWR_BIC_ENNIC3_MAIN_PWR_BIC_ENNIC4_MAIN_PWR_BIC_ENNIC5_MAIN_PWR_BIC_ENNIC6_MAIN_PWR_BIC_ENNIC7_MAIN_PWR_BIC_ENNIC0_MAIN_PWR_BIC_EN_RNIC1_MAIN_PWR_BIC_EN_RNIC2_MAIN_PWR_BIC_EN_RNIC3_MAIN_PWR_BIC_EN_RNIC4_MAIN_PWR_BIC_EN_RNIC5_MAIN_PWR_BIC_EN_RNIC6_MAIN_PWR_BIC_EN_RNIC7_MAIN_PWR_BIC_EN_RREV_ID0REV_ID1REV_ID2BOARD_ID0BOARD_ID1BOARD_ID2HSC_D_OC_BUF_R_NHSC_UV_R_NREV_ID0REV_ID1REV_ID2BOARD_ID0BOARD_ID1BOARD_ID2BIC_FORCE_THROTTLE_NBIC_FORCE_THROTTLE_R_NUSB2_BIC_DPUSB2_BIC_DNP1V2_BIC_USB2AV12P3V3_BIC_USB2AV33P12V_AUX_SCALEDP5V_AUX_SCALEDPD_BIC_ADCREXT0PD_BIC_ADCREXT1BIC_ADCVREFP0BIC_ADCVREFN0BIC_ADCVREFP1BIC_ADCVREFN1HSC_TIMER_R_NHSC_TIMER_NPRSNT_DBV2_SLIMSAS_RP3V3_AUX_SCALEDP1V2_AUX_SCALEDP3V3_SCALEDRST_PEX_MUX_NP1V8_PLL0_PEX0_SCALEDP1V8_PLL0_PEX1_SCALEDP1V8_PLL0_PEX2_SCALEDP1V8_PLL0_PEX3_SCALEDHSC_TYPE_ADC_RHSC_D_OC_BIC_N



5
5
4
4
3
3
2
2
1
1
D D
C C
B B
A A
For GPIOM0/TXD6(PinB15) - RST_SSD_LED_IOEXP_R_Nit is used as "Secure Boot function" selection:0: Disable Secure Boot1: Enable Secure Boot
STRAP GPION0STRAP GPION2
BIC_2
DVT_CHANGEDVT_CHANGE
DVT_CHANGE
DVT_CHANGEPVT_CHANGE
PVT_CHANGEPVT2_BOM_CHANGEPVT2_BOM_CHANGE
SMB_NIC0_R_SCL[168]SMB_NIC0_R_SDA[168]SMB_NIC1_R_SCL[171]SMB_NIC1_R_SDA[171]SMB_NIC2_R_SCL[174]SMB_NIC2_R_SDA[174]SMB_NIC3_R_SCL[177]SMB_NIC3_R_SDA[177]SMB_FIO_R1_SCL[211,212]SMB_FIO_R1_SDA[211,212]SMB_BIC_I2C6_R_SCL[90,99]SMB_BIC_I2C6_R_SDA[90,99]SMB_NIC4_R_SCL[94]SMB_NIC4_R_SDA[94]SMB_NIC5_R_SCL[94]SMB_NIC5_R_SDA[94]SMB_NIC6_R_SCL[94]SMB_NIC6_R_SDA[94]SMB_NIC7_R_SCL[94]SMB_NIC7_R_SDA[94]SMB_MB_I3C_ISO_SCL [87,158]SMB_MB_I3C_ISO_SDA [87,158]SMB_BIC_I2C9_SSD_MUX_R_SCL [87,96]SMB_BIC_I2C9_SSD_MUX_R_SDA [87,96]SMB_PEX_R_SCL [87,95]SMB_PEX_R_SDA [87,95]CLK_25M_BIC_CLKIN[88]RST_BIC_EXTRST_N[87,92]BIC_HEARTBEAT_N[88]
SMB_MB_I3C_ISO_SCL[87,158]SMB_MB_I3C_ISO_SDA[87,158]SMB_BIC_FPGA_R_SCL[87,115]SMB_BIC_FPGA_R_SDA[87,115]SMB_BIC_I2C9_SSD_MUX_R_SCL[87,96]SMB_BIC_I2C9_SSD_MUX_R_SDA[87,96]SMB_PEX_R_SCL[87,95]SMB_PEX_R_SDA[87,95]UART_BIC_DEBUG_R_TX [211]UART_BIC_DEBUG_RX [211]JTAG_BIC_TCK_R[87,120]JTAG_BIC_EN_R[120]JTAG_BIC_NTRST_R_N [87]JTAG_BIC_TCK_R [87,120]JTAG_BIC_TMS_R [87,120]JTAG_BIC_TDI_R [87,120]JTAG_BIC_TDO_R [87,120]JTAG_BIC_NTRST_R_N[87]JTAG_BIC_NTRST_R_N [87]JTAG_BIC_TCK_R [87,120]JTAG_BIC_TMS_R [87,120]RST_SMB_SSD_R_N [101,102]RST_SMB_FIO_R_N [87,211]RST_SMB_NIC_MUX_R_N [169,172,175,178,181,184,187,190]RST_SMB_FIO_R_N[87,211]
RST_BIC_SRST_R_N[92]RST_BIC_EXTRST_N[87,92]
SGPIO_BIC_DOUT[93]UART_BIC_DEBUG_TX [93]SGPIO_BIC_CLK[93]RST_SMB_FPGA_R_N [117]BIC_UART_BIC_SEL_R[211]NIC_ADC_ALERT_N[110,111]SSD_0_7_ADC_ALERT_N[106,107]SSD_8_15_ADC_ALERT_N[108,109]RST_BIC_I2C9_SSD_MUX0_R_N[96]RST_BIC_I2C9_SSD_MUX1_R_N[96]RST_BIC_I2C6_MUX_R_N[99]RST_SSD_LED_IOEXP_R_N[90,93]RST_PEX_USB_HUB_R_N[70]RST_BIC_USB_HUB_R_N[76,91,93]IRQ_SSD_LED_IOEXP_R_N[90]PEX_ADC_ALERT_N[112,113]MB_BIC_MON [132]MB_BMC_MON_ISO_R[132]FM_SYS_THROTTLE_R[118,192]JTAG_BIC_TDI_R[87,120]JTAG_BIC_TDO_R[87,120]JTAG_BIC_TMS_R[87,120]SMB_BIC_FPGA_R_SCL [87,115]SMB_BIC_FPGA_R_SDA [87,115]SMB_BIC_FPGA_R1_SCL [118]SMB_BIC_FPGA_R1_SDA [118]SMB_BIC_FPGA_SDA [87]SMB_BIC_FPGA_SDA[87]SMB_BIC_FPGA_SCL[87]SMB_BIC_FPGA_SCL [87]P1V2_AUX
P3V3_AUX
P3V3_AUXP1V2_AUX
P3V3_AUXP3V3_AUXP3V3_AUX
PECI_VDD
P3V3_AUXP1V2_AUXSizeDoc NumberRevDate: SheetofReviewerDesignerDepartmentProject
Page TitleCCBU D87 257Tuesday, August 29, 2023<project_name><Designer> GRANDTETON_SWB_20230829087 BIC_2<Reviewer>SizeDoc NumberRevDate: SheetofReviewerDesignerDepartmentProject
Page TitleCCBU D87 257Tuesday, August 29, 2023<project_name><Designer> GRANDTETON_SWB_20230829087 BIC_2<Reviewer>SizeDoc NumberRevDate: SheetofReviewerDesignerDepartmentProject
Page TitleCCBU D87 257Tuesday, August 29, 2023<project_name><Designer> GRANDTETON_SWB_20230829087 BIC_2<Reviewer>R5279 33 R0402-02011%R1499 0 R0402-0201R4891 0 R0402-0201R5288 0 R0402-0201R5475 4.7K 5% R0402-0201R5280 4.7K5%NIR4873 4.7K 5% R0402-0201NI
R1479 200 R0402-02013/6
AST1030A1-GP
U5CSCL1||GPIOH4R15SDA1||GPIOH5P12SCL2||GPIOH6P13SDA2||GPIOH7N14SCL3||GPIOI0T16SDA3||GPIOI1R16SCL4||GPIOI2P15SDA4||GPIOI3P16SCL5||GPIOI4M13SDA5||GPIOI5N15SCL6||GPIOI6N16SDA6||GPIOI7M14SCL7||GPIOJ0||I3C1SCLM15SDA7||GPIOJ1||I3C1SDAM16SCL8||GPIOJ2||I3C2SCLL14SDA8||GPIOJ3||I3C2SDAL15SCL9||GPIOJ4||I3C3SCLL16SDA9||GPIOJ5||I3C3SDAK16SCL10||GPIOJ6||I3C4SCLK14SDA10||GPIOJ7||I3C4SDAK15I3C1SCL||SCL11||GPIOK0J16I3C1SDA||SDA11||GPIOK1J15I3C2SCL||SCL12||GPIOK2J14I3C2SDA||SDA12||GPIOK3H16I3C3SCL||SCL13||GPIOK4H15I3C3SDA||SDA13||GPIOK5G15I3C4SCL||SCL14||GPIOK6J13I3C4SDA||SDA14||GPIOK7G16TXD1||GPIOL0F12RXD1||GPIOL1E12TXD2||GPIOL2D15RXD2||GPIOL3D16TXD3||GPIOL4C16RXD3||GPIOL5C15TXD4||GPIOL6B16RXD4||GPIOL7F11TXD6||GPIOM0||NRTS1B15RXD6||GPIOM1||NDCD1E11TXD7||GPIOM2||NDTR1D14RXD7||GPIOM3||NRI1C14TXD8||GPIOM4||NDSR1A16RXD8||GPIOM5||NCTS1A15TXD5D13RXD5A14SGPMCLK||GPION0B14SGPMLD||GPION1C13SGPMO||GPION2D12SGPMI||GPION3C12
PECIH14
NTRST2||MNTRST2||GPIOO4B13TCK2||MTCK2||GPIOO5A13TDI2||MTDI2||GPIOO6D11TDO2||MTDO2||GPIOO7C11TMS2||MTMS2||GPIOP0B12NTRST||MNTRST1||GPIOP1A12TCK||MTCK1||GPIOP2D10TDI||MTDI1||GPIOP3C10TDO||MTDO1||GPIOP4A11TMS||MTMS1||GPIOP5B11
CLKIND4SRST#C3EXTRST#B3ENTESTA3HBLEDA2RSTIND#C4PECIVDDH13I3CVDDL1J12I3CVDDL2_K13K13I3CVDDL2_L13L13R5480 0 R0402-0201NI
R5770 33 R0402-02011%R149733R0402-0201
R4880 4.7K 5% R0402-0201NI
R4862 0 R0402-02015%R5501 0 R0402-0201
R4878 4.7K 5% R0402-0201NIR5067 4.7K5%R4892 0 R0402-0201R4881 1K 1% R0402-0201NIR4885 2.2K 5% R0402-0201R5722 33 R0402-02011%R4876 4.7K 5% R0402-0201NI
R5712 1K1/16W 1%R0402-0201<Part Number>R1500 0 R0402-0201
R6413 4.7K 5% R0402-0201R4874 4.7K 5% R0402-0201NI
R1480 200 R0402-0201R5719 33 R0402-02011%R5281 4.7K5%R0402-0201
R1490 33 R0402-0201
R5284 4.7K5%NI
R680233R0402-0201R679933R0402-0201R4882 1K 1% R0402-0201NI
R4861 10KR0402-02011%R148522R0402-0201
R4886 2.2K 5% R0402-0201
R1501 0 R0402-0201R41131K1%R0402-0201
C36220.1UF16VX7R10%C0402_OCTAGONXA
R4887 4.7K 5% R0402-0201
R680333R0402-0201R5278 33 R0402-02011%R1492 33 R0402-0201R680033R0402-0201R41141K1%R0402-0201R5282 4.7K5%NIR4871 4.7K 5% R0402-0201R1502 0 R0402-0201R4893 33 R0402-02011%R6414 4.7K 5% R0402-0201R4883 4.7K 5% R0402-0201
C3621 1UF C0402-020125V10% X6S
R5289 0 R0402-0201
R148333R0402-0201R5721 33 R0402-02011%R1481 200 R0402-0201R149133R0402-0201R148733R0402-0201R5718 33 R0402-02011%R4888 4.7K 5% R0402-0201R4898 33 R0402-02011%R1494 33 R0402-0201R1503 0 R0402-0201R4872 4.7K 5% R0402-0201R6296100K1% R0402-0201<Part Number>R4895 33 R0402-02011%R1484 200 R0402-0201
R5283 4.7K5%NIR5715 0 R0402-0201R148933R0402-0201C36230.1UF16VX7R10%C0402_OCTAGONXAR149333R0402-0201
R4884 4.7K 5% R0402-0201
R1486 200 R0402-0201R1477 200 R0402-0201R1496 33 R0402-0201R1504 0 R0402-0201R1488 200 R0402-0201R5285 0 R0402-0201R5716 33 R0402-02011%R5890 0 R0402-0201R1498 0 R0402-0201R1478 200 R0402-0201
R5066 4.7K5%R4879 4.7K 5% R0402-0201NIR5720 33 R0402-02011%R1505 0 R0402-0201R149533R0402-0201
R5068 4.7K5%R4877 4.7K 5% R0402-0201NIR4894 33 R0402-02011%R4875 4.7K 5% R0402-0201NI R6412 4.7K 5% R0402-0201
SMB_NIC0_SCLSMB_NIC0_SDASMB_NIC1_SCLSMB_NIC1_SDASMB_NIC2_SCLSMB_NIC2_SDASMB_NIC3_SCLSMB_NIC3_SDASMB_FIO_SCLSMB_FIO_SDASMB_BIC_I2C6_SCLSMB_BIC_I2C6_SDASMB_NIC4_SCLSMB_NIC4_SDASMB_NIC5_SCLSMB_NIC5_SDASMB_NIC6_SCLSMB_NIC6_SDASMB_NIC7_SCLSMB_NIC7_SDAI3C_MB_SCLSMB_MB_I3C_ISO_SCLI3C_MB_SDASMB_BIC_FPGA_SCLSMB_BIC_FPGA_SDASMB_BIC_I2C9_SSD_MUX_SCLSMB_BIC_I2C9_SSD_MUX_SDASMB_PEX_SCLSMB_PEX_SDA
SMB_BIC_I2C6_SCLSMB_BIC_I2C6_SDA
CLK_25M_BIC_CLKINRST_BIC_EXTRST_NBIC_HEARTBEAT_NBIC_PECIPECI_VDD
SMB_FIO_SCLSMB_FIO_SDASMB_NIC4_SCLSMB_NIC4_SDASMB_NIC5_SCLSMB_NIC5_SDASMB_NIC6_SCLSMB_NIC6_SDASMB_NIC7_SCLSMB_NIC7_SDAUART_BIC_DEBUG_TXUART_BIC_DEBUG_R_RXUART_BIC_DEBUG_R_TXUART_BIC_DEBUG_RXJTAG_BIC_TCKJTAG_BIC_EN_RJTAG_BIC_ENJTAG_BIC_NTRST_R_NJTAG_BIC_NTRST_NRST_SMB_SSD_NRST_SMB_SSD_R_NRST_SMB_FIO_NRST_SMB_FIO_R_NRST_SMB_NIC_MUX_NRST_SMB_NIC_MUX_R_N
RST_BIC_SRST_BIC_N
SGPIO_BIC_DOUTSGPIO_BIC_CLK
PD_BIC_ENTEST
RST_SMB_FPGA_NRST_SMB_FPGA_R_NBIC_UART_BIC_SELBIC_UART_BIC_SEL_RNIC_ADC_ALERT_NSSD_0_7_ADC_ALERT_NSSD_8_15_ADC_ALERT_NRST_BIC_I2C9_SSD_MUX0_R_NRST_BIC_I2C9_SSD_MUX0_NRST_BIC_I2C9_SSD_MUX1_R_NRST_BIC_I2C9_SSD_MUX1_NRST_BIC_I2C6_MUX_R_NRST_BIC_I2C6_MUX_NRST_SSD_LED_IOEXP_R_NRST_SSD_LED_IOEXP_NRST_PEX_USB_HUB_R_NRST_PEX_USB_HUB_NRST_BIC_USB_HUB_R_NRST_BIC_USB_HUB_NIRQ_SSD_LED_IOEXP_R_NPEX_ADC_ALERT_NMB_BIC_MONMB_BMC_MON_ISO_RFM_SYS_THROTTLE_RFM_SYS_THROTTLE_R1SMB_NIC0_R_SCLSMB_NIC0_R_SDASMB_NIC1_R_SCLSMB_NIC1_R_SDASMB_NIC2_R_SCLSMB_NIC2_R_SDASMB_NIC3_R_SCLSMB_NIC3_R_SDASMB_FIO_R1_SCLSMB_FIO_R1_SDASMB_BIC_I2C6_R_SCLSMB_BIC_I2C6_R_SDASMB_NIC4_R_SCLSMB_NIC4_R_SDASMB_NIC5_R_SCLSMB_NIC5_R_SDASMB_NIC6_R_SCLSMB_NIC6_R_SDASMB_NIC7_R_SCLSMB_NIC7_R_SDAJTAG_BIC_TCK_RSMB_MB_I3C_ISO_SDASMB_BIC_I2C9_SSD_MUX_R_SCLSMB_BIC_I2C9_SSD_MUX_R_SDASMB_PEX_R_SCLSMB_PEX_R_SDAJTAG_BIC_TDI_RJTAG_BIC_TDIJTAG_BIC_TDO_RJTAG_BIC_TDO_R1JTAG_BIC_TMS_RJTAG_BIC_TMSRST_BIC_I2C9_SSD_MUX0_NRST_BIC_I2C9_SSD_MUX1_NRST_BIC_I2C6_MUX_NSMB_BIC_FPGA_R_SCLSMB_BIC_FPGA_R_SDASMB_BIC_FPGA_R1_SCLSMB_BIC_FPGA_R1_SDASMB_BIC_FPGA_R2_SCLSMB_BIC_FPGA_R2_SDA



5
5
4
4
3
3
2
2
1
1
D D
C C
B B
A A
120ohm@100MHzDCR=50mohmIsat=2.5A120ohm@100MHzDCR=50mohmIsat=2.5A120ohm@100MHzDCR=50mohmIsat=2.5A
HEART BEATING LED
LPC : 3.3VESPI: 1.8v
P3V3_AUX -> P1V8_PEX OPEN DRAIN
OPEN DRAIN
STRAP GPIOR6STRAP GPIOS0 P3V3_BIC_ADCAV33 power trace at least 20 mil 
Add Test Point OnU5.C5
BIC_3
SPI_BIC1_CS0_N[63,88]SPI_BIC1_CS1_N[88]SPI_BIC1_CLK[63,93]SPI_BIC1_MOSI[63]SPI_BIC1_MISO[63,93]SPI_BIC1_CS0_N [63,88]SPI_BIC1_CS1_N [88]BIC_HEARTBEAT_N [87]CLK_25M_BIC_CLKIN [87]PRSNT_GPU_ISO_R_N[124]SMB_FPGA_ALERT_R_N[115]SMB_ALERT_PMBUS_R_N[223,226]SMB_ALERT_HSC_R_N[118,216]RST_BIC_SELF_HW_RST_R_N[88,92]
BIC_SYS_READY_R_N [132]SYS_PWR_READY_R_N [115]BIC_SEL_FLASH_SW0_R [88]BIC_SEL_FLASH_SW1_R [88]BIC_SEL_FLASH_SW2_R [88]BIC_SEL_FLASH_SW3_R [88]BIC_SEL_FLASH_SW0_R[88]SEL_FLASH_PEX0_BUF_R [16,63]BIC_SEL_FLASH_SW1_R[88]SEL_FLASH_PEX1_BUF_R [29,63]BIC_SEL_FLASH_SW2_R[88]SEL_FLASH_PEX2_BUF_R [42,63]BIC_SEL_FLASH_SW3_R[88]SEL_FLASH_PEX3_BUF_R [55,63]
BIC_SEL_FLASH_SW0_R [88]BIC_SEL_FLASH_SW0_R [88]BIC_SEL_FLASH_SW1_R [88]BIC_SEL_FLASH_SW1_R [88]BIC_SEL_FLASH_SW2_R [88]BIC_SEL_FLASH_SW2_R [88]BIC_SEL_FLASH_SW3_R [88]BIC_SEL_FLASH_SW3_R [88]BIC_FWSPICK[93,211]BIC_FWSPIMISO[93]RST_MB_BMC_N[132]USB_DEBUG_RST_BTN_R_N[212]RST_BIC_SELF_HW_RST_R_N [88,92]P3V3_AUX
P1V2_BIC_USB2AV12P1V2_AUXP3V3_AUXP3V3_BIC_USB2AV33P3V3_AUXP3V3_BIC_ADCAV33P1V2_AUXP1V2_BIC_ADCVREFREXT0P1V2_AUXP1V2_BIC_ADCVREFREXT1P3V3_AUXP3V3_AUXP3V3_AUXP3V3_AUX
P3V3_AUXP3V3_AUXP3V3_AUXP3V3_AUX
P3V3_LEDP3V3_AUX
SizeDoc NumberRevDate: SheetofReviewerDesignerDepartmentProject
Page TitleCCBU D88 257Tuesday, August 29, 2023<project_name><Designer> GRANDTETON_SWB_20230829088 BIC_3<Reviewer>SizeDoc NumberRevDate: SheetofReviewerDesignerDepartmentProject
Page TitleCCBU D88 257Tuesday, August 29, 2023<project_name><Designer> GRANDTETON_SWB_20230829088 BIC_3<Reviewer>SizeDoc NumberRevDate: SheetofReviewerDesignerDepartmentProject
Page TitleCCBU D88 257Tuesday, August 29, 2023<project_name><Designer> GRANDTETON_SWB_20230829088 BIC_3<Reviewer>R6151 4.7K 5% R0402-0201R4854 0 5%1/16WR0402-0201NI
R5304 4.7K5%NIR5290 0 R0402-02015%
L146BLM18PG121SN1D21R530033 R0402-02011%R529833 R0402-02011%R54184.7K5%
R4860 221%R0402-0201R6152 4.7K 5% R0402-0201R32864.7K5%R0402-0201OSC225MHZFJ2500009<Part Number>OE1GND2OUT3VDD4C36100.1UFC0402_OCTAGONXA
R1506 4.7K 5%R0402-0201
R54204.7KR0402-02015%
R5414 4.7KR0402-0201 5%
C36120.1UFC0402_OCTAGONXA  R54194.7KR0402-02015%C36111UFC0402_OCTAGONXAR5292 0 R0402-02015%R54214.7KR0402-02015%R4857 100 R0402-02015%R5295 0 R0402-02015%
C36240.1UF16VX7R10%C0402_OCTAGONXAR5415 4.7KR0402-0201 5%
L147BLM18PG121SN1D21D7LED_BLUEACR5293 0 R0402-02015%R6149 4.7K 5% R0402-0201R5296 0 R0402-02015%R1507 4.7K 5%R0402-0201
C36260.1UFC0402-0201C36250.1UFC0402-0201
R5301 4.7K5%NI
C36050.1UFR5416 4.7KR0402-0201 5%
C36070.1UFR5294 0 R0402-02015%
4/6AST1030A1-GPU5DLAD0||ESPID0||GPION4G14LAD1||ESPID1||GPION5F16GPION6||LAD2||ESPID2F15LAD3||ESPID3||GPION7F14LCLK||ESPICK||GPIOO0E16LFRAME#||ESPICS#||GPIOO1E15LSIRQ#||ESPIALT#||GPIOO2E14LPCRST#||ESPIRST#||GPIOO3E13LPVDD_G13G13LPVDD_F13F13
R4855 0 5%1/16WR0402-0201NI
C45020.22UF25V10%C0402-0201
C36081UFU352SN74LVC2G07DCKR1A12A31Y62Y4GND2VCC5
R5302 4.7K5%NIR5417 4.7KR0402-0201 5%U351SN74LVC2G07DCKR1A12A31Y62Y4GND2VCC5 C36061UFR529933 R0402-02011%
R5913 4.7K 5%R0402-0201R6150 4.7K 5% R0402-0201R529733 R0402-02011%C36130.1UFC0402_OCTAGONXA  5/6AST1030A1-GPU5ESPI2CS0#||GPIOP6A10SPI2CS1#||GPIOP7B10SPI2CK||GPIOQ0A9SPI2MOSI||GPIOQ1B9SPI2MISO||GPIOQ2C9SPI2DQ2||GPIOQ3D9SPI2DQ3||GPIOQ4A8FWSPICS1#F7FWSPICKE7FWSPIMOSIC5FWSPIMISOC8FWSPIDQ2D8FWSPIDQ3D5SPI1CS0#A7SPI1CS1#B6SPI1CKA5SPI1MOSIA6SPI1MISOB5SPI1DQ2||GPIOS1A4SPI1DQ3||GPIOS2B4R485910K1%R0402-0201<Part Number>R5303 4.7K5%NIR6148 4.7K 5% R0402-0201L148BLM18PG121SN1D21C36200.1UF25V10%X6SSPI_BIC1_CS0_NSPI_BIC1_CS1_NSPI_BIC1_CLKSPI_BIC1_MOSISPI_BIC1_MISOSPI_BIC1_CS0_NSPI_BIC1_CS1_NBMC_HEARTBEAT_N_DCLK_25M_BICPU_CLK_25M_BIC_ENRST_BIC_SELF_HW_RST_NRST_BIC_SELF_HW_RST_R_NPRSNT_GPU_ISO_R_NSMB_FPGA_ALERT_R_NSMB_ALERT_PMBUS_R_NSMB_ALERT_HSC_R_N
BIC_SYS_READY_NBIC_SYS_READY_R_NSYS_PWR_READY_R_NBIC_SEL_FLASH_SW0BIC_SEL_FLASH_SW0_RBIC_SEL_FLASH_SW1BIC_SEL_FLASH_SW1_RBIC_SEL_FLASH_SW2BIC_SEL_FLASH_SW2_RBIC_SEL_FLASH_SW3BIC_SEL_FLASH_SW3_RSEL_FLASH_PEX0_BUFSEL_FLASH_PEX1_BUFSEL_FLASH_PEX2_BUFSEL_FLASH_PEX3_BUFBIC_SEL_FLASH_SW0_RBIC_SEL_FLASH_SW1_RBIC_SEL_FLASH_SW2_RBIC_SEL_FLASH_SW3_R
BIC_SEL_FLASH_SW0_RBIC_SEL_FLASH_SW1_RBIC_SEL_FLASH_SW2_RBIC_SEL_FLASH_SW3_RBIC_SEL_FLASH_SW0_RBIC_SEL_FLASH_SW1_RBIC_SEL_FLASH_SW2_RBIC_SEL_FLASH_SW3_RBIC_FWSPICKRST_MB_BMC_NUSB_DEBUG_RST_BTN_R_NRST_BIC_SELF_HW_RST_R_NBIC_FWSPICS1_NBIC_FWSPIDQ2BIC_FWSPIDQ3BIC_SPI1DQ2BIC_SPI1DQ3BIC_FWSPIMOSIBIC_FWSPIMISO



5
5
4
4
3
3
2
2
1
1
D D
C C
B B
A A
PLACE UNDER BGA AND POWER PINS OF AST1030
VDD_CORE
PVDD33
PLACE UNDER BGA AND POWER PINS OF AST1030
PLLAVDD1
PLACE UNDER BGA AND POWER PINS OF AST1030
SPI_VCC
BIC_4
P1V2_AUXP3V3_AUXP1V2_AUXP3V3_AUXP1V2_AUXP1V2_BIC_PLLP1V2_BIC_PLLP3V3_AUXP3V3_BIC_SPIP3V3_BIC_SPI
SizeDoc NumberRevDate: SheetofReviewerDesignerDepartmentProject
Page TitleCCBU D89 257Tuesday, August 29, 2023<project_name><Designer> GRANDTETON_SWB_20230829089 BIC_4<Reviewer>SizeDoc NumberRevDate: SheetofReviewerDesignerDepartmentProject
Page TitleCCBU D89 257Tuesday, August 29, 2023<project_name><Designer> GRANDTETON_SWB_20230829089 BIC_4<Reviewer>SizeDoc NumberRevDate: SheetofReviewerDesignerDepartmentProject
Page TitleCCBU D89 257Tuesday, August 29, 2023<project_name><Designer> GRANDTETON_SWB_20230829089 BIC_4<Reviewer>
C201122UF20%6.3VC20210.1UFC0402_OCTAGONXA10%16VC20141UFC0402_OCTAGONXA10%25VC201222UFC0603_H4020%6.3VC20221UF10%25VC20250.1UFC0402_OCTAGONXA10%16VC20191UF10%25VC20231UF10%25VC20261UFC0402_OCTAGONXA10%25V6/6U5FAST1030A1-GPSPIVDDB8PVDD33_E8E8PVDD33_E9E9PVDD33_E10E10VDDCORE_F8F8VDDCORE_F9F9VDDCORE_F10F10PLLVDD1G3PVDD33_G4G4VDDCORE_G5G5PVDD33_G12G12PVDD33_H4H4VDDCORE_H5H5VDDCORE_H12H12VDDCORE_K12K12PVDD33_L12L12PVDD33_N7N7VDDCORE_N8N8VDDCORE_N9N9PVDD33_N10N10GND_N13N13GND_A1A1GND_B7B7GND_C6C6GND_C7C7GND_D6D6GND_D7D7GND_E6E6GND_F3F3GND_F6F6GND_G6G6GND_G7G7GND_G8G8GND_G9G9GND_G10G10GND_G11G11GND_H6H6GND_H7H7GND_H8H8GND_H9H9GND_H10H10GND_H11H11GND_J6J6GND_J7J7GND_J8J8GND_J9J9GND_J10J10GND_J11J11GND_K6K6GND_K7K7GND_K8K8GND_K9K9GND_K10K10GND_K11K11GND_L6L6GND_L7L7GND_L8L8GND_L9L9GND_L10L10GND_L11L11VDDCORE_M6M6GND_M7M7GND_M8M8GND_M9M9GND_M10M10GND_M11M11PVDD33_L5L5C20060.1UF10%16VC0402_OCTAGONXAL1BLM18PG121SN1D21C20070.1UF10%16V
C20271UFC0402_OCTAGONXA10%25VC20241UFC0402_OCTAGONXA10%25VC20080.1UF10%16VC20170.1UFC0402_OCTAGONXA10%16VC20091UF10%25V<Part Number>C20130.1UF10%16VC201522UF20%6.3VC202022UF20%6.3VC20180.1UF10%16VR457 0R0603
C201022UF20%6.3VC201622UFC0603_H4020%6.3V



5
5
4
4
3
3
2
2
1
1
D D
C C
B B
A A
Push-Pull I/OOpen-Drain INT_NSMBUS ADDRESS: 0XEC (8bit)
BIC_SSD_LED_EN_IOEXP
SSD7_LED_R[197]SSD6_LED_R[197]SSD5_LED_R[196]SSD4_LED_R[196]SSD3_LED_R[195]SSD2_LED_R[195]SSD1_LED_R[194]SSD0_LED_R[194]RST_SSD_LED_IOEXP_R_N[87,93]SSD_LED_IOEXP_A1[90]SSD_LED_IOEXP_A0 [90]SSD_LED_IOEXP_A1 [90]SSD_LED_IOEXP_A0 [90]SMB_BIC_I2C6_R_SDA [87,99]SMB_BIC_I2C6_R_SCL [87,99]SSD8_LED_R [198]SSD9_LED_R [198]SSD10_LED_R [199]SSD11_LED_R [199]SSD12_LED_R [200]SSD13_LED_R [200]SSD14_LED_R [201]SSD15_LED_R [201]IRQ_SSD_LED_IOEXP_R_N[87]P3V3_AUXP3V3_AUXP3V3_AUX
P3V3_AUXP3V3_AUXP3V3_AUX
SizeDoc NumberRevDate: SheetofReviewerDesignerDepartmentProject
Page TitleCCBU D90 257Tuesday, August 29, 2023<project_name><Designer> GRANDTETON_SWB_20230829090 BIC_SSD_LED_EN_IOEXP<Reviewer>SizeDoc NumberRevDate: SheetofReviewerDesignerDepartmentProject
Page TitleCCBU D90 257Tuesday, August 29, 2023<project_name><Designer> GRANDTETON_SWB_20230829090 BIC_SSD_LED_EN_IOEXP<Reviewer>SizeDoc NumberRevDate: SheetofReviewerDesignerDepartmentProject
Page TitleCCBU D90 257Tuesday, August 29, 2023<project_name><Designer> GRANDTETON_SWB_20230829090 BIC_SSD_LED_EN_IOEXP<Reviewer>
R43524.7K1%1/16WR4268 33R43594.7KR0402-02011%1/16WR5769 33R4263 0 R0402-02015%R4302 33R426010K<Part Number>5%R0402-0201NI R43534.7K1%1/16WR4308 33R5764 33R4304 33R426110K<Part Number>5%R0402-0201R43364.7K1%1/16WR4306 33R5766 33R43464.7K1%1/16WR43304.7K1%1/16WR43474.7K1%1/16WR43314.7K1%1/16WR5768 33R5771 33R43374.7K1%1/16WR43484.7K1%1/16WR4307 33R5763 33R43324.7K1%1/16WR4303 33R43494.7K1%1/16WR4309 33R426610K<Part Number>5%R0402-0201R43334.7K1%1/16WR5765 33C28090.1UF16VX7R10%C0402-0201R4305 33R43504.7K1%1/16WU330PCA9539RPWINT1A12RESET3IO0_04IO0_15IO0_26IO0_37IO0_48IO0_59IO0_610IO0_711VSS12IO1_013IO1_114IO1_215IO1_316IO1_417IO1_518IO1_619IO1_720A021SCL22SDA23VDD24R426710K<Part Number>5%R0402-0201NIR43344.7K1%1/16WR4264 0 R0402-02015%R43584.7KR0402-02011%1/16WNIR43514.7K1%1/16WR43354.7K1%1/16WR5767 33SSD7_LED_RSSD7_LEDSSD6_LED_RSSD6_LEDSSD5_LED_RSSD5_LEDSSD4_LED_RSSD4_LEDSSD3_LED_RSSD3_LEDSSD2_LED_RSSD2_LEDSSD1_LED_RSSD1_LEDSSD0_LED_RSSD0_LEDRST_SSD_LED_IOEXP_R_NSMB_SSD_LED_IOEXP_SDASMB_SSD_LED_IOEXP_SCLSSD0_LED_RSSD1_LED_RSSD2_LED_RSSD3_LED_RSSD4_LED_RSSD5_LED_RSSD6_LED_RSSD7_LED_RSSD8_LED_RSSD9_LED_RSSD10_LED_RSSD11_LED_RSSD12_LED_RSSD13_LED_RSSD14_LED_RSSD15_LED_RSSD8_LEDSSD8_LED_RSSD9_LEDSSD9_LED_RSSD10_LEDSSD10_LED_RSSD11_LEDSSD11_LED_RSSD12_LEDSSD12_LED_RSSD13_LEDSSD13_LED_RSSD14_LEDSSD14_LED_RSSD15_LEDSSD15_LED_RIRQ_SSD_LED_IOEXP_N



5
5
4
4
3
3
2
2
1
1
D D
C C
B B
A A
USB_HUB_I2C only for EEPROM.Remove I2C.
Port0   is to MB ( HOST )Port1   is to BICPort2   is to GPU
12M CystalMain:  BG6120000E02nd  : BG6120000B0 
BIC_USB_HUB
USB2_MB_BMC_DP [76,133]USB2_MB_BMC_DN [76,133]USB2_BIC_DP [76,86]USB2_BIC_DN [76,86]USB2_GPU_HMC_DP [76,128]USB2_GPU_HMC_DN [76,128]BIC_USB_HUB_PSELF[91]BIC_USB_HUB_PSELF [91]RST_BIC_USB_HUB_R_N[76,87,93]P3V3_AUXP3V3_BIC_USB_HUBP3V3_AUXP3V3_AUXP3V3_AUXSizeDoc NumberRevDate: SheetofReviewerDesignerDepartmentProject
Page TitleCCBU D91 257Tuesday, August 29, 2023<project_name><Designer> GRANDTETON_SWB_20230829091 BIC_USB_HUB<Reviewer>SizeDoc NumberRevDate: SheetofReviewerDesignerDepartmentProject
Page TitleCCBU D91 257Tuesday, August 29, 2023<project_name><Designer> GRANDTETON_SWB_20230829091 BIC_USB_HUB<Reviewer>SizeDoc NumberRevDate: SheetofReviewerDesignerDepartmentProject
Page TitleCCBU D91 257Tuesday, August 29, 2023<project_name><Designer> GRANDTETON_SWB_20230829091 BIC_USB_HUB<Reviewer>
R5443 0 R0402-02015%USB_BOM1R5444 0 R04025%USB_BOM1R629449.91%NIC363618PFC0402-02015%50V<Part Number>R629149.91%NIR5450 4.7K 1% 1/16W R0402-0201NIC36280.1UFX7R25V10%C0402-0201<Part Number>USB_BOM1R5458 10K 1/16W 1%R0402-0201 <Part Number>NIR5455 680<Part Number>1%R0402-0201USB_BOM1R629249.9<Part Number>R0402-02011%NIR5445 0 R04025%USB_BOM1R6844 1.5K1%R0402-0201Y812MHZUSB_BOM1X11G12G24X23C36290.1UFX7R25V10%C0402-0201<Part Number>USB_BOM1R5451 0 R04025%USB_BOM1R629349.91%NIC36301UF25VX6S10%C0402-0201<Part Number>USB_BOM1R544610K1/16W1%R0402-0201<Part Number>NIR5452 4.7K 1% 1/16W R0402-0201NIR545910K1/16W1%R0402-0201<Part Number>USB_BOM1R5442 0R0402-0201 1/16WUSB_BOM1C36310.1UFX7R25V10%C0402-0201<Part Number>USB_BOM1R5447 0 R04025%USB_BOM1C36320.1UFX7R25V10%C0402-0201<Part Number>USB_BOM1R5453 0 R04025%USB_BOM1R6181 0 R0402-02015%USB_BOM1R545647K1/16W0.1%R0402-0201<Part Number>NIR546010K1/16W1%R0402-0201<Part Number>NIR5448 4.7K 1% 1/16W R0402-0201NIC36330.1UFX7R25V10%C0402-0201<Part Number>USB_BOM1C36371UF<Part Number>C0402-020110%25VX6SUSB_BOM1R5454 4.7K 1% 1/16W R0402-0201NIC36341UF25VX6S10%C0402-0201<Part Number>USB_BOM1R5449 0 R04025%USB_BOM1U353GL852G-OHY60<Part Number>USB_BOM1X110X211TEST||SCL18SDA26V527V3328AVDD5AVDD9AVDD14DVDD21THTHOVCUR1#||SMC25OVCUR2#||SMD24OVCUR3#20OVCUR4#19RESET#17PGANG23PSELF22RREF8DP02DM01DP14DM13DP27DM26DP313DM312DP416DM415C363518PFC0402-02015%50V<Part Number>C362710UFX6SC0402-020120%6.3V<Part Number>USB_BOM1R5457100K<Part Number>R0402-02011%1/16WUSB_BOM1BIC_USB_HUB_TESTBIC_USB_HUB_XOUT_RBIC_USB_HUB_XINBIC_USB_HUB_XOUTUSB2_MB_BMC_R_DPUSB2_MB_BMC_DPUSB2_MB_BMC_R_DNUSB2_MB_BMC_DNUSB2_BIC_R_DPUSB2_BIC_DPBIC_USB_HUB_OVCUR1USB2_BIC_R_DNUSB2_BIC_DNBIC_USB_HUB_OVCUR2USB2_GPU_HMC_R_DPUSB2_GPU_HMC_DPBIC_USB_HUB_OVCUR3USB2_GPU_HMC_R_DNUSB2_GPU_HMC_DNBIC_USB_HUB_OVCUR4BIC_USB_HUB_RREFBIC_USB_HUB_PSELFBIC_USB_HUB_PGANGBIC_USB_HUB_PSELFRST_BIC_USB_HUB_R1_N



5
5
4
4
3
3
2
2
1
1
D D
C C
B B
A A
DESIGN NOTE: 2.93V, 140ms delay, open drain
BIC_RST_RSMRST_N is BMC chip reset.
H( Reset )
RST_FW_BIC_PLTRST1
H( Reset )
L
H
H
2
OPEN DRAIN
H H
H( Reset )
L( default )
L
L
L
P1V2_AUX Power Good from PMIC thru FPGA to BIC
Simple SequencersVth is 0.6VDelay : 226 ms
BIC_RST
DVT_CHANGEPVT_CHANGEPVT_CHANGEPWRGD_P1V2_AUX_DLY [92]PWRGD_P1V2_AUX_R[118,222]
RST_BIC_EXTRST_N[87]RST_FPGA_BIC_R_N [92,116]RST_BIC_SRST_R_N[87,92]BIC_RST_RSMRST_N [92]RST_MB_BIC_ISO_R_N[116,132]RST_BIC_SELF_HW_RST_R_N[88]
PWRGD_P1V2_AUX_RST[92]BIC_RST_PWRGD_RSMRST [92]BIC_RST_RSMRST_N[92]PWRGD_P1V2_AUX_FPGA_R[116]PWRGD_P1V2_AUX_RST [92]PWRGD_P1V2_AUX_DLY[92]BIC_RST_PWRGD_RSMRST[92]RST_BIC_SRST_R_N [87,92]RST_FPGA_BIC_R_N[92,116]P3V3_AUXP3V3_AUXP12V_AUXP3V3_AUX
P3V3_AUXP3V3_AUXP3V3_AUXP3V3_AUXP3V3_AUXP3V3_AUXP3V3_AUX
SizeDoc NumberRevDate: SheetofReviewerDesignerDepartmentProject
Page TitleCCBU D92 257Tuesday, August 29, 2023<project_name><Designer> GRANDTETON_SWB_20230829092 BIC_RST<Reviewer>SizeDoc NumberRevDate: SheetofReviewerDesignerDepartmentProject
Page TitleCCBU D92 257Tuesday, August 29, 2023<project_name><Designer> GRANDTETON_SWB_20230829092 BIC_RST<Reviewer>SizeDoc NumberRevDate: SheetofReviewerDesignerDepartmentProject
Page TitleCCBU D92 257Tuesday, August 29, 2023<project_name><Designer> GRANDTETON_SWB_20230829092 BIC_RST<Reviewer>
R54922KR0402-02011%1/16WR4257 33.2Q58BDMN53D0LDW-7<Part Number>D23G25S24U359ADM1085AKSZ-REEL7<Part Number>DELAY1_BOM1VCC6VIN3ENIN1ENOUT4CEXT5GND2 R5495 107KR0402-0201 1%R314510KR0402-02010.1%1/16WNI
R549310KR0402-02011%R31490R0402-02015%C36450.1UFX7RC0402-020110%16VU36274LVC1G07GWVCC5A2GND3Y4NC1
U32574LVC1G08GV12453R425810K5%R0402-0201R314810KR0402-02011%1/16WC36490.1UFC0402-0201R3153 0 R0402-02015%R5502 0 R0402-0201R5500 0 R0402-0201
R4249 33.2R0402-0201 1%
R31440R0402-02015%
R5494 0R0402-0201R4250 33.2C28080.1UF16VX7R10%C0402-0201
D23SDMK0340L-7-F<Part Number>12R57814.75KR0402-02011%1/16WC36460.1UFX7RC0402-020110%16VU450TPS3897PDRYR<Part Number>DELAY1_BOM2ENABLE1GND2SENSE3SENSE_OUT4CT5VCC6R3150100KR0402-02011%1/16WNIU36074LVC1G08GV12453 R54971KR0402-02011%NID12SDMK0340L-7-F12R425110K5%R0402-0201U32774LVC1G08GV12453
R31476.19KR0402-02011%1/16W  R5479 4.7K5%1/16WR0402-0201R3146100KR0402-02011%1/16W  Q58ADMN53D0LDW-7<Part Number>S11G12D16R4256 33.2R0402-0201 1%Q56MMBT3904<Part Number>BECR54914.75KR0402-02011%1/16WC36470.047UFX7RC0402-020110%25VC2185 0.1UFC0402-0201
R3152 0 R0402-02015%NIQ57MMBT3904<Part Number>BECU358ADM6315-29D3ARTZR7GND1RESET#2MR#3VCC4
C21470.1UF16VX7R10%C0402-0201R6804 0R0402-0201PWRGD_P1V2_AUX_DLYADM1085_INTHRESHOLDADM1085_CEXT
RST_BIC_EXTRST_R_N
RST_BJT_Q15_C RST_BJT_Q15_B
RST_FW_BIC_PLTRST_C
RST_BIC_BUF_RSMRST_N RST_BIC_BUF_RSMRST_N_BUFRST_FW_BIC_PLTRST_RRST_MB_BIC_ISO_R_NRST_FW_BIC_PLTRST_NRST_BIC_SELF_HW_RST_R_NRST_FW_BIC_PLTRST
PWRGD_P1V2_AUX_RST
BIC_RST_PWRGD_RSMRST_R
BIC_RST_RSMRST_R_N
PWRGD_P1V2_AUX_FPGA_RPWRGD_P1V2_AUX_RSTPWRGD_P1V2_AUX_DLYBIC_RST_PWRGD_RSMRSTRST_BIC_SRST_N
RST_FPGA_BIC_R1_N
ADM1085_ENOUT



5
5
4
4
3
3
2
2
1
1
D D
C C
B B
A A
Secure Boot0  Disable Secure Boot1  Enable Secure BootInternal PDLow Secure BootInternal PDEnable ACPI Function0  Disable ACPI Function1  Enable ACPI FunctionInternal PDCS Pass ThroughFor GPIOR6/SPI1CK (PinA5), it is used as "FWSPICS0# pin mux" selection:Disable engineer mode of flash passthrough(SPI1.CS1 to FWSPI.CS0)0: Disable (A1 revise)1: Enable (A1 revise)(Default boot from UART to programming FWSPI ROM)This CS mode need to be disable.Select LPC/eSPI0  eSPI1  LPCInternal PDSelect Debug port from UART10  Enable from UART51  Enable from UART1Internal PDDisable ARM CM4 CPU BOOT0  ARM Boot Disable1  ARM Boot EnableGPIOC[7:0] Pass Through0  Disable GPIO Pass Through1  Enable GPIO Pass ThroughInternal PD
BIC FW UPDATE: pop jumper0: Boot from SPI ROM1: Boot from UART
0
1
0
1
0
0
0
1
0
BIC_HW_STRAPS
RST_SSD_LED_IOEXP_R_N [87,90]BIC_FWSPIMISO [88]SGPIO_BIC_DOUT [87]SPI_BIC1_CLK [63,88]RST_BIC_USB_HUB_R_N [76,87,91]SPI_BIC1_MISO [63,88]UART_BIC_DEBUG_TX [87]SGPIO_BIC_CLK [87]
BIC_FWSPICK [88,211]P3V3_AUXP3V3_AUXP3V3_AUXP3V3_AUXP3V3_AUXP3V3_AUXP3V3_AUXP3V3_AUX
P3V3_AUX
SizeDoc NumberRevDate: SheetofReviewerDesignerDepartmentProject
Page TitleCCBU D93 257Tuesday, August 29, 2023<project_name><Designer> GRANDTETON_SWB_20230829093 BIC_HW_STRAPS<Reviewer>SizeDoc NumberRevDate: SheetofReviewerDesignerDepartmentProject
Page TitleCCBU D93 257Tuesday, August 29, 2023<project_name><Designer> GRANDTETON_SWB_20230829093 BIC_HW_STRAPS<Reviewer>SizeDoc NumberRevDate: SheetofReviewerDesignerDepartmentProject
Page TitleCCBU D93 257Tuesday, August 29, 2023<project_name><Designer> GRANDTETON_SWB_20230829093 BIC_HW_STRAPS<Reviewer>
R5526 4.7K R0402-0201NIR5531 4.7K R0402-0201NIR5532 4.7K R0402-0201R5533 4.7K R0402-0201NIR5513 4.7K R0402-0201NIR5527 4.7K R0402-0201NIR5534 4.7K R0402-0201NIR5528 4.7K R0402-0201NIR5523 4.7K R0402-0201NI
R5535 4.7K R0402-0201NI
R5522100K1% R0402-0201<Part Number>R5504 2.2K R0402-0201
R5536 4.7K R0402-0201NIR5529 4.7K R0402-0201J19SCONN3_TSM-103-01-S-SV-TR123
R5537 4.7K R0402-0201NI
R5525 4.7K R0402-0201R5530 4.7K R0402-0201R5524 4.7K R0402-0201NIJ19_12<Part Number>1BIC_FWSPICK_R



5
5
4
4
3
3
2
2
1
1
D D
C C
B B
A A
BIC 1.2V PortNIC 3.3V Port
BIC 1.2V PortNIC 3.3V Port
BIC 1.2V PortNIC 3.3V Port
BIC 1.2V PortNIC 3.3V Port
BIC_NIC_I2C_LEVEL_SHIFTER
PVT2_BOM_CHANGEPVT2_BOM_CHANGEPVT2_BOM_CHANGEPVT2_BOM_CHANGE
SMB_NIC4_R_SDA [87]SMB_NIC4_R_SCL [87]SMB_NIC4_LS_SDA[180]SMB_NIC4_LS_SCL[180]SMB_NIC5_LS_SDA[183]SMB_NIC5_R_SDA [87]SMB_NIC5_LS_SCL[183]SMB_NIC5_R_SCL [87]SMB_NIC6_LS_SDA[186]SMB_NIC6_R_SDA [87]SMB_NIC6_LS_SCL[186]SMB_NIC6_R_SCL [87]SMB_NIC7_LS_SDA[189]SMB_NIC7_R_SDA [87]SMB_NIC7_LS_SCL[189]SMB_NIC7_R_SCL [87]
P3V3_NIC4P1V2_AUXP3V3_NIC5P1V2_AUXP3V3_NIC6P1V2_AUXP3V3_NIC7P1V2_AUXSizeDoc NumberRevDate: SheetofReviewerDesignerDepartmentProject
Page TitleCCBU D94 257Tuesday, August 29, 2023<project_name><Designer> GRANDTETON_SWB_20230829094 BIC_NIC_I2C_LEVEL_SHIFTER<Reviewer>SizeDoc NumberRevDate: SheetofReviewerDesignerDepartmentProject
Page TitleCCBU D94 257Tuesday, August 29, 2023<project_name><Designer> GRANDTETON_SWB_20230829094 BIC_NIC_I2C_LEVEL_SHIFTER<Reviewer>SizeDoc NumberRevDate: SheetofReviewerDesignerDepartmentProject
Page TitleCCBU D94 257Tuesday, August 29, 2023<project_name><Designer> GRANDTETON_SWB_20230829094 BIC_NIC_I2C_LEVEL_SHIFTER<Reviewer>
R6307 825 R0402-0201
U122PCA9509DPVCCA1VCCB8A12A23GND4EN5B17B26R152610KR0402-02015%NI
R150910KR0402-02015%NIR1521 0 R0402-02015%NIU121PCA9509DPVCCA1VCCB8A12A23GND4EN5B17B26C26270.1UF10%16VC0402-0201R1535 0 R0402-02015%NI
U120PCA9509DPVCCA1VCCB8A12A23GND4EN5B17B26R15104.7KR0402-02015%R151510KR0402-02015%NIC26280.1UF10%16VC0402-0201
R151110KR0402-02015%NI
R152910KR0402-02015%NIR1527 0 R0402-02015%NIR6310 825 R0402-0201R151610KR0402-02015%NIR151210KR0402-02015%NI
R153010KR0402-02015%NIR6311 825 R0402-0201R15174.7KR0402-02015%R1528 0 R0402-02015%NI
C25550.1UF10%16VC0402-0201
R15314.7KR0402-02015%
R151810KR0402-02015%NI
R6312 825 R0402-0201
C25560.1UF10%16VC0402-0201
R153210KR0402-02015%NIR152210KR0402-02015%NIR6308 825 R0402-0201R1513 0 R0402-02015%NIR151910KR0402-02015%NI
R6313 825 R0402-0201
R6309 825 R0402-0201R153310KR0402-02015%NIR152310KR0402-02015%NIC26250.1UF10%16VC0402-0201R1514 0 R0402-02015%NI
C27050.1UF10%16VC0402-0201R15244.7KR0402-02015%C26260.1UF10%16VC0402-0201R6306 825 R0402-0201
C27060.1UF10%16VC0402-0201R1520 0 R0402-02015%NIU119PCA9509DPVCCA1VCCB8A12A23GND4EN5B17B26R152510KR0402-02015%NI
R150810KR0402-02015%NI
R1534 0 R0402-02015%NI
SMB_NIC4_LS_R_SDASMB_NIC4_LS_R_SCLSMB_NIC4_LS_ENSMB_NIC5_LS_R_SDASMB_NIC5_LS_R_SCLSMB_NIC5_LS_ENSMB_NIC6_LS_R_SDASMB_NIC6_LS_R_SCLSMB_NIC6_LS_ENSMB_NIC7_LS_R_SDASMB_NIC7_LS_R_SCLSMB_NIC7_LS_EN



5
5
4
4
3
3
2
2
1
1
D D
C C
B B
A A
PEX 1.8V PortBIC 3.3V Port
SMBUS ADDRESS: 0x70(7bit), 0XE0(8bit)
BIC_PEX_I2C_LEVEL_SHIFTER
DVT_CHANGEDVT_CHANGE
DVT_CHANGEPVT_CHANGEPVT2_BOM_CHANGESMB_PEX_R_SCL[87]SMB_PEX_R_SDA[87]SMB_PEX0_SCL [16,95]SMB_PEX0_SDA [16,95]SMB_PEX1_SCL [29,95]SMB_PEX1_SDA [29,95]SMB_PEX2_SCL [42,95]SMB_PEX2_SDA [42,95]SMB_PEX3_SCL [55,95]SMB_PEX3_SDA [55,95]PWRGD_P1V8_PEX_R[16,29,42,55,118,233]
PEX_MUX_A0[95]PEX_MUX_A1[95]SMB_PEX_LS_SDA [95]PEX_MUX_A2[95]SMB_PEX_LS_SCL [95]RST_PEX_MUX_R_N[86]SMB_PEX0_SDA[16,95]SMB_PEX0_SCL[16,95]SMB_PEX1_SDA[29,95]SMB_PEX1_SCL[29,95]SMB_PEX2_SDA[42,95]SMB_PEX2_SCL[42,95]SMB_PEX3_SDA[55,95]SMB_PEX3_SCL[55,95]PEX_MUX_A0 [95]PEX_MUX_A1 [95]PEX_MUX_A2 [95]
SMB_PEX_LS_SCL [95]SMB_PEX_LS_SDA [95]P3V3_AUXP1V8_PEX
P1V8_PEXP1V8_PEXP1V8_PEXP3V3_AUXSizeDoc NumberRevDate: SheetofReviewerDesignerDepartmentProject
Page TitleCCBU D95 257Tuesday, August 29, 2023<project_name><Designer> GRANDTETON_SWB_20230829095 BIC_PEX_I2C_LEVEL_SHIFTER<Reviewer>SizeDoc NumberRevDate: SheetofReviewerDesignerDepartmentProject
Page TitleCCBU D95 257Tuesday, August 29, 2023<project_name><Designer> GRANDTETON_SWB_20230829095 BIC_PEX_I2C_LEVEL_SHIFTER<Reviewer>SizeDoc NumberRevDate: SheetofReviewerDesignerDepartmentProject
Page TitleCCBU D95 257Tuesday, August 29, 2023<project_name><Designer> GRANDTETON_SWB_20230829095 BIC_PEX_I2C_LEVEL_SHIFTER<Reviewer>R6332 0 R0402-0201 5%NI
R1550 0 R0402-02015%R153710KR0402-02015%NIR6345 4.7K 5% R0402-0201U423TCA9548APWRNIA01A12RESET#3SD04SC05SD16SC17SD28SC29SD310SC311GND12VCC24SDA23SCL22A221SC720SD719SC618SD617SC516SD515SC414SD413R633910K<Part Number>5%R0402-0201R6322 33 R0402-0201 1%NI
R1543 33 R0402-02015%R634010K<Part Number>5%R0402-0201R6328 0 R0402-0201 5%NI
R15392.2KR0402-02015%R6346 4.7K 5% R0402-0201R6318 0 R0402-02015%NI
R153610KR0402-02015%NI
R634110K<Part Number>5%R0402-0201R1545 0 R0402-02015%R15402.2KR0402-02015%C27080.1UF10%16VC0402-0201
R6334 33 R0402-0201 1%NIR63601K1%R0402-0201<Part Number>NI
C27070.1UF10%16VC0402-0201R633610K<Part Number>5%R0402-0201NIR6161 0 R0402-02015%R1541 33 R0402-02015%R6347 4.7K 5% R0402-0201R6342 4.7K 5% R0402-0201R6319 0 R0402-02015%NIR6324 0 R0402-0201 5%NI
R1547 33 R0402-02015%R1546 0 R0402-02015%NIR633710K<Part Number>5%R0402-0201NIR1544 0 R0402-02015%NI
R6330 33 R0402-0201 1%NI
R1542 0 R0402-02015%R6348 4.7K 5% R0402-0201R6343 4.7K 5% R0402-0201R633810K<Part Number>5%R0402-0201NI R6358 33 1%
C40070.1UF16VX7R10%C0402-0201NI
R1548 0 R0402-02015%R6359 33 1%U123PCA9617ADP<Part Number>EN5VCCA1VCCB8SCLA2SDAA3SDAB6SCLB7GND4
R6320 0 R0402-0201 5%NIR6349 4.7K 5% R0402-0201R6344 4.7K 5% R0402-0201R6326 33 R0402-0201 1%NI
R1549 33 R0402-02015%PWRGD_P1V8_PEX_R1
SMB_PEX_MUX_SDASMB_PEX_MUX_SCLSMB_PEX0_MUX_SDASMB_PEX0_MUX_SCLSMB_PEX1_MUX_SDASMB_PEX1_MUX_SCLSMB_PEX2_MUX_SDASMB_PEX2_MUX_SCLSMB_PEX3_MUX_SDASMB_PEX3_MUX_SCL
SMB_PEX0_MUX_SDASMB_PEX0_MUX_SCLSMB_PEX1_MUX_SDASMB_PEX1_MUX_SCLSMB_PEX2_MUX_SDASMB_PEX2_MUX_SCLSMB_PEX3_MUX_SDASMB_PEX3_MUX_SCLSMB_PEX_LS_R_SCLSMB_PEX_LS_R_SDA



5
5
4
4
3
3
2
2
1
1
D D
C C
B B
A A
SMBUS ADDRESS: 0x70(7bit), 0XE0(8bit)
SMBUS ADDRESS: 0x71(7bit), 0XE2(8bit)
BIC_SSD_I2C_MUX
DVT_CHANGE
SMB_BIC_I2C9_MUX0_SSD0_R_SDA [96,97]SMB_BIC_I2C9_MUX0_SSD0_R_SCL [96,97]SMB_BIC_I2C9_MUX0_SSD1_R_SDA [96,97]SMB_BIC_I2C9_MUX0_SSD1_R_SCL [96,97]BIC_I2C9_SSD_MUX0_A0 [96]SMB_BIC_I2C9_MUX0_SSD2_R_SDA [96,97]BIC_I2C9_SSD_MUX0_A1 [96]SMB_BIC_I2C9_MUX0_SSD2_R_SCL [96,97]BIC_I2C9_SSD_MUX0_A2 [96]SMB_BIC_I2C9_MUX0_SSD3_R_SDA [96,97]SMB_BIC_I2C9_MUX0_SSD3_R_SCL [96,97]SMB_BIC_I2C9_MUX0_SSD4_R_SDA [96,97]SMB_BIC_I2C9_MUX0_SSD4_R_SCL [96,97]SMB_BIC_I2C9_MUX0_SSD5_R_SDA [96,97]SMB_BIC_I2C9_MUX0_SSD5_R_SCL [96,97]BIC_I2C9_SSD_MUX0_A0[96]BIC_I2C9_SSD_MUX0_A1[96]BIC_I2C9_SSD_MUX0_A2[96]RST_BIC_I2C9_SSD_MUX0_R_N[87]SMB_BIC_I2C9_MUX0_SSD0_R_SDA[96,97]SMB_BIC_I2C9_MUX0_SSD0_R_SCL[96,97]SMB_BIC_I2C9_MUX0_SSD1_R_SDA[96,97]SMB_BIC_I2C9_MUX0_SSD1_R_SCL[96,97]SMB_BIC_I2C9_MUX0_SSD2_R_SDA[96,97]SMB_BIC_I2C9_MUX0_SSD2_R_SCL[96,97]SMB_BIC_I2C9_MUX0_SSD3_R_SDA[96,97]SMB_BIC_I2C9_MUX0_SSD3_R_SCL[96,97]SMB_BIC_I2C9_MUX0_SSD4_R_SDA [96,97]SMB_BIC_I2C9_MUX0_SSD4_R_SCL [96,97]SMB_BIC_I2C9_MUX0_SSD5_R_SDA [96,97]SMB_BIC_I2C9_MUX0_SSD5_R_SCL [96,97]SMB_BIC_I2C9_MUX0_SSD6_R_SDA [96,97]SMB_BIC_I2C9_MUX0_SSD6_R_SCL [96,97]SMB_BIC_I2C9_MUX0_SSD7_R_SDA [96,97]SMB_BIC_I2C9_MUX0_SSD7_R_SCL [96,97]SMB_BIC_I2C9_MUX0_SSD6_R_SDA [96,97]SMB_BIC_I2C9_MUX0_SSD6_R_SCL [96,97]SMB_BIC_I2C9_MUX0_SSD7_R_SDA [96,97]SMB_BIC_I2C9_MUX0_SSD7_R_SCL [96,97]SMB_BIC_I2C9_MUX1_SSD8_R_SDA [96,98]SMB_BIC_I2C9_MUX1_SSD8_R_SCL [96,98]SMB_BIC_I2C9_MUX1_SSD9_R_SDA [96,98]SMB_BIC_I2C9_MUX1_SSD9_R_SCL [96,98]SMB_BIC_I2C9_MUX1_SSD10_R_SDA [96,98]SMB_BIC_I2C9_MUX1_SSD10_R_SCL [96,98]SMB_BIC_I2C9_MUX1_SSD11_R_SDA [96,98]SMB_BIC_I2C9_MUX1_SSD11_R_SCL [96,98]SMB_BIC_I2C9_MUX1_SSD12_R_SDA [96,98]BIC_I2C9_SSD_MUX1_A0 [96]SMB_BIC_I2C9_MUX1_SSD12_R_SCL [96,98]BIC_I2C9_SSD_MUX1_A1 [96]SMB_BIC_I2C9_MUX1_SSD13_R_SDA [96,98]BIC_I2C9_SSD_MUX1_A2 [96]SMB_BIC_I2C9_MUX1_SSD13_R_SCL [96,98]SMB_BIC_I2C9_MUX1_SSD14_R_SDA [96,98]SMB_BIC_I2C9_MUX1_SSD14_R_SCL [96,98]SMB_BIC_I2C9_MUX1_SSD15_R_SDA [96,98]SMB_BIC_I2C9_MUX1_SSD15_R_SCL [96,98]BIC_I2C9_SSD_MUX1_A0[96]BIC_I2C9_SSD_MUX1_A1[96]BIC_I2C9_SSD_MUX1_A2[96]RST_BIC_I2C9_SSD_MUX1_R_N[87]SMB_BIC_I2C9_MUX1_SSD8_R_SDA[96,98]SMB_BIC_I2C9_MUX1_SSD12_R_SDA [96,98]SMB_BIC_I2C9_MUX1_SSD8_R_SCL[96,98]SMB_BIC_I2C9_MUX1_SSD12_R_SCL [96,98]SMB_BIC_I2C9_MUX1_SSD9_R_SDA[96,98]SMB_BIC_I2C9_MUX1_SSD13_R_SDA [96,98]SMB_BIC_I2C9_MUX1_SSD9_R_SCL[96,98]SMB_BIC_I2C9_MUX1_SSD13_R_SCL [96,98]SMB_BIC_I2C9_MUX1_SSD10_R_SDA[96,98]SMB_BIC_I2C9_MUX1_SSD14_R_SDA [96,98]SMB_BIC_I2C9_MUX1_SSD10_R_SCL[96,98]SMB_BIC_I2C9_MUX1_SSD14_R_SCL [96,98]SMB_BIC_I2C9_MUX1_SSD11_R_SDA[96,98]SMB_BIC_I2C9_MUX1_SSD15_R_SDA [96,98]SMB_BIC_I2C9_MUX1_SSD11_R_SCL[96,98]SMB_BIC_I2C9_MUX1_SSD15_R_SCL [96,98]SMB_BIC_I2C9_SSD_MUX_R_SDA [87,96]SMB_BIC_I2C9_SSD_MUX_R_SCL [87,96]SMB_BIC_I2C9_SSD_MUX_R_SDA [87,96]SMB_BIC_I2C9_SSD_MUX_R_SCL [87,96]P3V3_AUXP3V3_AUXP3V3_AUXP3V3_AUXP3V3_AUXP3V3_AUXSizeDoc NumberRevDate: SheetofReviewerDesignerDepartmentProject
Page TitleCCBU D96 257Tuesday, August 29, 2023<project_name><Designer> GRANDTETON_SWB_20230829096 BIC_SSD_I2C_MUX<Reviewer>SizeDoc NumberRevDate: SheetofReviewerDesignerDepartmentProject
Page TitleCCBU D96 257Tuesday, August 29, 2023<project_name><Designer> GRANDTETON_SWB_20230829096 BIC_SSD_I2C_MUX<Reviewer>SizeDoc NumberRevDate: SheetofReviewerDesignerDepartmentProject
Page TitleCCBU D96 257Tuesday, August 29, 2023<project_name><Designer> GRANDTETON_SWB_20230829096 BIC_SSD_I2C_MUX<Reviewer>R1600 4.7K 5% R0402-0201R1604 4.7K 5% R0402-0201R1617 0 5%R0402-0201R1628 0 R0402-02015%
R1554 4.7K 5% R0402-0201R1579 0 5%R0402-0201R1610 4.7K 5% R0402-0201U124TCA9548APWRA01A12RESET#3SD04SC05SD16SC17SD28SC29SD310SC311GND12VCC24SDA23SCL22A221SC720SD719SC618SD617SC516SD515SC414SD413R1551 4.7K 5% R0402-0201
R1623 0 5%R0402-0201
R1561 4.7K 5% R0402-0201R159710K<Part Number>5%R0402-0201R1618 0 R0402-02015%
R1570 4.7K 5% R0402-0201R1601 4.7K 5% R0402-0201U125TCA9548APWRA01A12RESET#3SD04SC05SD16SC17SD28SC29SD310SC311GND12VCC24SDA23SCL22A221SC720SD719SC618SD617SC516SD515SC414SD413R1581 0 5%R0402-0201R1564 4.7K 5% R0402-0201R1576 0 R0402-02015%R1595 4.7K 5% R0402-0201R1583 0 5%R0402-0201
R1629 0 5%R0402-0201R1591 4.7K 5% R0402-0201R1605 4.7K 5% R0402-0201R1624 0 R0402-02015%
R1552 4.7K 5% R0402-0201
R1611 4.7K 5% R0402-0201
R156610K<Part Number>5%R0402-0201R1555 4.7K 5% R0402-0201R1584 0 R0402-02015%R1619 0 5%R0402-0201
R1571 4.7K 5% R0402-0201R1585 0 5%R0402-0201
R1630 0 R0402-02015%
R1565 4.7K 5% R0402-0201R155710K<Part Number>5%R0402-0201NI R1596 4.7K 5% R0402-0201R1577 0 5%R0402-0201R156710K<Part Number>5%R0402-0201R1602 4.7K 5% R0402-0201R1592 4.7K 5% R0402-0201R1586 0 R0402-02015%R1578 0 R0402-02015%R1606 4.7K 5% R0402-0201R1625 0 5%R0402-0201R1620 0 R0402-02015%
R1573 0 R0402-02015%R156810K<Part Number>5%R0402-0201R1588 0 R0402-02015%R155810K<Part Number>5%R0402-0201NI
R1613 0 R0402-02015%R1575 0 5%R0402-0201R1572 4.7K 5% R0402-0201R1612 4.7K 5% R0402-0201R1587 0 5%R0402-0201R160710K<Part Number>5%R0402-0201NI
R1556 4.7K 5% R0402-0201C27090.1UF16VX7R10%C0402-0201R1590 0 R0402-02015%R1614 33 R0402-02011%R1626 0 R0402-02015%
R155910K<Part Number>5%R0402-0201NIR1593 4.7K 5% R0402-0201R1562 4.7K 5% R0402-0201
R1615 0 5%R0402-0201
R1574 33 R0402-02011%R160810K<Part Number>5%R0402-0201R1603 4.7K 5% R0402-0201R1621 0 5%R0402-0201R159810K<Part Number>5%R0402-0201NI R1580 0 R0402-02015%R1589 0 5%R0402-0201R1616 0 R0402-02015%C27100.1UF16VX7R10%C0402-0201R160910K<Part Number>5%R0402-0201
R1553 4.7K 5% R0402-0201R1582 0 R0402-02015%R159910K<Part Number>5%R0402-0201NIR1627 0 5%R0402-0201
R1560 4.7K 5% R0402-0201
R1622 0 R0402-02015%
R1563 4.7K 5% R0402-0201R1594 4.7K 5% R0402-0201R1569 4.7K 5% R0402-0201SMB_BIC_I2C9_MUX0_SSD0_SDASMB_BIC_I2C9_MUX0_SSD0_SCLSMB_BIC_I2C9_MUX0_SSD1_SDASMB_BIC_I2C9_MUX0_SSD1_SCLSMB_BIC_I2C9_MUX0_SSD2_SDASMB_BIC_I2C9_MUX0_SSD2_SCLSMB_BIC_I2C9_MUX0_SSD3_SDASMB_BIC_I2C9_MUX0_SSD3_SCLSMB_BIC_I2C9_MUX0_SSD4_SDASMB_BIC_I2C9_MUX0_SSD4_SCLSMB_BIC_I2C9_MUX0_SSD5_SDASMB_BIC_I2C9_MUX0_SSD5_SCLSMB_BIC_I2C9_MUX0_SSD6_SDASMB_BIC_I2C9_MUX0_SSD6_SCLSMB_BIC_I2C9_MUX0_SSD7_SDASMB_BIC_I2C9_MUX0_SSD7_SCLSMB_BIC_I2C9_MUX1_SSD8_SDASMB_BIC_I2C9_MUX1_SSD12_SDASMB_BIC_I2C9_MUX1_SSD8_SCLSMB_BIC_I2C9_MUX1_SSD12_SCLSMB_BIC_I2C9_MUX1_SSD9_SDASMB_BIC_I2C9_MUX1_SSD13_SDASMB_BIC_I2C9_MUX1_SSD9_SCLSMB_BIC_I2C9_MUX1_SSD13_SCLSMB_BIC_I2C9_MUX1_SSD10_SDASMB_BIC_I2C9_MUX1_SSD14_SDASMB_BIC_I2C9_MUX1_SSD10_SCLSMB_BIC_I2C9_MUX1_SSD14_SCLSMB_BIC_I2C9_MUX1_SSD11_SDASMB_BIC_I2C9_MUX1_SSD15_SDASMB_BIC_I2C9_MUX1_SSD11_SCLSMB_BIC_I2C9_MUX1_SSD15_SCLSMB_BIC_I2C9_SSD_MUX1_SDASMB_BIC_I2C9_SSD_MUX1_SCLSMB_BIC_I2C9_SSD_MUX0_SDASMB_BIC_I2C9_SSD_MUX0_SCL



5
5
4
4
3
3
2
2
1
1
D D
C C
B B
A A
INTERNAL PUBY VCCB
RESERVED BY-PASS
RESERVED BY-PASS
INTERNAL PUBY VCCB
RESERVED BY-PASS
RESERVED BY-PASS
INTERNAL PUBY VCCB
INTERNAL PUBY VCCB
RESERVED BY-PASS
RESERVED BY-PASS
INTERNAL PUBY VCCB
INTERNAL PUBY VCCB
INTERNAL PUBY VCCB
RESERVED BY-PASS
INTERNAL PUBY VCCB
RESERVED BY-PASS
BIC_MUX_ISO_SSD(1/2)
PVT2_BOM_CHANGEPVT2_BOM_CHANGEPVT2_BOM_CHANGEPVT2_BOM_CHANGEPVT2_BOM_CHANGEPVT2_BOM_CHANGEPVT2_BOM_CHANGEPVT2_BOM_CHANGE
SMB_BIC_I2C9_MUX0_SSD0_R_SCL[96]SMB_BIC_I2C9_MUX0_SSD0_R_SDA[96]SMB_BIC_I2C9_MUX0_SSD1_R_SCL[96]SMB_BIC_I2C9_MUX0_SSD1_R_SDA[96]SMB_BIC_I2C9_MUX0_SSD2_R_SCL[96]SMB_BIC_I2C9_MUX0_SSD3_R_SCL[96]SMB_BIC_I2C9_MUX0_SSD2_R_SDA[96]SMB_BIC_I2C9_MUX0_SSD3_R_SDA[96]SMB_BIC_I2C9_MUX0_SSD4_R_SCL[96]SMB_BIC_I2C9_MUX0_SSD5_R_SCL[96]SMB_BIC_I2C9_MUX0_SSD4_R_SDA[96]SMB_BIC_I2C9_MUX0_SSD5_R_SDA[96]SMB_BIC_I2C9_MUX0_SSD6_R_SCL[96]SMB_BIC_I2C9_MUX0_SSD7_R_SCL[96]SMB_BIC_I2C9_MUX0_SSD6_R_SDA[96]SMB_BIC_I2C9_MUX0_SSD7_R_SDA[96]
SMB_ISO_SSD0_R_SCL [194]SMB_ISO_SSD0_R_SDA [194]SMB_ISO_SSD2_R_SCL [195]SMB_ISO_SSD2_R_SDA [195]SMB_ISO_SSD4_R_SCL [196]SMB_ISO_SSD4_R_SDA [196]SMB_ISO_SSD6_R_SCL [197]SMB_ISO_SSD6_R_SDA [197]
SMB_ISO_SSD1_R_SCL [194]SMB_ISO_SSD1_R_SDA [194]SMB_ISO_SSD3_R_SCL [195]SMB_ISO_SSD3_R_SDA [195]SMB_ISO_SSD5_R_SCL [196]SMB_ISO_SSD5_R_SDA [196]SMB_ISO_SSD7_R_SCL [197]SMB_ISO_SSD7_R_SDA [197]
P3V3_AUXP3V3_SSD0P3V3_SSD1P3V3_AUXP3V3_SSD2P3V3_SSD3P3V3_AUXP3V3_AUXP3V3_SSD4P3V3_SSD5P3V3_AUXP3V3_AUXP3V3_SSD6P3V3_SSD7P3V3_AUXP3V3_AUXSizeDoc NumberRevDate: SheetofReviewerDesignerDepartmentProject
Page TitleCCBU D97 257Tuesday, August 29, 2023<project_name><Designer> GRANDTETON_SWB_20230829097 BIC_MUX_ISO_SSD(1/2)<Reviewer>SizeDoc NumberRevDate: SheetofReviewerDesignerDepartmentProject
Page TitleCCBU D97 257Tuesday, August 29, 2023<project_name><Designer> GRANDTETON_SWB_20230829097 BIC_MUX_ISO_SSD(1/2)<Reviewer>SizeDoc NumberRevDate: SheetofReviewerDesignerDepartmentProject
Page TitleCCBU D97 257Tuesday, August 29, 2023<project_name><Designer> GRANDTETON_SWB_20230829097 BIC_MUX_ISO_SSD(1/2)<Reviewer>
C27140.1UF10%16VC0402-0201
R16644.7KR0402-02015%
U127PCA9617ADPEN5VCCA1VCCB8SCLA2SDAA3SDAB6SCLB7GND4C27200.1UF10%16VC0402-0201R1653 33 1%R16364.7KR0402-02015%
C27260.1UF10%16VC0402-0201
R1643 0 R0402-02015%NIR16464.7K5%R16334.7KR0402-02015%
C27210.1UF10%16VC0402-0201C27160.1UF10%16VC0402-0201R16324.7K5%
R16624.7KR0402-02015% NIR16474.7KR0402-02015%R16484.7KR0402-02015% NIR1654 33 1%
R1684 0 R0402-02015%NIR1671 0 R0402-02015%NIR1685 0 R0402-02015%NIR16604.7K5%
C27120.1UF10%16VC0402-0201
R1670 0 R0402-02015%NIU132PCA9617ADPEN5VCCA1VCCB8SCLA2SDAA3SDAB6SCLB7GND4R1665 33 1%C27230.1UF10%16VC0402-0201R16744.7K5%R1683 0 R0402-02015%NIR16614.7KR0402-02015%C27150.1UF10%16VC0402-0201R1666 33 1%
U126PCA9617ADPEN5VCCA1VCCB8SCLA2SDAA3SDAB6SCLB7GND4 C27170.1UF10%16VC0402-0201R16754.7KR0402-02015%
R1644 0 R0402-02015%NIU128PCA9617ADPEN5VCCA1VCCB8SCLA2SDAA3SDAB6SCLB7GND4 R16764.7KR0402-02015% NIR1679 33 1%
C27180.1UF10%16VC0402-0201R1669 0 R0402-02015%NI
R16344.7KR0402-02015% NI
R16774.7K5%R1658 0 R0402-02015%NIR1667 33 1%R1680 33 1%
R16454.7KR0402-02015% NIU131PCA9617ADPEN5VCCA1VCCB8SCLA2SDAA3SDAB6SCLB7GND4R16594.7KR0402-02015% NIR1655 0 R0402-02015%NI R16784.7KR0402-02015%R1668 33 1%R1641 0 R0402-02015%NI R1638 33 1%C27110.1UF10%16VC0402-0201
R1672 0 R0402-02015%NI
R1637 33 1%
U133PCA9617ADPEN5VCCA1VCCB8SCLA2SDAA3SDAB6SCLB7GND4
R16314.7KR0402-02015% NI
C27190.1UF10%16VC0402-0201R1681 33 1%C27220.1UF10%16VC0402-0201R1657 0 R0402-02015%NIR1639 33 1%
R1686 0 R0402-02015%NIR16734.7KR0402-02015% NIR1682 33 1%
R1651 33 1%R1656 0 R0402-02015%NIR16494.7K5%C27240.1UF10%16VC0402-0201R16634.7K5%R1640 33 1%C27130.1UF10%16VC0402-0201U129PCA9617ADPEN5VCCA1VCCB8SCLA2SDAA3SDAB6SCLB7GND4R1652 33 1%R1642 0 R0402-02015%NIR16504.7KR0402-02015%
C27250.1UF10%16VC0402-0201
R16354.7K5%
U130PCA9617ADPEN5VCCA1VCCB8SCLA2SDAA3SDAB6SCLB7GND4
SMB_SSD0_ISO_ENSMB_SSD1_ISO_ENSMB_SSD2_ISO_ENSMB_SSD3_ISO_ENSMB_SSD4_ISO_ENSMB_SSD5_ISO_ENSMB_SSD6_ISO_ENSMB_SSD7_ISO_EN
SMB_ISO_SSD0_SDASMB_ISO_SSD0_SCLSMB_ISO_SSD3_SDASMB_ISO_SSD5_SDASMB_ISO_SSD7_SDA
SMB_ISO_SSD2_SDASMB_ISO_SSD4_SDASMB_ISO_SSD6_SDA
SMB_ISO_SSD1_SDASMB_ISO_SSD1_SCLSMB_ISO_SSD2_SCLSMB_ISO_SSD3_SCLSMB_ISO_SSD4_SCLSMB_ISO_SSD5_SCLSMB_ISO_SSD7_SCLSMB_ISO_SSD6_SCL



5
5
4
4
3
3
2
2
1
1
D D
C C
B B
A A
INTERNAL PUBY VCCB
RESERVED BY-PASS
RESERVED BY-PASS
INTERNAL PUBY VCCB
RESERVED BY-PASS
RESERVED BY-PASS
INTERNAL PUBY VCCB
INTERNAL PUBY VCCB
RESERVED BY-PASS
RESERVED BY-PASS
INTERNAL PUBY VCCB
INTERNAL PUBY VCCB
INTERNAL PUBY VCCB
RESERVED BY-PASS
INTERNAL PUBY VCCB
RESERVED BY-PASS
BIC_MUX_ISO_SSD(2/2)
PVT2_BOM_CHANGEPVT2_BOM_CHANGEPVT2_BOM_CHANGEPVT2_BOM_CHANGEPVT2_BOM_CHANGEPVT2_BOM_CHANGEPVT2_BOM_CHANGEPVT2_BOM_CHANGE
SMB_BIC_I2C9_MUX1_SSD8_R_SCL[96]SMB_BIC_I2C9_MUX1_SSD8_R_SDA[96]SMB_BIC_I2C9_MUX1_SSD9_R_SCL[96]SMB_BIC_I2C9_MUX1_SSD9_R_SDA[96]SMB_BIC_I2C9_MUX1_SSD10_R_SCL[96]SMB_BIC_I2C9_MUX1_SSD11_R_SCL[96]SMB_BIC_I2C9_MUX1_SSD10_R_SDA[96]SMB_BIC_I2C9_MUX1_SSD11_R_SDA[96]SMB_BIC_I2C9_MUX1_SSD12_R_SCL[96]SMB_BIC_I2C9_MUX1_SSD13_R_SCL[96]SMB_BIC_I2C9_MUX1_SSD12_R_SDA[96]SMB_BIC_I2C9_MUX1_SSD13_R_SDA[96]SMB_BIC_I2C9_MUX1_SSD14_R_SCL[96]SMB_BIC_I2C9_MUX1_SSD15_R_SCL[96]SMB_BIC_I2C9_MUX1_SSD14_R_SDA[96]SMB_BIC_I2C9_MUX1_SSD15_R_SDA[96]
SMB_ISO_SSD8_R_SCL [198]SMB_ISO_SSD8_R_SDA [198]SMB_ISO_SSD10_R_SCL [199]SMB_ISO_SSD10_R_SDA [199]SMB_ISO_SSD12_R_SCL [200]SMB_ISO_SSD12_R_SDA [200]SMB_ISO_SSD14_R_SCL [201]SMB_ISO_SSD14_R_SDA [201]SMB_ISO_SSD15_R_SCL [201]SMB_ISO_SSD15_R_SDA [201]SMB_ISO_SSD13_R_SCL [200]SMB_ISO_SSD13_R_SDA [200]SMB_ISO_SSD11_R_SCL [199]SMB_ISO_SSD11_R_SDA [199]SMB_ISO_SSD9_R_SCL [198]SMB_ISO_SSD9_R_SDA [198]P3V3_AUXP3V3_SSD8P3V3_SSD9P3V3_AUXP3V3_SSD10P3V3_SSD11P3V3_AUXP3V3_AUXP3V3_SSD12P3V3_SSD13P3V3_AUXP3V3_AUXP3V3_SSD14P3V3_SSD15P3V3_AUXP3V3_AUXSizeDoc NumberRevDate: SheetofReviewerDesignerDepartmentProject
Page TitleCCBU D98 257Tuesday, August 29, 2023<project_name><Designer> GRANDTETON_SWB_20230829098 BIC_MUX_ISO_SSD(2/2)<Reviewer>SizeDoc NumberRevDate: SheetofReviewerDesignerDepartmentProject
Page TitleCCBU D98 257Tuesday, August 29, 2023<project_name><Designer> GRANDTETON_SWB_20230829098 BIC_MUX_ISO_SSD(2/2)<Reviewer>SizeDoc NumberRevDate: SheetofReviewerDesignerDepartmentProject
Page TitleCCBU D98 257Tuesday, August 29, 2023<project_name><Designer> GRANDTETON_SWB_20230829098 BIC_MUX_ISO_SSD(2/2)<Reviewer>
R17014.7KR0402-02015% NIR17194.7K5%R1712 0 R0402-02015%NIR16894.7KR0402-02015%
U141PCA9617ADPEN5VCCA1VCCB8SCLA2SDAA3SDAB6SCLB7GND4R1726 0 R0402-02015%NIR1709 33 1%
R1741 0 R0402-02015%NI
U136PCA9617ADPEN5VCCA1VCCB8SCLA2SDAA3SDAB6SCLB7GND4 R1698 0 R0402-02015%NIR17204.7KR0402-02015%R1728 0 R0402-02015%NIC27410.1UF10%16VC0402-0201R17324.7KR0402-02015% NI
C27330.1UF10%16VC0402-0201R1710 33 1%R1713 0 R0402-02015%NIR17154.7KR0402-02015% NIU138PCA9617ADPEN5VCCA1VCCB8SCLA2SDAA3SDAB6SCLB7GND4C27310.1UF10%16VC0402-0201U139PCA9617ADPEN5VCCA1VCCB8SCLA2SDAA3SDAB6SCLB7GND4R17164.7K5%R1697 0 R0402-02015%NI R1708 33 1%C27400.1UF10%16VC0402-0201
R17024.7K5%R16904.7KR0402-02015% NI
R17334.7K5%R17174.7KR0402-02015%
C27280.1UF10%16VC0402-0201C27320.1UF10%16VC0402-0201
R17294.7KR0402-02015% NI
U134PCA9617ADPEN5VCCA1VCCB8SCLA2SDAA3SDAB6SCLB7GND4R17034.7KR0402-02015%C27360.1UF10%16VC0402-0201R1721 33 1%R17054.7K5%R16914.7K5%
R17344.7KR0402-02015%
C27290.1UF10%16VC0402-0201R17044.7KR0402-02015% NIU137PCA9617ADPEN5VCCA1VCCB8SCLA2SDAA3SDAB6SCLB7GND4R17184.7KR0402-02015% NIR17064.7KR0402-02015%R16924.7KR0402-02015%
R1722 33 1%R1723 33 1%R1707 33 1%R1711 0 R0402-02015%NI C27300.1UF10%16VC0402-0201
R1742 0 R0402-02015%NIC27380.1UF10%16VC0402-0201C27390.1UF10%16VC0402-0201R1740 0 R0402-02015%NIR1724 33 1%R1735 33 1%R17304.7K5%R1739 0 R0402-02015%NIC27370.1UF10%16VC0402-0201
R16874.7KR0402-02015% NIR1695 33 1%
R1737 33 1%
C27340.1UF10%16VC0402-0201U140PCA9617ADPEN5VCCA1VCCB8SCLA2SDAA3SDAB6SCLB7GND4R17314.7KR0402-02015%
U135PCA9617ADPEN5VCCA1VCCB8SCLA2SDAA3SDAB6SCLB7GND4R1693 33 1%R1699 0 R0402-02015%NI
R1738 33 1%R1725 0 R0402-02015%NI R1736 33 1%
R1694 33 1%R1700 0 R0402-02015%NI
C27420.1UF10%16VC0402-0201
R1696 33 1%C27350.1UF10%16VC0402-0201R1714 0 R0402-02015%NIR16884.7K5%
R1727 0 R0402-02015%NI
C27270.1UF10%16VC0402-0201SMB_SSD8_ISO_ENSMB_SSD9_ISO_ENSMB_SSD10_ISO_ENSMB_SSD11_ISO_ENSMB_SSD12_ISO_ENSMB_SSD13_ISO_ENSMB_SSD14_ISO_ENSMB_SSD15_ISO_ENSMB_ISO_SSD14_SDA
SMB_ISO_SSD8_SDASMB_ISO_SSD10_SDASMB_ISO_SSD12_SDA
SMB_ISO_SSD9_SDASMB_ISO_SSD11_SDA
SMB_ISO_SSD15_SDASMB_ISO_SSD13_SDA
SMB_ISO_SSD8_SCLSMB_ISO_SSD9_SCLSMB_ISO_SSD11_SCLSMB_ISO_SSD10_SCLSMB_ISO_SSD13_SCLSMB_ISO_SSD12_SCLSMB_ISO_SSD15_SCLSMB_ISO_SSD14_SCL



5
5
4
4
3
3
2
2
1
1
D D
C C
B B
A A
SMBUS ADDRESS: 0x70(7bit), 0XE0(8bit)
INTERNAL PUBY VCCB
RESERVED BY-PASS
BIC_SENSOR_I2C_MUX
DVT_CHANGEDVT_CHANGE
DVT_CHANGEPVT2_BOM_CHANGEPVT2_BOM_CHANGE
SMB_BIC_I2C6_MUX_NIC_ADC_R_SDA [99,110,111]SMB_BIC_I2C6_MUX_NIC_ADC_R_SCL [99,110,111]SMB_BIC_I2C6_MUX_PEX_ADC_R_SDA [99,112,113,213]SMB_BIC_I2C6_MUX_PEX_ADC_R_SCL [99,112,113,213]BIC_I2C6_MUX_A0 [99]SMB_BIC_I2C6_MUX_THERMAL_R_SDA [99,104,105]BIC_I2C6_MUX_A1 [99]SMB_BIC_I2C6_MUX_THERMAL_R_SCL [99]BIC_I2C6_MUX_A2 [99]SMB_BIC_I2C6_MUX_SSD_0_7_ADC_R_SDA [99,106,107]SMB_BIC_I2C6_MUX_SSD_0_7_ADC_R_SCL [99,106,107]SMB_BIC_I2C6_MUX_SSD_8_15_ADC_R_SDA [99,108,109]SMB_BIC_I2C6_MUX_SSD_8_15_ADC_R_SCL [99,108,109]SMB_BIC_I2C6_MUX_CLK_R_SDA [99]SMB_BIC_I2C6_MUX_CLK_R_SCL [99]BIC_I2C6_MUX_A0[99]BIC_I2C6_MUX_A1[99]BIC_I2C6_MUX_A2[99]RST_BIC_I2C6_MUX_R_N[87]SMB_BIC_I2C6_MUX_NIC_ADC_R_SDA[99,110,111]SMB_BIC_I2C6_MUX_NIC_ADC_R_SCL[99,110,111]SMB_BIC_I2C6_MUX_PEX_ADC_R_SDA[99,112,113,213]SMB_BIC_I2C6_MUX_PEX_ADC_R_SCL[99,112,113,213]SMB_BIC_I2C6_MUX_SSD_8_15_ADC_R_SDA [99,108,109]SMB_BIC_I2C6_MUX_SSD_8_15_ADC_R_SCL [99,108,109]SMB_BIC_I2C6_MUX_CLK_R_SDA [99]SMB_BIC_I2C6_MUX_CLK_R_SCL [99]SMB_BIC_I2C6_MUX_VR_R_SDA [99,213,214,223,226]SMB_BIC_I2C6_MUX_VR_R_SCL [99,213,214,223,226]SMB_BIC_I2C6_MUX_FRU_R_SDA [81,99,104]SMB_BIC_I2C6_MUX_FRU_R_SCL [81,99,104]SMB_BIC_I2C6_MUX_VR_R_SDA [99,213,214,223,226]SMB_BIC_I2C6_MUX_VR_R_SCL [99,213,214,223,226]SMB_BIC_I2C6_MUX_FRU_R_SDA [81,99,104]SMB_BIC_I2C6_MUX_FRU_R_SCL [81,99,104]SMB_BIC_I2C6_MUX_THERMAL_R_SDA[99,104,105]SMB_BIC_I2C6_MUX_THERMAL_R_SCL[99]SMB_BIC_I2C6_MUX_SSD_0_7_ADC_R_SDA[99,106,107]SMB_BIC_I2C6_MUX_SSD_0_7_ADC_R_SCL[99,106,107]SMB_BIC_I2C6_R_SDA [87,90]SMB_BIC_I2C6_R_SCL [87,90]SMB_BIC_I2C6_MUX_CLK_R_SCL[99]SMB_BIC_I2C6_MUX_CLK_R_SDA[99]SMB_CLK_ISO_R_SDA [78,79,80,82,83]SMB_CLK_ISO_R_SCL [79,80,82,83]SMB_CLK_ISO_R_SCL_R1 [78]
SMB_BIC_I2C6_MUX_THERMAL_R1_SCL[105]SMB_BIC_I2C6_MUX_THERMAL_R_SCL [99]SMB_BIC_I2C6_MUX_THERMAL_R2_SCL[104]SMB_BIC_I2C6_MUX_THERMAL_R_SCL [99]P3V3_AUXP3V3_AUXP3V3_AUXP3V3P3V3_AUXSizeDoc NumberRevDate: SheetofReviewerDesignerDepartmentProject
Page TitleCCBU D99 257Tuesday, August 29, 2023<project_name><Designer> GRANDTETON_SWB_20230829099 BIC_SENSOR_I2C_MUX<Reviewer>SizeDoc NumberRevDate: SheetofReviewerDesignerDepartmentProject
Page TitleCCBU D99 257Tuesday, August 29, 2023<project_name><Designer> GRANDTETON_SWB_20230829099 BIC_SENSOR_I2C_MUX<Reviewer>SizeDoc NumberRevDate: SheetofReviewerDesignerDepartmentProject
Page TitleCCBU D99 257Tuesday, August 29, 2023<project_name><Designer> GRANDTETON_SWB_20230829099 BIC_SENSOR_I2C_MUX<Reviewer>
R17542.2K5%R0402-0201R175110K<Part Number>5%R0402-0201NIR175010K<Part Number>5%R0402-0201NIR1767 33 R0402-02011%R1776 33 R0402-02011%R6303 33 R0402-02011%
R6269 33 1%
R17552.2K5%R0402-0201
C39940.1UF10%16VC0402-0201R1772 0 R0402-02015%C39950.1UF10%16VC0402-0201U142TCA9548APWRA01A12RESET#3SD04SC05SD16SC17SD28SC29SD310SC311GND12VCC24SDA23SCL22A221SC720SD719SC618SD617SC516SD515SC414SD413R1763 4.7K 5% R0402-0201R1770 0 R0402-02015%R1775 33 R0402-02011%R1777 0 R0402-02015%R175910K<Part Number>5%R0402-0201
U421PCA9617ADPEN5VCCA1VCCB8SCLA2SDAA3SDAB6SCLB7GND4R6270 0 R0402-02015%NI
R17602.2K5%R0402-0201R1774 0 R0402-02015%R17522.2K5%R0402-0201R1771 33 R0402-02011%R1756 4.7K 5% R0402-0201R17622.2K5%R0402-0201
R6271 0 R0402-02015%NI
R17532.2K5%R0402-0201R6304 33 R0402-02011%R1778 0 R0402-02015%R1773 0 R0402-02015%R1779 33 R0402-02011%R6302 75 R0402-02011%R1780 33 R0402-02011%
R17452.2K5%R0402-0201
R6268 33 1%R1766 0 R0402-02015%R1764 4.7K 5% R0402-0201R17481.8K1%R0402-0201R17462.2K5%R0402-0201R4109 0 R0402-02015%R174910K<Part Number>5%R0402-0201NI R17431.8K1%R0402-0201
R62654.7KR0402-02015% NIR62662.2K5%R0402-0201
R17471.8K1%R0402-0201R4110 33 R0402-02011%R1757 4.7K 5% R0402-0201R1768 33 R0402-02011%R1769 0 R0402-02015%R176110K<Part Number>5%R0402-0201R17441.8K1%R0402-0201
R62672.2K5%R0402-0201C27430.1UF16VX7R10%C0402-0201R1765 0 R0402-02015%R175810K<Part Number>5%R0402-0201SMB_BIC_I2C6_MUX_NIC_ADC_SDASMB_BIC_I2C6_MUX_NIC_ADC_SCLSMB_BIC_I2C6_MUX_PEX_ADC_SDASMB_BIC_I2C6_MUX_PEX_ADC_SCLSMB_BIC_I2C6_MUX_THERMAL_SDASMB_BIC_I2C6_MUX_THERMAL_SCLSMB_BIC_I2C6_MUX_SSD_0_7_ADC_SDASMB_BIC_I2C6_MUX_SSD_0_7_ADC_SCLSMB_BIC_I2C6_MUX_SSD_8_15_ADC_SDASMB_BIC_I2C6_MUX_SSD_8_15_ADC_SCLSMB_BIC_I2C6_MUX_CLK_SDASMB_BIC_I2C6_MUX_CLK_SCLSMB_BIC_I2C6_MUX_VR_SDASMB_BIC_I2C6_MUX_VR_SCLSMB_BIC_I2C6_MUX_FRU_SDASMB_BIC_I2C6_MUX_FRU_SCLSMB_BIC_I2C6_SENEOR_SDASMB_BIC_I2C6_SENEOR_SCLSMB_CLK_ISO_SCLSMB_CLK_ISO_R_SCL_R1SMB_CLK_ISO_SDACLK_ISO_EN



5
5
4
4
3
3
2
2
1
1
D D
C C
B B
A A
Vi=1.35V
CAD Note:Place colse to BIC1030 pin
CAD Note:Place colse to BIC1030 pin
Vi=1.2VVi=1.35V
Vi=1.35V
CAD Note:Place colse to BIC1030 pin
CAD Note:Place colse to BIC1030 pin
ROUTE ALL ADC NETS AT 8 MILLS WIDE
BIC_ADC
CAD Note:Place colse to BIC1030 pin
Vi=1.35V
Vi=1.35V
CAD Note:Place colse to BIC1030 pin
CAD Note:Place colse to BIC1030 pin
Vi=1.35V
CAD Note:Place colse to BIC1030 pin
Vi=1.35V
CAD Note:Place colse to BIC1030 pin
Vi=1.35V
DVT_CHANGEP3V3_AUX_SCALED [86]P5V_AUX_SCALED [86]P3V3_SCALED [86]P1V2_AUX_SCALED [86]P12V_AUX_SCALED [86]P1V8_PLL0_PEX0_SCALED [86]P1V8_PLL0_PEX1_SCALED [86]P1V8_PLL0_PEX2_SCALED [86]P1V8_PLL0_PEX3_SCALED [86]P3V3_AUXP5V_AUXP3V3P1V2_AUXP12V_AUXP1V8_PLL0_PEX0P1V8_PLL0_PEX1P1V8_PLL0_PEX2P1V8_PLL0_PEX3
SizeDoc NumberRevDate: SheetofReviewerDesignerDepartmentProject
Page TitleCCBU D100 257Tuesday, August 29, 2023<project_name><Designer> GRANDTETON_SWB_20230829100 BIC_ADC<Reviewer>SizeDoc NumberRevDate: SheetofReviewerDesignerDepartmentProject
Page TitleCCBU D100 257Tuesday, August 29, 2023<project_name><Designer> GRANDTETON_SWB_20230829100 BIC_ADC<Reviewer>SizeDoc NumberRevDate: SheetofReviewerDesignerDepartmentProject
Page TitleCCBU D100 257Tuesday, August 29, 2023<project_name><Designer> GRANDTETON_SWB_20230829100 BIC_ADC<Reviewer>C44340.1UFC0402-0201R4735.36K1/16W1%R0402-0201<Part Number>C36090.1UFC0402-0201C1960.1UFC0402-0201R4772K1/16W1%<Part Number>R0402-0201R4762K1/16W1%<Part Number>R0402-0201R65953K1/16W1%<Part Number>R0402-0201R4792.87K1/16W1%R0402-0201<Part Number>R485015.8K<Part Number>R0402-02011%1/16WR4742.87K1/16W1%R0402-0201<Part Number>R65963K1/16W1%<Part Number>R0402-0201R4782K1/16W1%<Part Number>R0402-0201NIR65911K1/16W1%R0402-0201<Part Number>R48512K1/16W1%<Part Number>R0402-0201C44360.1UFC0402-0201R47510K1/16W1%R0402-0201<Part Number>C1950.1UFC0402-0201C44370.1UFC0402-0201R65891K1/16W1%R0402-0201<Part Number>C1940.1UFC0402-0201C1930.1UFC0402-0201R65923K1/16W1%<Part Number>R0402-0201R65931K1/16W1%R0402-0201<Part Number>R4802K1/16W1%<Part Number>R0402-0201C44350.1UFC0402-0201R65941K1/16W1%R0402-0201<Part Number>R65903K1/16W1%<Part Number>R0402-0201P3V3_AUX_SCALEDP5V_AUX_SCALEDP3V3_SCALEDP1V2_AUX_SCALEDP12V_AUX_SCALED



5
5
4
4
3
3
2
2
1
1
D D
C C
B B
A A
SSD_SMB_RST(1/2)
PWRGD_P3V3_SSD1_R[115,239,250]RST_SMB_SSD_R_N[87,101,102]RST_SMB_SSD1_ISO_R_N [194]PWRGD_P3V3_SSD0_R[115,239,250]RST_SMB_SSD_R_N[87,101,102]RST_SMB_SSD0_ISO_R_N [194]PWRGD_P3V3_SSD3_R[115,239,250]RST_SMB_SSD_R_N[87,101,102]RST_SMB_SSD3_ISO_R_N [195]PWRGD_P3V3_SSD2_R[115,239,250]RST_SMB_SSD_R_N[87,101,102]RST_SMB_SSD2_ISO_R_N [195]PWRGD_P3V3_SSD5_R[115,239,251]PWRGD_P3V3_SSD4_R[115,239,251]RST_SMB_SSD_R_N[87,101,102]RST_SMB_SSD5_ISO_R_N [196]RST_SMB_SSD_R_N[87,101,102]RST_SMB_SSD4_ISO_R_N [196]PWRGD_P3V3_SSD7_R[115,239,251]PWRGD_P3V3_SSD6_R[115,239,251]RST_SMB_SSD_R_N[87,101,102]RST_SMB_SSD7_ISO_R_N [197]RST_SMB_SSD_R_N[87,101,102]RST_SMB_SSD6_ISO_R_N [197]
P3V3_AUXP3V3_SSD1P3V3_AUXP3V3_SSD0P3V3_AUXP3V3_SSD3P3V3_AUXP3V3_SSD2P3V3_AUXP3V3_SSD5P3V3_AUXP3V3_SSD4P3V3_AUXP3V3_SSD7P3V3_AUXP3V3_SSD6SizeDoc NumberRevDate: SheetofReviewerDesignerDepartmentProject
Page TitleCCBU D101 257Tuesday, August 29, 2023<project_name><Designer> GRANDTETON_SWB_20230829101 SSD_SMB_RST(1/2)<Reviewer>SizeDoc NumberRevDate: SheetofReviewerDesignerDepartmentProject
Page TitleCCBU D101 257Tuesday, August 29, 2023<project_name><Designer> GRANDTETON_SWB_20230829101 SSD_SMB_RST(1/2)<Reviewer>SizeDoc NumberRevDate: SheetofReviewerDesignerDepartmentProject
Page TitleCCBU D101 257Tuesday, August 29, 2023<project_name><Designer> GRANDTETON_SWB_20230829101 SSD_SMB_RST(1/2)<Reviewer>
3 state outputU38474HC1G126GW<Part Number>24513R5663100K1%R0402-0201<Part Number>R5673 33 R0402-02011%R5668100K1%R0402-0201<Part Number>R565405% R0402-0201<Part Number>R5651100K1%R0402-0201<Part Number>C36640.1UFX6SC0402-020110%25V<Part Number>C36610.1UFX6SC0402-020110%25V<Part Number>
R5677 33 R0402-02011%R567405% R0402-0201<Part Number>R5657 33 R0402-02011%3 state outputU38674HC1G126GW<Part Number>24513R567805% R0402-0201<Part Number>
R56604.75KR0402-02011%NI3 state outputU38774HC1G126GW<Part Number>24513 R565805% R0402-0201<Part Number>C36660.1UFX6SC0402-020110%25V<Part Number>
R56484.75KR0402-02011%NI
C36680.1UFX6SC0402-020110%25V<Part Number>C36670.1UFX6SC0402-020110%25V<Part Number>R5669 33 R0402-02011%R5655100K1%R0402-0201<Part Number>3 state outputU38574HC1G126GW<Part Number>24513R5665 33 R0402-02011%C36620.1UFX6SC0402-020110%25V<Part Number>3 state outputU38274HC1G126GW<Part Number>24513
R567005% R0402-0201<Part Number>R56724.75KR0402-02011%NIR566605% R0402-0201<Part Number>R5661 33 R0402-02011%C36650.1UFX6SC0402-020110%25V<Part Number>R5649 33 R0402-02011%R5659100K1%R0402-0201<Part Number>
R5679100K1%R0402-0201<Part Number>
R56524.75KR0402-02011%NIC36630.1UFX6SC0402-020110%25V<Part Number>
R56754.75KR0402-02011%NIR566205% R0402-0201<Part Number>R565005% R0402-0201<Part Number>
R5676100K1%R0402-0201<Part Number>R56644.75KR0402-02011%NI3 state outputU38374HC1G126GW<Part Number>24513 R56564.75KR0402-02011%NI
3 state outputU38874HC1G126GW<Part Number>24513R56674.75KR0402-02011%NIR5671100K1%R0402-0201<Part Number>
R5653 33 R0402-02011%
3 state outputU38974HC1G126GW<Part Number>24513
RST_SMB_SSD1_NRST_SMB_SSD1_ISO_NRST_SMB_SSD0_NRST_SMB_SSD0_ISO_NRST_SMB_SSD3_NRST_SMB_SSD3_ISO_NRST_SMB_SSD2_NRST_SMB_SSD2_ISO_NRST_SMB_SSD5_NRST_SMB_SSD5_ISO_NRST_SMB_SSD4_NRST_SMB_SSD4_ISO_NRST_SMB_SSD7_NRST_SMB_SSD7_ISO_NRST_SMB_SSD6_NRST_SMB_SSD6_ISO_N



5
5
4
4
3
3
2
2
1
1
D D
C C
B B
A A
SSD_SMB_RST(2/2)
PWRGD_P3V3_SSD9_R[117,240,252]PWRGD_P3V3_SSD8_R[117,240,252]RST_SMB_SSD_R_N[87,101,102]RST_SMB_SSD9_ISO_R_N [198]RST_SMB_SSD_R_N[87,101,102]RST_SMB_SSD8_ISO_R_N [198]PWRGD_P3V3_SSD11_R[117,240,252]PWRGD_P3V3_SSD10_R[117,240,252]RST_SMB_SSD_R_N[87,101,102]RST_SMB_SSD11_ISO_R_N [199]RST_SMB_SSD_R_N[87,101,102]RST_SMB_SSD10_ISO_R_N [199]PWRGD_P3V3_SSD13_R[117,240,253]PWRGD_P3V3_SSD12_R[117,240,253]RST_SMB_SSD_R_N[87,101,102]RST_SMB_SSD13_ISO_R_N [200]RST_SMB_SSD_R_N[87,101,102]RST_SMB_SSD12_ISO_R_N [200]PWRGD_P3V3_SSD15_R[117,240,253]PWRGD_P3V3_SSD14_R[117,240,253]RST_SMB_SSD_R_N[87,101,102]RST_SMB_SSD15_ISO_R_N [201]RST_SMB_SSD_R_N[87,101,102]RST_SMB_SSD14_ISO_R_N [201]
P3V3_AUXP3V3_SSD9P3V3_AUXP3V3_SSD8P3V3_AUXP3V3_SSD11P3V3_AUXP3V3_SSD10P3V3_AUXP3V3_SSD13P3V3_AUXP3V3_SSD12P3V3_AUXP3V3_SSD15P3V3_AUXP3V3_SSD14SizeDoc NumberRevDate: SheetofReviewerDesignerDepartmentProject
Page TitleCCBU D102 257Tuesday, August 29, 2023<project_name><Designer> GRANDTETON_SWB_20230829102 SSD_SMB_RST(2/2)<Reviewer>SizeDoc NumberRevDate: SheetofReviewerDesignerDepartmentProject
Page TitleCCBU D102 257Tuesday, August 29, 2023<project_name><Designer> GRANDTETON_SWB_20230829102 SSD_SMB_RST(2/2)<Reviewer>SizeDoc NumberRevDate: SheetofReviewerDesignerDepartmentProject
Page TitleCCBU D102 257Tuesday, August 29, 2023<project_name><Designer> GRANDTETON_SWB_20230829102 SSD_SMB_RST(2/2)<Reviewer>3 state outputU39774HC1G126GW<Part Number>245133 state outputU39574HC1G126GW<Part Number>24513C36740.1UFX6SC0402-020110%25V<Part Number>C36750.1UFX6SC0402-020110%25V<Part Number>R5692100K1%R0402-0201<Part Number>R56804.75KR0402-02011%NI
R5709 33 R0402-02011%R5701 33 R0402-02011%3 state outputU39274HC1G126GW<Part Number>24513R56834.75KR0402-02011%NIR5687100K1%R0402-0201<Part Number>R5697 33 R0402-02011%R571005% R0402-0201<Part Number>R570205% R0402-0201<Part Number>R57044.75KR0402-02011%NIC36760.1UFX6SC0402-020110%25V<Part Number>3 state outputU39374HC1G126GW<Part Number>24513 R569805% R0402-0201<Part Number>C36730.1UFX6SC0402-020110%25V<Part Number>R5689 33 R0402-02011%R5684100K1%R0402-0201<Part Number>R5693 33 R0402-02011%R569005% R0402-0201<Part Number>3 state outputU39074HC1G126GW<Part Number>24513R569405% R0402-0201<Part Number>3 state outputU39174HC1G126GW<Part Number>24513C36700.1UFX6SC0402-020110%25V<Part Number>R56964.75KR0402-02011%NIC36720.1UFX6SC0402-020110%25V<Part Number>C36710.1UFX6SC0402-020110%25V<Part Number>
R5711100K1%R0402-0201<Part Number>3 state outputU39674HC1G126GW<Part Number>24513R56994.75KR0402-02011%NIR5703100K1%R0402-0201<Part Number>R57074.75KR0402-02011%NI
R5685 33 R0402-02011%R5681 33 R0402-02011%
R5708100K1%R0402-0201<Part Number>
R568605% R0402-0201<Part Number>
R5705 33 R0402-02011%R5700100K1%R0402-0201<Part Number>R56884.75KR0402-02011%NIR568205% R0402-0201<Part Number>C36690.1UFX6SC0402-020110%25V<Part Number>
R570605% R0402-0201<Part Number>R5695100K1%R0402-0201<Part Number>3 state outputU39474HC1G126GW<Part Number>24513R56914.75KR0402-02011%NIRST_SMB_SSD9_NRST_SMB_SSD9_ISO_NRST_SMB_SSD8_NRST_SMB_SSD8_ISO_NRST_SMB_SSD11_NRST_SMB_SSD11_ISO_NRST_SMB_SSD10_NRST_SMB_SSD10_ISO_NRST_SMB_SSD13_NRST_SMB_SSD13_ISO_NRST_SMB_SSD12_NRST_SMB_SSD12_ISO_NRST_SMB_SSD15_NRST_SMB_SSD15_ISO_NRST_SMB_SSD14_NRST_SMB_SSD14_ISO_N



5
5
4
4
3
3
2
2
1
1
D D
C C
B B
A A
BLANK SizeDoc NumberRevDate: SheetofReviewerDesignerDepartmentProject
Page TitleCCBU D103 257Tuesday, August 29, 2023<project_name><Designer> GRANDTETON_SWB_20230829103 BLANK<Reviewer>SizeDoc NumberRevDate: SheetofReviewerDesignerDepartmentProject
Page TitleCCBU D103 257Tuesday, August 29, 2023<project_name><Designer> GRANDTETON_SWB_20230829103 BLANK<Reviewer>SizeDoc NumberRevDate: SheetofReviewerDesignerDepartmentProject
Page TitleCCBU D103 257Tuesday, August 29, 2023<project_name><Designer> GRANDTETON_SWB_20230829103 BLANK<Reviewer>



5
5
4
4
3
3
2
2
1
1
D D
C C
B B
A A
BASEBOARD FRU (ADDRESS: 0XA8)
FRU_TEMP_SENSOR(1/2)
BASEBOARD THERMAL SENSOR (7-bit ADDRESS: 0X4A)(8-bit 0x94)
BASEBOARD THERMAL SENSOR (7-bit ADDRESS: 0X4E)(8-bit 0x9C)
SMB_BIC_I2C6_MUX_FRU_R_SCL[81,99]SMB_BIC_I2C6_MUX_FRU_R_SDA[81,99]SMB_BIC_I2C6_MUX_THERMAL_R_SDA[99,104,105]SMB_BIC_I2C6_MUX_THERMAL_R2_SCL[99,104]SMB_BIC_I2C6_MUX_THERMAL_R_SDA[99,104,105]SMB_BIC_I2C6_MUX_THERMAL_R2_SCL[99,104]
P3V3_AUXP3V3_AUXP3V3_AUXP3V3_AUXP3V3_AUXP3V3_AUXSizeDoc NumberRevDate: SheetofReviewerDesignerDepartmentProject
Page TitleCCBU D104 257Tuesday, August 29, 2023<project_name><Designer> GRANDTETON_SWB_20230829104 FRU_TEMP_SENSOR(1/2)<Reviewer>SizeDoc NumberRevDate: SheetofReviewerDesignerDepartmentProject
Page TitleCCBU D104 257Tuesday, August 29, 2023<project_name><Designer> GRANDTETON_SWB_20230829104 FRU_TEMP_SENSOR(1/2)<Reviewer>SizeDoc NumberRevDate: SheetofReviewerDesignerDepartmentProject
Page TitleCCBU D104 257Tuesday, August 29, 2023<project_name><Designer> GRANDTETON_SWB_20230829104 FRU_TEMP_SENSOR(1/2)<Reviewer>
R488 33 R0402-02015%
R58221KR0402-02011%NIR5818 0 R0402-02015%
R48610K1%R0402-0201
R58231KR0402-02011%NIR580510K1%R0402-0201NIR4911KR0402-02011%NIC1980.1UFC0402-020110%16VX7RR580610K1%R0402-0201C38710.1UFC0402-020110%16VX7R
R4901KR0402-02011%R580710K1%R0402-0201NIR5819 0 R0402-02015%
U7AT24C64D-SSHM-TVCC8WP7SCL6SDA5GND4A23A12A01R48510K1%R0402-0201NIR58111KR0402-02011%R48410K1%R0402-0201NIU416LM75BDSDA1SCL2OS3GND4A25A16A07VCC8R58121KR0402-02011%NIR581510K1%R0402-0201NIR5808 0 R0402-02015%R4891KR0402-02011%R58131KR0402-02011%R581610K1%R0402-0201R581710K1%R0402-0201C38700.1UFC0402-020110%16VX7RR5809 33 R0402-02011%R487 33 R0402-02015%
R58211KR0402-02011%U417LM75BDSDA1SCL2OS3GND4A25A16A07VCC8
BB_FRU_A0BB_FRU_A2BB_FRU_A1SMB_BMC_FRU_SDASMB_BMC_FRU_SCLSMB_BIC_I2C6_MUX_THERMAL_R_SDASMB_LM75_2_SDASMB_BIC_I2C6_MUX_THERMAL_R2_SCLSMB_LM75_2_SCLLM75_2_A0LM75_2_A1LM75_2_A2SMB_BIC_I2C6_MUX_THERMAL_R_SDASMB_LM75_3_SDASMB_BIC_I2C6_MUX_THERMAL_R2_SCLSMB_LM75_3_SCLLM75_3_A0LM75_3_A1LM75_3_A2



5
5
4
4
3
3
2
2
1
1
D D
C C
B B
A A
FRU_TEMP_SENSOR(2/2)
BASEBOARD THERMAL SENSOR (7-bit ADDRESS: 0X48)(8-bit 0x90)
BASEBOARD THERMAL SENSOR (7-bit ADDRESS: 0X4C)(8-bit 0x98)
SMB_BIC_I2C6_MUX_THERMAL_R1_SCL[99,105]SMB_BIC_I2C6_MUX_THERMAL_R_SDA[99,104,105]SMB_BIC_I2C6_MUX_THERMAL_R1_SCL[99,105]SMB_BIC_I2C6_MUX_THERMAL_R_SDA[99,104,105]P3V3_AUXP3V3_AUXP3V3_AUXP3V3_AUX
SizeDoc NumberRevDate: SheetofReviewerDesignerDepartmentProject
Page TitleCCBU D105 257Tuesday, August 29, 2023<project_name><Designer> GRANDTETON_SWB_20230829105 FRU_TEMP_SENSOR(2/2)<Reviewer>SizeDoc NumberRevDate: SheetofReviewerDesignerDepartmentProject
Page TitleCCBU D105 257Tuesday, August 29, 2023<project_name><Designer> GRANDTETON_SWB_20230829105 FRU_TEMP_SENSOR(2/2)<Reviewer>SizeDoc NumberRevDate: SheetofReviewerDesignerDepartmentProject
Page TitleCCBU D105 257Tuesday, August 29, 2023<project_name><Designer> GRANDTETON_SWB_20230829105 FRU_TEMP_SENSOR(2/2)<Reviewer>
R55921KR0402-02011%R5602 0 R0402-02015%U328LM75BDSDA1SCL2OS3GND4A25A16A07VCC8R5588 33 R0402-02011%R559410K1%R0402-0201NIR558910K1%R0402-0201NIU329LM75BDSDA1SCL2OS3GND4A25A16A07VCC8R559910K1%R0402-0201NIR559010K1%R0402-0201NIR560010K1%R0402-0201NIR5603 0 R0402-02015%R560110K1%R0402-0201C36530.1UFC0402-020110%16VX7RR5587 0 R0402-02015%R56051KR0402-02011%C36520.1UFC0402-020110%16VX7RR55951KR0402-02011%R56061KR0402-02011%R55931KR0402-02011%R56071KR0402-02011%NILM75_1_A0LM75_1_A1LM75_1_A2SMB_BIC_I2C6_MUX_THERMAL_R1_SCLSMB_LM75_0_SCLSMB_BIC_I2C6_MUX_THERMAL_R_SDASMB_LM75_0_SDALM75_0_A0LM75_0_A1LM75_0_A2SMB_BIC_I2C6_MUX_THERMAL_R1_SCLSMB_LM75_1_SCLSMB_BIC_I2C6_MUX_THERMAL_R_SDASMB_LM75_1_SDA



5
5
4
4
3
3
2
2
1
1
D D
C C
B B
A A
Address : 0X80
E1.S_SSD_ADC(1/4)
Address : 0X82
Address : 0X84
Address : 0X86
Imax: 2.083A
SSD_0_7_ADC_ALERT_N [87,106,107]SSD_0_7_ADC_ALERT_N [87,106,107]SSD_0_7_ADC_ALERT_N [87,106,107]SSD_0_7_ADC_ALERT_N [87,106,107]
SMB_BIC_I2C6_MUX_SSD_0_7_ADC_R_SCL[99,106,107]SMB_BIC_I2C6_MUX_SSD_0_7_ADC_R_SDA[99,106,107]SMB_BIC_I2C6_MUX_SSD_0_7_ADC_R_SCL[99,106,107]SMB_BIC_I2C6_MUX_SSD_0_7_ADC_R_SDA[99,106,107]SMB_BIC_I2C6_MUX_SSD_0_7_ADC_R_SCL[99,106,107]SMB_BIC_I2C6_MUX_SSD_0_7_ADC_R_SDA[99,106,107]SMB_BIC_I2C6_MUX_SSD_0_7_ADC_R_SCL[99,106,107]SMB_BIC_I2C6_MUX_SSD_0_7_ADC_R_SDA[99,106,107]
P3V3_AUXP3V3_AUXP12V_SSD0_RP12V_SSD0P12V_SSD0_RP3V3_AUXP3V3_AUXP12V_SSD1P12V_SSD1_RP12V_SSD1_RP3V3_AUXP3V3_AUXP12V_SSD2P12V_SSD2_RP12V_SSD2_RP3V3_AUXP3V3_AUXP12V_SSD3P12V_SSD3_RP12V_SSD3_R
P3V3_AUXP3V3_AUXP3V3_AUXP3V3_AUXSizeDoc NumberRevDate: SheetofReviewerDesignerDepartmentProject
Page TitleCCBU D106 257Tuesday, August 29, 2023<project_name><Designer> GRANDTETON_SWB_20230829106 E1.S_SSD_ADC(1/4)<Reviewer>SizeDoc NumberRevDate: SheetofReviewerDesignerDepartmentProject
Page TitleCCBU D106 257Tuesday, August 29, 2023<project_name><Designer> GRANDTETON_SWB_20230829106 E1.S_SSD_ADC(1/4)<Reviewer>SizeDoc NumberRevDate: SheetofReviewerDesignerDepartmentProject
Page TitleCCBU D106 257Tuesday, August 29, 2023<project_name><Designer> GRANDTETON_SWB_20230829106 E1.S_SSD_ADC(1/4)<Reviewer>
C2060.1UF25V10%C0402-0201X7RR541 0 5%
U51ISL28022FRZ-TVCC9A11A02SCL|||SMBCLK5SDA||SMBDAT4VBUS11VINP13VINM12EXT_CLK||INT3NC06NC17NC28NC314NC415NC516GND10TH_GNDTHC2020.1UF25V10%C0402-0201X7RR5894 0C3080.1UF25V10%C0402-0201X7R
R511 0 5%C2080.1UF25V10%C0402-0201X7RR535 101%R0402-0201R545 0 5%C2110.1UF25V10%C0402-0201X7RR523 0 5%R5424.7K 1%R536 101%R0402-0201R520 0 5%R5044.7K5%R0402-0201
C2070.1UF25V10%X6SR524 101%R0402-0201R5104.7K 1%R530 0 5%R5394.7KR0402-02011%NI
R5154.7K5%R0402-0201U55ISL28022FRZ-TVCC9A11A02SCL|||SMBCLK5SDA||SMBDAT4VBUS11VINP13VINM12EXT_CLK||INT3NC06NC17NC28NC314NC415NC516GND10TH_GNDTHR5324.7K 1%NIR513 101%R0402-0201R5214.7K 1%R5314.7K 1%C2050.1UF25V10%C0402-0201X7RR5895 0
R5060.002 2WR2512XSR5160.002 2WR2512XSR5404.7KR0402-02011%NIR522 0 5%R5174.7KR0402-02011%NIR533 0 5%R5374.7K5%R0402-0201U54ISL28022FRZ-TVCC9A11A02SCL|||SMBCLK5SDA||SMBDAT4VBUS11VINP13VINM12EXT_CLK||INT3NC06NC17NC28NC314NC415NC516GND10TH_GNDTHC2030.1UF25V10%C0402-0201X7R
R547 101%R0402-0201R5294.7KR0402-02011%NIR525 101%R0402-0201C2010.1UF25V10%X6SR512 0 5%C2040.1UF25V10%X6SC2100.1UF25V10%X6SR534 0 5%
R509 0 5%
R544 0 5%
R5194.7K 1%NIR5184.7KR0402-02011%R5084.7K 1%R5074.7KR0402-02011%NI
U56ISL28022FRZ-TVCC9A11A02SCL|||SMBCLK5SDA||SMBDAT4VBUS11VINP13VINM12EXT_CLK||INT3NC06NC17NC28NC314NC415NC516GND10TH_GNDTHR5380.002 2WR2512XSC2090.1UF25V10%C0402-0201X7R
R5054.7KR0402-02011%NIR5270.002 2WR2512XSR5264.7K5%R0402-0201R5284.7KR0402-02011%NIR514 101%R0402-0201
R5434.7K 1%NIR546 101%R0402-0201
SSD0_ADC_A1SSD0_ADC_A0SMB_SSD0_ADC_SCLSMB_SSD0_ADC_SDAP12V_SSD0_VIN_PP12V_SSD0_VIN_NSSD1_ADC_A1SSD1_ADC_A0SMB_SSD1_ADC_SCLSMB_SSD1_ADC_SDAP12V_SSD1_VIN_PP12V_SSD1_VIN_NSSD2_ADC_A1SSD2_ADC_A0SMB_SSD2_ADC_SCLSMB_SSD2_ADC_SDAP12V_SSD2_VIN_PP12V_SSD2_VIN_NSSD3_ADC_A1SSD3_ADC_A0SMB_SSD3_ADC_SCLSMB_SSD3_ADC_SDAP12V_SSD3_VIN_PP12V_SSD3_VIN_N
SSD0_ADC_ALERT_N
SSD2_ADC_ALERT_NSSD1_ADC_ALERT_N
SSD3_ADC_ALERT_NSSD2_ADC_A0SMB_SSD2_ADC_SDASSD3_ADC_A0SMB_SSD3_ADC_SCL



5
5
4
4
3
3
2
2
1
1
D D
C C
B B
A A
Address : 0X88
E1.S_SSD_ADC(2/4)
Address : 0X8A
Address : 0X8C
Address : 0X8E
Imax: 2.083A
SSD_0_7_ADC_ALERT_N [87,106,107]SSD_0_7_ADC_ALERT_N [87,106,107]SSD_0_7_ADC_ALERT_N [87,106,107]SSD_0_7_ADC_ALERT_N [87,106,107]
SMB_BIC_I2C6_MUX_SSD_0_7_ADC_R_SCL[99,106,107]SMB_BIC_I2C6_MUX_SSD_0_7_ADC_R_SDA[99,106,107]SMB_BIC_I2C6_MUX_SSD_0_7_ADC_R_SCL[99,106,107]SMB_BIC_I2C6_MUX_SSD_0_7_ADC_R_SDA[99,106,107]SMB_BIC_I2C6_MUX_SSD_0_7_ADC_R_SCL[99,106,107]SMB_BIC_I2C6_MUX_SSD_0_7_ADC_R_SDA[99,106,107]SMB_BIC_I2C6_MUX_SSD_0_7_ADC_R_SCL[99,106,107]SMB_BIC_I2C6_MUX_SSD_0_7_ADC_R_SDA[99,106,107]
P3V3_AUXP3V3_AUXP12V_SSD4_RP12V_SSD4P12V_SSD4_RP3V3_AUXP3V3_AUXP12V_SSD5P12V_SSD5_RP12V_SSD5_RP3V3_AUXP3V3_AUXP12V_SSD6P12V_SSD6_RP12V_SSD6_RP3V3_AUXP3V3_AUXP12V_SSD7P12V_SSD7_RP12V_SSD7_R
P3V3_AUXP3V3_AUXP3V3_AUXP3V3_AUXSizeDoc NumberRevDate: SheetofReviewerDesignerDepartmentProject
Page TitleCCBU D107 257Tuesday, August 29, 2023<project_name><Designer> GRANDTETON_SWB_20230829107 E1.S_SSD_ADC(2/4)<Reviewer>SizeDoc NumberRevDate: SheetofReviewerDesignerDepartmentProject
Page TitleCCBU D107 257Tuesday, August 29, 2023<project_name><Designer> GRANDTETON_SWB_20230829107 E1.S_SSD_ADC(2/4)<Reviewer>SizeDoc NumberRevDate: SheetofReviewerDesignerDepartmentProject
Page TitleCCBU D107 257Tuesday, August 29, 2023<project_name><Designer> GRANDTETON_SWB_20230829107 E1.S_SSD_ADC(2/4)<Reviewer>U61ISL28022FRZ-TVCC9A11A02SCL|||SMBCLK5SDA||SMBDAT4VBUS11VINP13VINM12EXT_CLK||INT3NC06NC17NC28NC314NC415NC516GND10TH_GNDTH
R5510.002 2WR2512XS
R5824.7KR0402-02011%R5724.7KR0402-02011%NIR579 101%R0402-0201R567 0 5%R5744.7K 1%NIR577 0 5%R557 101%R0402-0201R5896 0R5714.7KR0402-02011%R590 101%R0402-0201R569 101%R0402-0201R5814.7K5%R0402-0201
R5484.7K5%R0402-0201C3120.1UF25V10%X6SR5504.7KR0402-02011%NI
R5830.002 2WR2512XS
U59ISL28022FRZ-TVCC9A11A02SCL|||SMBCLK5SDA||SMBDAT4VBUS11VINP13VINM12EXT_CLK||INT3NC06NC17NC28NC314NC415NC516GND10TH_GNDTH
C3190.1UF25V10%C0402-0201X7RR566 0 5%R5897 0R5864.7K 1%NI
R5644.7K 1%NI
R591 101%R0402-0201R588 0 5%
C3100.1UF25V10%C0402-0201X7RR5614.7KR0402-02011%R5634.7K 1%NIC3150.1UF25V10%X6SC3130.1UF25V10%C0402-0201X7RR5620.002 2WR2512XSC3180.1UF25V10%X6S
R5544.7K 1%R556 0 5%
R5844.7KR0402-02011%NI
R5534.7K 1%NIR5704.7K5%R0402-0201R589 0 5%R5754.7K 1%NIC3160.1UF25V10%C0402-0201X7RC3170.1UF25V10%C0402-0201X7RU60ISL28022FRZ-TVCC9A11A02SCL|||SMBCLK5SDA||SMBDAT4VBUS11VINP13VINM12EXT_CLK||INT3NC06NC17NC28NC314NC415NC516GND10TH_GNDTHR5594.7K5%R0402-0201C3140.1UF25V10%C0402-0201X7R
C3200.1UF25V10%C0402-0201X7RR580 101%R0402-0201
C3090.1UF25V10%X6SR555 0 5%R5730.002 2WR2512XS
R552 0 5%R568 101%R0402-0201R558 101%R0402-0201R576 0 5%R565 0 5%
R5854.7K 1%NIR587 0 5%
C3110.1UF25V10%C0402-0201X7R
U62ISL28022FRZ-TVCC9A11A02SCL|||SMBCLK5SDA||SMBDAT4VBUS11VINP13VINM12EXT_CLK||INT3NC06NC17NC28NC314NC415NC516GND10TH_GNDTH
R5494.7KR0402-02011%
R578 0 5%R5604.7KR0402-02011%SSD4_ADC_A1SSD4_ADC_A0SMB_SSD4_ADC_SCLSMB_SSD4_ADC_SDAP12V_SSD4_VIN_PP12V_SSD4_VIN_NSSD5_ADC_A1SSD5_ADC_A0SMB_SSD5_ADC_SCLSMB_SSD5_ADC_SDAP12V_SSD5_VIN_PP12V_SSD5_VIN_NSSD6_ADC_A1SSD6_ADC_A0SMB_SSD6_ADC_SCLSMB_SSD6_ADC_SDAP12V_SSD6_VIN_PP12V_SSD6_VIN_NSSD7_ADC_A1SSD7_ADC_A0SMB_SSD7_ADC_SCLSMB_SSD7_ADC_SDAP12V_SSD7_VIN_PP12V_SSD7_VIN_N
SSD5_ADC_ALERT_NSSD6_ADC_ALERT_NSSD7_ADC_ALERT_N
SSD4_ADC_ALERT_NSSD6_ADC_A0SMB_SSD6_ADC_SDASSD7_ADC_A0SMB_SSD7_ADC_SCL



5
5
4
4
3
3
2
2
1
1
D D
C C
B B
A A
E1.S_SSD_ADC(3/4)
Address : 0X92
Address : 0X94
Address : 0X96
Address : 0X90
Imax: 2.083A
SSD_8_15_ADC_ALERT_N [87,108,109]SSD_8_15_ADC_ALERT_N [87,108,109]SSD_8_15_ADC_ALERT_N [87,108,109]
SSD_8_15_ADC_ALERT_N [87,108,109]SMB_BIC_I2C6_MUX_SSD_8_15_ADC_R_SCL[99,108,109]SMB_BIC_I2C6_MUX_SSD_8_15_ADC_R_SDA[99,108,109]SMB_BIC_I2C6_MUX_SSD_8_15_ADC_R_SCL[99,108,109]SMB_BIC_I2C6_MUX_SSD_8_15_ADC_R_SDA[99,108,109]SMB_BIC_I2C6_MUX_SSD_8_15_ADC_R_SCL[99,108,109]SMB_BIC_I2C6_MUX_SSD_8_15_ADC_R_SDA[99,108,109]SMB_BIC_I2C6_MUX_SSD_8_15_ADC_R_SCL[99,108,109]SMB_BIC_I2C6_MUX_SSD_8_15_ADC_R_SDA[99,108,109]
P3V3_AUXP3V3_AUXP12V_SSD9P12V_SSD9_RP12V_SSD9_RP3V3_AUXP3V3_AUXP12V_SSD10P12V_SSD10_RP12V_SSD10_RP3V3_AUXP3V3_AUXP12V_SSD11P12V_SSD11_RP12V_SSD11_R
P3V3_AUXP3V3_AUXP3V3_AUXP3V3_AUXP12V_SSD8P12V_SSD8_RP12V_SSD8_RP3V3_AUXP3V3_AUXSizeDoc NumberRevDate: SheetofReviewerDesignerDepartmentProject
Page TitleCCBU D108 257Tuesday, August 29, 2023<project_name><Designer> GRANDTETON_SWB_20230829108 E1.S_SSD_ADC(3/4)<Reviewer>SizeDoc NumberRevDate: SheetofReviewerDesignerDepartmentProject
Page TitleCCBU D108 257Tuesday, August 29, 2023<project_name><Designer> GRANDTETON_SWB_20230829108 E1.S_SSD_ADC(3/4)<Reviewer>SizeDoc NumberRevDate: SheetofReviewerDesignerDepartmentProject
Page TitleCCBU D108 257Tuesday, August 29, 2023<project_name><Designer> GRANDTETON_SWB_20230829108 E1.S_SSD_ADC(3/4)<Reviewer>
C3210.1UF25V10%X6SR6094.7K 1%NIR611 0 5%R610 0 5%
R633 0 5%R624 101%R0402-0201R612 101%R0402-0201R6314.7K 1%NIR6304.7K 1%NI
C3250.1UF25V10%C0402-0201X7RC3220.1UF25V10%C0402-0201X7RC3270.1UF25V10%X6SR6144.7K5%R0402-0201U71ISL28022FRZ-TVCC9A11A02SCL|||SMBCLK5SDA||SMBDAT4VBUS11VINP13VINM12EXT_CLK||INT3NC06NC17NC28NC314NC415NC516GND10TH_GNDTH
R6284.7KR0402-02011%NIR622 0 5%C3310.1UF25V10%C0402-0201X7RC3320.1UF25V10%C0402-0201X7RR629 0 5%
R600 0 5%R602 101%R0402-0201C3290.1UF25V10%C0402-0201X7RR6064.7KR0402-02011%R6174.7KR0402-02011%NIC3300.1UF25V10%X6S
R5930.002 2WR2512XSR5900 0R6044.7KR0402-02011%NIR6084.7K 1%NIR6034.7K5%R0402-0201R6164.7KR0402-02011%NIR613 101%R0402-0201R5901 0R5974.7K 1%NI
R632 0 5%R5902 0R6150.002 2WR2512XSC3280.1UF25V10%C0402-0201X7RR621 0 5%R634 101%R0402-0201
R6050.002 2WR2512XSR6204.7K 1%NIR599 0 5%C3260.1UF25V10%C0402-0201X7RR5984.7K 1%R596 0 5%R5954.7KR0402-02011%NIR607 0 5%R5944.7KR0402-02011%NI
R635 101%R0402-0201
C3240.1UF25V10%X6S
U74ISL28022FRZ-TVCC9A11A02SCL|||SMBCLK5SDA||SMBDAT4VBUS11VINP13VINM12EXT_CLK||INT3NC06NC17NC28NC314NC415NC516GND10TH_GNDTH
C3230.1UF25V10%C0402-0201X7R
R6260.002 2WR2512XS
R601 101%R0402-0201U73ISL28022FRZ-TVCC9A11A02SCL|||SMBCLK5SDA||SMBDAT4VBUS11VINP13VINM12EXT_CLK||INT3NC06NC17NC28NC314NC415NC516GND10TH_GNDTHR6194.7K 1%NIR623 101%R0402-0201U72ISL28022FRZ-TVCC9A11A02SCL|||SMBCLK5SDA||SMBDAT4VBUS11VINP13VINM12EXT_CLK||INT3NC06NC17NC28NC314NC415NC516GND10TH_GNDTHR5898 0R5899 0
R6254.7K5%R0402-0201
R5924.7K5%R0402-0201
R6274.7KR0402-02011%NIR618 0 5%R5903 0SSD9_ADC_A1SSD9_ADC_A0SMB_SSD9_ADC_SCLSMB_SSD9_ADC_SDAP12V_SSD9_VIN_PP12V_SSD9_VIN_NSSD10_ADC_A1SSD10_ADC_A0SMB_SSD10_ADC_SCLSMB_SSD10_ADC_SDAP12V_SSD10_VIN_PP12V_SSD10_VIN_NSSD11_ADC_A1SSD11_ADC_A0SMB_SSD11_ADC_SCLSMB_SSD11_ADC_SDAP12V_SSD11_VIN_PP12V_SSD11_VIN_N
SSD8_ADC_A1SSD8_ADC_A0SMB_SSD8_ADC_SCLSMB_SSD8_ADC_SDAP12V_SSD8_VIN_PP12V_SSD8_VIN_NSSD9_ADC_ALERT_NSSD8_ADC_ALERT_N
SSD11_ADC_ALERT_NSSD10_ADC_ALERT_NSSD10_ADC_A1SMB_SSD10_ADC_SDASSD10_ADC_A0SMB_SSD10_ADC_SDASSD11_ADC_A1SMB_SSD11_ADC_SDASSD11_ADC_A0SMB_SSD11_ADC_SCL
SSD8_ADC_A1SMB_SSD8_ADC_SDASSD9_ADC_A1SMB_SSD9_ADC_SDA



5
5
4
4
3
3
2
2
1
1
D D
C C
B B
A A
Address : 0X98
E1.S_SSD_ADC(4/4)
Address : 0X9A
Address : 0X9C
Address : 0X9E
Imax: 2.083A
SSD_8_15_ADC_ALERT_N [87,108,109]SSD_8_15_ADC_ALERT_N [87,108,109]SSD_8_15_ADC_ALERT_N [87,108,109]SSD_8_15_ADC_ALERT_N [87,108,109]
SMB_BIC_I2C6_MUX_SSD_8_15_ADC_R_SCL[99,108,109]SMB_BIC_I2C6_MUX_SSD_8_15_ADC_R_SDA[99,108,109]SMB_BIC_I2C6_MUX_SSD_8_15_ADC_R_SCL[99,108,109]SMB_BIC_I2C6_MUX_SSD_8_15_ADC_R_SDA[99,108,109]SMB_BIC_I2C6_MUX_SSD_8_15_ADC_R_SCL[99,108,109]SMB_BIC_I2C6_MUX_SSD_8_15_ADC_R_SDA[99,108,109]SMB_BIC_I2C6_MUX_SSD_8_15_ADC_R_SCL[99,108,109]SMB_BIC_I2C6_MUX_SSD_8_15_ADC_R_SDA[99,108,109]
P3V3_AUXP3V3_AUXP12V_SSD12_RP12V_SSD12P12V_SSD12_RP3V3_AUXP3V3_AUXP12V_SSD13P12V_SSD13_RP12V_SSD13_RP3V3_AUXP3V3_AUXP12V_SSD14P12V_SSD14_RP12V_SSD14_RP3V3_AUXP3V3_AUXP12V_SSD15P12V_SSD15_RP12V_SSD15_R
P3V3_AUXP3V3_AUXP3V3_AUXP3V3_AUXSizeDoc NumberRevDate: SheetofReviewerDesignerDepartmentProject
Page TitleCCBU D109 257Tuesday, August 29, 2023<project_name><Designer> GRANDTETON_SWB_20230829109 E1.S_SSD_ADC(4/4)<Reviewer>SizeDoc NumberRevDate: SheetofReviewerDesignerDepartmentProject
Page TitleCCBU D109 257Tuesday, August 29, 2023<project_name><Designer> GRANDTETON_SWB_20230829109 E1.S_SSD_ADC(4/4)<Reviewer>SizeDoc NumberRevDate: SheetofReviewerDesignerDepartmentProject
Page TitleCCBU D109 257Tuesday, August 29, 2023<project_name><Designer> GRANDTETON_SWB_20230829109 E1.S_SSD_ADC(4/4)<Reviewer>C4060.1UF25V10%X6SR6754.7K 1%NIR6694.7K5%R0402-0201U78ISL28022FRZ-TVCC9A11A02SCL|||SMBCLK5SDA||SMBDAT4VBUS11VINP13VINM12EXT_CLK||INT3NC06NC17NC28NC314NC415NC516GND10TH_GNDTH
R643 0 5%
R5908 0R665 0 5%R6490.002 2WR2512XSR6414.7K 1%
R674 0 5%R667 101%R0402-0201R676 0 5%U77ISL28022FRZ-TVCC9A11A02SCL|||SMBCLK5SDA||SMBDAT4VBUS11VINP13VINM12EXT_CLK||INT3NC06NC17NC28NC314NC415NC516GND10TH_GNDTHC4070.1UF25V10%C0402-0201X7R
R6394.7KR0402-02011%NIR6484.7KR0402-02011%NIR6594.7KR0402-02011%NIC3380.1UF25V10%C0402-0201X7RR656 101%R0402-0201R6604.7KR0402-02011%NIR6714.7KR0402-02011%NI
R6404.7K 1%NIR653 0 5%R6700.002 2WR2512XS
R6474.7K5%R0402-0201R6514.7K 1%NIU76ISL28022FRZ-TVCC9A11A02SCL|||SMBCLK5SDA||SMBDAT4VBUS11VINP13VINM12EXT_CLK||INT3NC06NC17NC28NC314NC415NC516GND10TH_GNDTHR5906 0C3360.1UF25V10%X6S
R6734.7K 1%NIR6634.7K 1%NI
C3330.1UF25V10%X6S
R6644.7K 1%NIR668 101%R0402-0201R5905 0R6364.7K5%R0402-0201
R6724.7KR0402-02011%NI
R5904 0
R678 101%R0402-0201
R654 0 5%R6380.002 2WR2512XSC3340.1UF25V10%C0402-0201X7RR646 101%R0402-0201
R679 101%R0402-0201
R655 0 5%C4050.1UF25V10%C0402-0201X7RC3390.1UF25V10%X6SR657 101%R0402-0201R644 0 5%R662 0 5%R6610.002 2WR2512XSC4080.1UF25V10%C0402-0201X7R
R6374.7KR0402-02011%NIR642 0 5%R6584.7K5%R0402-0201C3350.1UF25V10%C0402-0201X7R
R5909 0R677 0 5%
C3370.1UF25V10%C0402-0201X7RU75ISL28022FRZ-TVCC9A11A02SCL|||SMBCLK5SDA||SMBDAT4VBUS11VINP13VINM12EXT_CLK||INT3NC06NC17NC28NC314NC415NC516GND10TH_GNDTHC4040.1UF25V10%C0402-0201X7RR645 101%R0402-0201R5907 0R6524.7K 1%NIR666 0 5%R6504.7KR0402-02011%SSD12_ADC_A1SSD12_ADC_A0SMB_SSD12_ADC_SCLSMB_SSD12_ADC_SDAP12V_SSD12_VIN_PP12V_SSD12_VIN_NSSD13_ADC_A1SSD13_ADC_A0SMB_SSD13_ADC_SCLSMB_SSD13_ADC_SDAP12V_SSD13_VIN_PP12V_SSD13_VIN_NSSD14_ADC_A1SSD14_ADC_A0SMB_SSD14_ADC_SCLSMB_SSD14_ADC_SDAP12V_SSD14_VIN_PP12V_SSD14_VIN_NSSD15_ADC_A1SSD15_ADC_A0SMB_SSD15_ADC_SCLSMB_SSD15_ADC_SDAP12V_SSD15_VIN_PP12V_SSD15_VIN_NSSD15_ADC_ALERT_N
SSD13_ADC_ALERT_NSSD12_ADC_ALERT_N
SSD14_ADC_ALERT_N
SSD12_ADC_A1SMB_SSD12_ADC_SCLSSD13_ADC_A1SMB_SSD13_ADC_SCLSSD14_ADC_A1SMB_SSD14_ADC_SCLSSD14_ADC_A0SMB_SSD14_ADC_SDASSD15_ADC_A1SMB_SSD15_ADC_SCLSSD15_ADC_A0SMB_SSD15_ADC_SCL



5
5
4
4
3
3
2
2
1
1
D D
C C
B B
A A
Address : 0X80
NIC_ADC(1/2)
Address : 0X82
Address : 0X84
Address : 0X86
Imax: 6.6A
NIC_ADC_ALERT_N [87,110,111]NIC_ADC_ALERT_N [87,110,111]NIC_ADC_ALERT_N [87,110,111]NIC_ADC_ALERT_N [87,110,111]
SMB_BIC_I2C6_MUX_NIC_ADC_R_SCL[99,110,111]SMB_BIC_I2C6_MUX_NIC_ADC_R_SDA[99,110,111]SMB_BIC_I2C6_MUX_NIC_ADC_R_SCL[99,110,111]SMB_BIC_I2C6_MUX_NIC_ADC_R_SDA[99,110,111]SMB_BIC_I2C6_MUX_NIC_ADC_R_SCL[99,110,111]SMB_BIC_I2C6_MUX_NIC_ADC_R_SDA[99,110,111]SMB_BIC_I2C6_MUX_NIC_ADC_R_SCL[99,110,111]SMB_BIC_I2C6_MUX_NIC_ADC_R_SDA[99,110,111]
P3V3_AUXP3V3_AUXP12V_NIC0_RP12V_NIC0P12V_NIC0_RP3V3_AUXP3V3_AUXP12V_NIC1P12V_NIC1_RP12V_NIC1_RP3V3_AUXP3V3_AUXP12V_NIC2P12V_NIC2_RP12V_NIC2_RP3V3_AUXP3V3_AUXP12V_NIC3P12V_NIC3_RP12V_NIC3_R
P3V3_AUXP3V3_AUXP3V3_AUXP3V3_AUXSizeDoc NumberRevDate: SheetofReviewerDesignerDepartmentProject
Page TitleCCBU D110 257Tuesday, August 29, 2023<project_name><Designer> GRANDTETON_SWB_20230829110 NIC_ADC(1/2)<Reviewer>SizeDoc NumberRevDate: SheetofReviewerDesignerDepartmentProject
Page TitleCCBU D110 257Tuesday, August 29, 2023<project_name><Designer> GRANDTETON_SWB_20230829110 NIC_ADC(1/2)<Reviewer>SizeDoc NumberRevDate: SheetofReviewerDesignerDepartmentProject
Page TitleCCBU D110 257Tuesday, August 29, 2023<project_name><Designer> GRANDTETON_SWB_20230829110 NIC_ADC(1/2)<Reviewer>R706 0 5%R7184.7K 1%
R684 0 5%C4140.1UF25V10%C0402-0201X7RR695 0 5%R6820.002 2WR2512XS
C4200.1UF25V10%C0402-0201X7R
U80ISL28022FRZ-TVCC9A11A02SCL|||SMBCLK5SDA||SMBDAT4VBUS11VINP13VINM12EXT_CLK||INT3NC06NC17NC28NC314NC415NC516GND10TH_GNDTHC4170.1UF25V10%C0402-0201X7RR721 0 5%
R690 101%R0402-0201
C4190.1UF25V10%C0402-0201X7R
C4090.1UF25V10%X6S
R710 0 5%R6974.7K 1%NIR688 0 5%R6834.7KR0402-02011%NIR6864.7K 1%
R5621 0R6930.002 2WR2512XS
U82ISL28022FRZ-TVCC9A11A02SCL|||SMBCLK5SDA||SMBDAT4VBUS11VINP13VINM12EXT_CLK||INT3NC06NC17NC28NC314NC415NC516GND10TH_GNDTHR7040.002 2WR2512XS
R6814.7KR0402-02011%NI
R720 0 5%R7194.7K 1%NIR7074.7K 1%
R6804.7K5%R0402-0201R689 101%R0402-0201R7054.7KR0402-02011%NIR7154.7KR0402-02011%NIR723 101%R0402-0201R711 101%R0402-0201
R687 331%R701 101%R0402-0201U81ISL28022FRZ-TVCC9A11A02SCL|||SMBCLK5SDA||SMBDAT4VBUS11VINP13VINM12EXT_CLK||INT3NC06NC17NC28NC314NC415NC516GND10TH_GNDTHR7024.7K5%R0402-0201R7160.002 2WR2512XSR709 0 5%
C4100.1UF25V10%C0402-0201X7R
C4180.1UF25V10%X6S
U79ISL28022FRZ-TVCC9A11A02SCL|||SMBCLK5SDA||SMBDAT4VBUS11VINP13VINM12EXT_CLK||INT3NC06NC17NC28NC314NC415NC516GND10TH_GNDTHR6944.7KR0402-02011%C4150.1UF25V10%X6SR698 0 5%R7084.7K 1%NIR7134.7K5%R0402-0201R5622 0R6854.7K 1%R6924.7KR0402-02011%NIR699 0 5%R7034.7KR0402-02011%NIR700 101%R0402-0201R6914.7K5%R0402-0201R6964.7K 1%R712 101%R0402-0201C4130.1UF25V10%C0402-0201X7RC4110.1UF25V10%C0402-0201X7RC4160.1UF25V10%C0402-0201X7RR7144.7KR0402-02011%NI
C4120.1UF25V10%X6S
R722 101%R0402-0201R717 0 5%
NIC0_ADC_A1NIC0_ADC_A0SMB_NIC0_ADC_SCLSMB_NIC0_ADC_SDAP12V_NIC0_VIN_PP12V_NIC0_VIN_NNIC1_ADC_A1NIC1_ADC_A0SMB_NIC1_ADC_SCLSMB_NIC1_ADC_SDAP12V_NIC1_VIN_PP12V_NIC1_VIN_NNIC2_ADC_A1NIC2_ADC_A0SMB_NIC2_ADC_SCLSMB_NIC2_ADC_SDAP12V_NIC2_VIN_PP12V_NIC2_VIN_NNIC3_ADC_A1NIC3_ADC_A0SMB_NIC3_ADC_SCLSMB_NIC3_ADC_SDAP12V_NIC3_VIN_PP12V_NIC3_VIN_NNIC3_ADC_ALERT_N
NIC1_ADC_ALERT_NNIC2_ADC_ALERT_NNIC0_ADC_ALERT_NNIC2_ADC_A0SMB_NIC2_ADC_SDANIC3_ADC_A0SMB_NIC3_ADC_SCL



5
5
4
4
3
3
2
2
1
1
D D
C C
B B
A A
Address : 0X88
NIC_ADC(2/2)
Address : 0X8A
Address : 0X8C
Address : 0X8E
Imax: 6.6A
NIC_ADC_ALERT_N [87,110,111]NIC_ADC_ALERT_N [87,110,111]NIC_ADC_ALERT_N [87,110,111]NIC_ADC_ALERT_N [87,110,111]
SMB_BIC_I2C6_MUX_NIC_ADC_R_SCL[99,110,111]SMB_BIC_I2C6_MUX_NIC_ADC_R_SDA[99,110,111]SMB_BIC_I2C6_MUX_NIC_ADC_R_SCL[99,110,111]SMB_BIC_I2C6_MUX_NIC_ADC_R_SDA[99,110,111]SMB_BIC_I2C6_MUX_NIC_ADC_R_SCL[99,110,111]SMB_BIC_I2C6_MUX_NIC_ADC_R_SDA[99,110,111]SMB_BIC_I2C6_MUX_NIC_ADC_R_SCL[99,110,111]SMB_BIC_I2C6_MUX_NIC_ADC_R_SDA[99,110,111]
P3V3_AUXP3V3_AUXP12V_NIC4_RP12V_NIC4P12V_NIC4_RP3V3_AUXP3V3_AUXP12V_NIC5P12V_NIC5_RP12V_NIC5_RP3V3_AUXP3V3_AUXP12V_NIC6P12V_NIC6_RP12V_NIC6_RP3V3_AUXP3V3_AUXP12V_NIC7P12V_NIC7_RP12V_NIC7_R
P3V3_AUXP3V3_AUXP3V3_AUXP3V3_AUXSizeDoc NumberRevDate: SheetofReviewerDesignerDepartmentProject
Page TitleCCBU D111 257Tuesday, August 29, 2023<project_name><Designer> GRANDTETON_SWB_20230829111 NIC_ADC(2/2)<Reviewer>SizeDoc NumberRevDate: SheetofReviewerDesignerDepartmentProject
Page TitleCCBU D111 257Tuesday, August 29, 2023<project_name><Designer> GRANDTETON_SWB_20230829111 NIC_ADC(2/2)<Reviewer>SizeDoc NumberRevDate: SheetofReviewerDesignerDepartmentProject
Page TitleCCBU D111 257Tuesday, August 29, 2023<project_name><Designer> GRANDTETON_SWB_20230829111 NIC_ADC(2/2)<Reviewer>C6220.1UF25V10%X6S
R728 0R0402-02015%U84ISL28022FRZ-TVCC9A11A02SCL|||SMBCLK5SDA||SMBDAT4VBUS11VINP13VINM12EXT_CLK||INT3NC06NC17NC28NC314NC415NC516GND10TH_GNDTHR7594.7KR0402-02011%
R7374.7KR0402-02011%R7394.7K 1%NIR7304.7K 1%R7474.7KR0402-02011%R743 0 5%R7624.7K 1%NIR5623 0
R7270.002 2WR2512XSR742 0 5%
R767 101%R0402-0201
R7264.7KR0402-02011%NIR744 101%R0402-0201R7414.7K 1%NI
R765 0 5%
R731 0 5%C6150.1UF25V10%C0402-0201X7R
R7574.7K5%R0402-0201R7634.7K 1%NI
R734 101%R0402-0201R7480.002 2WR2512XSU83ISL28022FRZ-TVCC9A11A02SCL|||SMBCLK5SDA||SMBDAT4VBUS11VINP13VINM12EXT_CLK||INT3NC06NC17NC28NC314NC415NC516GND10TH_GNDTHR7354.7K5%R0402-0201C6170.1UF25V10%C0402-0201X7RR7294.7K 1%NIR7524.7K 1%NIR733 101%R0402-0201C4220.1UF25V10%C0402-0201X7R
R753 0 5%C6210.1UF25V10%C0402-0201X7R
C4210.1UF25V10%X6SR7380.002 2WR2512XSR732 0 5%U85ISL28022FRZ-TVCC9A11A02SCL|||SMBCLK5SDA||SMBDAT4VBUS11VINP13VINM12EXT_CLK||INT3NC06NC17NC28NC314NC415NC516GND10TH_GNDTH
R7254.7K1%C6160.1UF25V10%X6SC6230.1UF25V10%C0402-0201X7RR7464.7K5%R0402-0201R761 0 5%R754 0 5%R750 0 5%R755 101%R0402-0201R740 0 5%R7364.7KR0402-02011%R7244.7K5%R0402-0201
R7604.7KR0402-02011%NIR5624 0R745 101%R0402-0201C6190.1UF25V10%X6SR7494.7KR0402-02011%NIR7580.002 2WR2512XSC6240.1UF25V10%C0402-0201X7RR7514.7K 1%NIU86ISL28022FRZ-TVCC9A11A02SCL|||SMBCLK5SDA||SMBDAT4VBUS11VINP13VINM12EXT_CLK||INT3NC06NC17NC28NC314NC415NC516GND10TH_GNDTHC6200.1UF25V10%C0402-0201X7RR766 101%R0402-0201R756 101%R0402-0201R764 331%C6180.1UF25V10%C0402-0201X7RNIC4_ADC_A1NIC4_ADC_A0SMB_NIC4_ADC_SCLSMB_NIC4_ADC_SDAP12V_NIC4_VIN_PP12V_NIC4_VIN_NNIC5_ADC_A1NIC5_ADC_A0SMB_NIC5_ADC_SCLSMB_NIC5_ADC_SDAP12V_NIC5_VIN_PP12V_NIC5_VIN_NNIC6_ADC_A1NIC6_ADC_A0SMB_NIC6_ADC_SCLSMB_NIC6_ADC_SDAP12V_NIC6_VIN_PP12V_NIC6_VIN_NNIC7_ADC_A1NIC7_ADC_A0SMB_NIC7_ADC_SCLSMB_NIC7_ADC_SDAP12V_NIC7_VIN_PP12V_NIC7_VIN_N
NIC4_ADC_ALERT_NNIC6_ADC_ALERT_NNIC5_ADC_ALERT_N
NIC7_ADC_ALERT_NNIC6_ADC_A0SMB_NIC6_ADC_SDANIC7_ADC_A0SMB_NIC7_ADC_SCL



5
5
4
4
3
3
2
2
1
1
D D
C C
B B
A A
Address : 0X80
PEX_P1V25_ADC
Address : 0X82
Address : 0X88
Address : 0X8A
Imax: 17A
PEX_ADC_ALERT_N [87,112,113]SMB_BIC_I2C6_MUX_PEX_ADC_R_SCL[99,112,113,213]SMB_BIC_I2C6_MUX_PEX_ADC_R_SDA[99,112,113,213]PEX_ADC_ALERT_N [87,112,113]PEX_ADC_ALERT_N [87,112,113]PEX_ADC_ALERT_N [87,112,113]SMB_BIC_I2C6_MUX_PEX_ADC_R_SCL[99,112,113,213]SMB_BIC_I2C6_MUX_PEX_ADC_R_SDA[99,112,113,213]SMB_BIC_I2C6_MUX_PEX_ADC_R_SCL[99,112,113,213]SMB_BIC_I2C6_MUX_PEX_ADC_R_SDA[99,112,113,213]SMB_BIC_I2C6_MUX_PEX_ADC_R_SCL[99,112,113,213]SMB_BIC_I2C6_MUX_PEX_ADC_R_SDA[99,112,113,213]
P3V3_AUXP3V3_AUXP1V25_PEX0_RP1V25_PEX0P1V25_PEX0_RP3V3_AUXP3V3_AUXP1V25_PEX1P1V25_PEX1_RP1V25_PEX1_RP3V3_AUXP3V3_AUXP1V25_PEX2P1V25_PEX2_RP1V25_PEX2_RP3V3_AUXP3V3_AUXP1V25_PEX3P1V25_PEX3_RP1V25_PEX3_R
P3V3_AUXP3V3_AUXP3V3_AUXP3V3_AUXSizeDoc NumberRevDate: SheetofReviewerDesignerDepartmentProject
Page TitleCCBU D112 257Tuesday, August 29, 2023<project_name><Designer> GRANDTETON_SWB_20230829112 PEX_P1V25_ADC<Reviewer>SizeDoc NumberRevDate: SheetofReviewerDesignerDepartmentProject
Page TitleCCBU D112 257Tuesday, August 29, 2023<project_name><Designer> GRANDTETON_SWB_20230829112 PEX_P1V25_ADC<Reviewer>SizeDoc NumberRevDate: SheetofReviewerDesignerDepartmentProject
Page TitleCCBU D112 257Tuesday, August 29, 2023<project_name><Designer> GRANDTETON_SWB_20230829112 PEX_P1V25_ADC<Reviewer>R797 0 5%R795 0 5%
R7694.7KR0402-02011%NIC6260.1UF25V10%C0402-0201X7RR787 0 5%
R811 101%R0402-0201
R7824.7KR0402-02011%R788 101%R0402-0201R8024.7KR0402-02011%R786 0 5%R798 0 5%R783 0 5%
R809 0 5%R800 101%R0402-0201R7844.7K 1%U90ISL28022FRZ-TVCC9A11A02SCL|||SMBCLK5SDA||SMBDAT4VBUS11VINP13VINM12EXT_CLK||INT3NC06NC17NC28NC314NC415NC516GND10TH_GNDTHR775 331%C6250.1UF25V10%X6SR776 0 5%
C8260.1UF25V10%X6S
R7744.7K 1%
C8280.1UF25V10%C0402-0201X7RR8014.7K5%R0402-0201R799 101%R0402-0201C6300.1UF25V10%C0402-0201X7RR7964.7K 1%R7804.7KR0402-02011%NIR7734.7K 1%R777 101%R0402-0201R7934.7KR0402-02011%
U87ISL28022FRZ-TVCC9A11A02SCL|||SMBCLK5SDA||SMBDAT4VBUS11VINP13VINM12EXT_CLK||INT3NC06NC17NC28NC314NC415NC516GND10TH_GNDTHR772 0 5%R7920.002 2WR2512XSR8040.002 2WR2512XS
C6290.1UF25V10%C0402-0201X7R
R8074.7K 1%NIR7944.7K 1%NIU94ISL28022FRZ-TVCC9A11A02SCL|||SMBCLK5SDA||SMBDAT4VBUS11VINP13VINM12EXT_CLK||INT3NC06NC17NC28NC314NC415NC516GND10TH_GNDTH
R7714.7KR0402-02011%NI
C6330.1UF25V10%C0402-0201X7RR810 101%R0402-0201
C6270.1UF25V10%C0402-0201X7R
R808 0 5%
R7854.7K 1%NIR7794.7K5%R0402-0201
C8270.1UF25V10%C0402-0201X7R
R7684.7K5%R0402-0201
R7904.7K5%R0402-0201R7810.002 2WR2512XS
R805 0 5%
R7700.002 2WR2512XSC6320.1UF25V10%C0402-0201X7RR8034.7KR0402-02011%C6310.1UF25V10%X6SR778 101%R0402-0201R7914.7KR0402-02011%NIR8064.7K 1%NIU95ISL28022FRZ-TVCC9A11A02SCL|||SMBCLK5SDA||SMBDAT4VBUS11VINP13VINM12EXT_CLK||INT3NC06NC17NC28NC314NC415NC516GND10TH_GNDTHR789 101%R0402-0201C6280.1UF25V10%X6SPEX0_P1V25_ADC_A1PEX0_P1V25_ADC_A0SMB_PEX0_P1V25_ADC_SCLSMB_PEX0_P1V25_ADC_SDAP12V_PEX0_P1V25_VIN_PP12V_PEX0_P1V25_VIN_NPEX1_P1V25_ADC_A1PEX1_P1V25_ADC_A0SMB_PEX1_P1V25_ADC_SCLSMB_PEX1_P1V25_ADC_SDAP12V_PEX1_P1V25_VIN_PP12V_PEX1_P1V25_VIN_NPEX2_P1V25_ADC_A1PEX2_P1V25_ADC_A0SMB_PEX2_P1V25_ADC_SCLSMB_PEX2_P1V25_ADC_SDAP12V_PEX2_P1V25_VIN_PP12V_PEX2_P1V25_VIN_NPEX3_P1V25_ADC_A1PEX3_P1V25_ADC_A0SMB_PEX3_P1V25_ADC_SCLSMB_PEX3_P1V25_ADC_SDAP12V_PEX3_P1V25_VIN_PP12V_PEX3_P1V25_VIN_NPEX2_P1V25_ADC_ALERT_NPEX0_P1V25_ADC_ALERT_NPEX1_P1V25_ADC_ALERT_N
PEX3_P1V25_ADC_ALERT_N



5
5
4
4
3
3
2
2
1
1
D D
C C
B B
A A
Address : 0X9A
PEX_P1V8_ADC
Imax: 4.88A
DVT_CHANGEPEX_ADC_ALERT_N [87,112]SMB_BIC_I2C6_MUX_PEX_ADC_R_SCL[99,112,213]SMB_BIC_I2C6_MUX_PEX_ADC_R_SDA[99,112,213]P3V3_AUXP3V3_AUXP1V8_PEX_RP1V8_PEXP1V8_PEX_RP3V3_AUX
SizeDoc NumberRevDate: SheetofReviewerDesignerDepartmentProject
Page TitleCCBU D113 257Tuesday, August 29, 2023<project_name><Designer> GRANDTETON_SWB_20230829113 PEX_P1V8_ADC<Reviewer>SizeDoc NumberRevDate: SheetofReviewerDesignerDepartmentProject
Page TitleCCBU D113 257Tuesday, August 29, 2023<project_name><Designer> GRANDTETON_SWB_20230829113 PEX_P1V8_ADC<Reviewer>SizeDoc NumberRevDate: SheetofReviewerDesignerDepartmentProject
Page TitleCCBU D113 257Tuesday, August 29, 2023<project_name><Designer> GRANDTETON_SWB_20230829113 PEX_P1V8_ADC<Reviewer>
R817 0R0402-0201 5%U96ISL28022FRZ-TVCC9A11A02SCL|||SMBCLK5SDA||SMBDAT4VBUS11VINP13VINM12EXT_CLK||INT3NC06NC17NC28NC314NC415NC516GND10TH_GNDTHR820 0 R0402-02015%R821 101%R0402-0201C8310.1UF25V10%C0402-0201X7RR819 0 R0402-02015%C8300.1UF25V10%C0402-0201X7RR8150.002 2WR2512XSR822 101%R0402-0201R8134.7KR0402-02011%NIR8144.7KR0402-02011%R8124.7K5%R0402-0201R5627 0R8184.7KR0402-0201 1%NIC8290.1UF25V10%X6SR8164.7KR0402-0201 1%NIPEX_P1V8_ADC_A1PEX_P1V8_ADC_A0SMB_PEX_P1V8_ADC_SCLSMB_PEX_P1V8_ADC_SDAP12V_PEX_P1V8_VIN_PP12V_PEX_P1V8_VIN_NPEX_P1V8_ADC_ALERT_NPEX_P1V8_ADC_A1SMB_PEX_P1V8_ADC_SCL



5
5
4
4
3
3
2
2
1
1
D D
C C
B B
A A
BLANK SizeDoc NumberRevDate: SheetofReviewerDesignerDepartmentProject
Page TitleCCBU D114 257Tuesday, August 29, 2023<project_name><Designer> GRANDTETON_SWB_20230829114 BLANK<Reviewer>SizeDoc NumberRevDate: SheetofReviewerDesignerDepartmentProject
Page TitleCCBU D114 257Tuesday, August 29, 2023<project_name><Designer> GRANDTETON_SWB_20230829114 BLANK<Reviewer>SizeDoc NumberRevDate: SheetofReviewerDesignerDepartmentProject
Page TitleCCBU D114 257Tuesday, August 29, 2023<project_name><Designer> GRANDTETON_SWB_20230829114 BLANK<Reviewer>



5
5
4
4
3
3
2
2
1
1
D D
C C
B B
A A
DESIGN NOTE:DEBUG MODE JUMPER1-2     DEBUG MODE OFF2-3     DEBUG MODE ON
DESIGN NOTE:FPGA_FORCE_POWER_ON1-2     NORMAL2-3     FPGA FORCE POWER ON
CAD NOTEP3V3_LED at least 20 mil.
LED Debug PurposeJumper(1-2) : Enable LEDJumper(2-3) : Disable LED
FPGA_1
DVT_CHANGEDVT_CHANGE
RST_MB_PERST_0_ISO_R_N[129]RST_MB_PERST_1_ISO_R_N[129]RST_MB_PERST_2_ISO_R_N[129]MB_SWB_PWR_EN_ISO_R[129]MB_SWB_PWRGD[129]RST_GPU_PERST_0_N[115]RST_GPU_PERST_1_N[115]RST_GPU_PERST_2_N[115]PRSNT_GPU_ISO_R1_N[124]SYS_PWR_READY_R_N[88,115]JP_FPGA_DEBUG_N[115]JP_FPGA_FRC_PWRON_N[115]JP_FPGA_LED[115]FPGA_HEARTBEAT_N[118]FM_SOL_UART_CH_SEL[212]SMB_PEX0_FPGA_SCL[16]SMB_PEX0_FPGA_SDA[16]PRSNT_SSD0_R_N[86,194,202]PWRGD_P12V_SSD0_R[236,244]PWRGD_P3V3_SSD0_R[101,239,250]SSD0_PWR_EN_R[117,236,244]SSD0_PWRDIS_R[194]RST_SSD0_PERST_R_N[194]SSD0_CLK_EN_R_N[80]PRSNT_SSD1_R_N[86,194,202]PWRGD_P12V_SSD1_R[236,244]PWRGD_P3V3_SSD1_R[101,239,250]SSD1_PWR_EN_R[117,236,244]SSD1_PWRDIS_R[194]RST_SSD1_PERST_R_N[194]SSD1_CLK_EN_R_N[80]PRSNT_SSD3_R_N [86,195,202]PWRGD_P12V_SSD3_R [236,244]PWRGD_P3V3_SSD3_R [101,239,250]SSD3_PWR_EN_R [117,236,244]SSD3_PWRDIS_R [195]RST_SSD3_PERST_R_N [195]SSD3_CLK_EN_R_N [80]PRSNT_SSD4_R_N [86,196,202]PWRGD_P12V_SSD4_R [236,245]PWRGD_P3V3_SSD4_R [101,239,251]SSD4_PWR_EN_R [117,236,245]SSD4_PWRDIS_R [196]RST_SSD4_PERST_R_N [196]SSD4_CLK_EN_R_N [80]PRSNT_SSD5_R_N [86,196,202]PWRGD_P12V_SSD5_R [236,245]PWRGD_P3V3_SSD5_R [101,239,251]SSD5_PWR_EN_R [117,236,245]SSD5_PWRDIS_R [196]RST_SSD5_PERST_R_N [196]SSD5_CLK_EN_R_N [80]PRSNT_SSD6_R_N [86,197,202]PWRGD_P12V_SSD6_R [236,245]PWRGD_P3V3_SSD6_R [101,239,251]SSD6_PWR_EN_R [117,236,245]SSD6_PWRDIS_R [197]RST_SSD6_PERST_R_N [197]SSD6_CLK_EN_R_N [80]PRSNT_SSD7_R_N [86,197,202]PWRGD_P12V_SSD7_R [236,245]PWRGD_P3V3_SSD7_R [101,239,251]SSD7_PWR_EN_R [117,236,245]SSD7_PWRDIS_R [197]RST_SSD7_PERST_R_N [197]SSD7_CLK_EN_R_N [80]JP_FPGA_FRC_PWRON_N [115]SMB_PEX1_FPGA_SCL[29]SMB_PEX1_FPGA_SDA[29]SMB_PEX2_FPGA_SCL[42]SMB_PEX2_FPGA_SDA[42]SMB_PEX3_FPGA_SCL[55]SMB_PEX3_FPGA_SDA[55]BIC_FORCE_THROTTLE_R_N [86]JP_FPGA_LED [115]JP_FPGA_DEBUG_N [115]RST_GPU_PERST_0_N[115]RST_GPU_PERST_0_BUF_R_N [128]RST_GPU_PERST_1_N[115]RST_GPU_PERST_1_BUF_R_N [126]RST_GPU_PERST_2_N[115]RST_GPU_PERST_2_BUF_R_N [124]SYS_PWR_READY_R_N[88,115]
SMB_MB_R_SCL [138,211]SMB_MB_R_SDA [138,211]SMB_BIC_FPGA_R_SCL [87]SMB_BIC_FPGA_R_SDA [87]SMB_FPGA_ALERT_R_N [88]BIC_SYS_READY_R2_N [132]PRSNT_SSD2_R_N[86,195,202]PWRGD_P12V_SSD2_R[236,244]PWRGD_P3V3_SSD2_R[101,239,250]SSD2_PWR_EN_R[117,236,244]SSD2_PWRDIS_R[195]RST_SSD2_PERST_R_N[195]SSD2_CLK_EN_R_N[80]P3V3_AUXP3V3_AUXP3V3_LEDP3V3_AUXP3V3_AUXP3V3_AUXP3V3_AUXP3V3_AUX
SizeDoc NumberRevDate: SheetofReviewerDesignerDepartmentProject
Page TitleCCBU D115 257Tuesday, August 29, 2023<project_name><Designer> GRANDTETON_SWB_20230829115 FPGA_1<Reviewer>SizeDoc NumberRevDate: SheetofReviewerDesignerDepartmentProject
Page TitleCCBU D115 257Tuesday, August 29, 2023<project_name><Designer> GRANDTETON_SWB_20230829115 FPGA_1<Reviewer>SizeDoc NumberRevDate: SheetofReviewerDesignerDepartmentProject
Page TitleCCBU D115 257Tuesday, August 29, 2023<project_name><Designer> GRANDTETON_SWB_20230829115 FPGA_1<Reviewer>
R3586 0 5% R0402-0201R3580 0 5% R0402-0201R3541 0 5% R0402-0201
R18634.7KR0402-02015%NIJ56_12<Part Number>1 R3583 0 5% R0402-0201R3564 0 5% R0402-0201
R6174 4.7KR0402-02015%R40474.7KR0402-02011%1/16WJ55_12<Part Number>1 R3566 0 5% R0402-0201BANK 03/7LCMXO3LF-9400C-5BG484CU6CPT43B||R_GPLLCB21PT43A||R_GPLLTA20PT41BB19PT41AA18PT31BF14PT31AG14PT28BF12PT28AG12PT27D||SDA||PCLKC0_0A12PT27C||SCL||PCLKT0_0B12PT44B||R_GPLLCB22PT44A||R_GPLLTA21PT23B||PCLKC0_1A10PT23A||PCLKT0_1B10PT15BD8PT9DF7PT9B||L_GPLLCA2PT9CE6PT9A||L_GPLLTB1PT15AC8PT11AB3PT11BA4PT22AF10PT22BE10PT11CF8PT11DG8PT10AB2PT10BA3PT10CC3PT10DC4PT12AB4PT12BA5PT12CD5PT12DC5PT13AB5PT13BA6PT13CD6PT13DE7PT14AB6PT14BA7PT14CC6PT14DD7PT20AB8PT20BA8PT20CC9PT20DD9PT21AB9PT21BA9PT21CF9PT21DG9PT23CG11PT23DF11PT24AB11PT24BA11PT24CE11PT24DD11PT27AD12PT27BE12PT28CE13PT28DF13PT29AA13PT29BB13PT29CC13PT29DD13PT30AA14PT30BB14PT30CC14PT30DD14PT38AA15PT38BB15PT38CC15PT38DD15PT39AA16PT39BB17PT39CC17PT39DD16PT40AA17PT40BB18PT40CE16PT40DD17PT41CC18PT41DD18PT42AA19PT42BB20PT42CF15PT42DG15PT43CC19PT43DC20R3555 0 5% R0402-0201
U309CSN74LVC3G34DCTR6284
R58934.7KR0402-02011%1/16WJ55SCONN3_TSM-103-01-S-SV-TR123
R5646 33 R0402-0201
J56SCONN3_TSM-103-01-S-SV-TR123 R3568 0 5% R0402-0201
C27480.1UF10%16VC0402-0201R186833 R0402-02011%U309BSN74LVC3G34DCTR3584
R3570 0 5% R0402-0201R3549 0 5% R0402-0201R3521 0 5% R0402-0201R5647 33 R0402-0201
R1869 33 R0402-02011%R18584.7KR0402-02015%NIR3594 0 5% R0402-0201R3546 51 5% R0402-0201R3592 0 5% R0402-0201R3552 0 5% R0402-0201
R186633 R0402-02011%J57_12<Part Number>1U309ASN74LVC3G34DCTR1784
R3523 0 5% R0402-0201
R18594.7KR0402-02015%NIR3596 0 5% R0402-0201R3593 0 5% R0402-0201R3554 0 5% R0402-0201R5891 33 R0402-0201R1867 33 R0402-02011%
R3581 0 5% R0402-0201J57SCONN3_TSM-103-01-S-SV-TR123R186433 R0402-02011%R18604.7KR0402-02015%NIR3595 0 5% R0402-0201R3598 0 5% R0402-0201R3556 0 5% R0402-0201R3535 0 5% R0402-0201R3582 0 5% R0402-0201R3525 0 5% R0402-0201
R6176 4.7KR0402-02015%
R3540 0 5% R0402-0201
R1865 33 R0402-02011%R3597 0 5% R0402-0201R3576 0 5% R0402-0201R3599 0 5% R0402-0201R3537 0 5% R0402-0201
R18614.7KR0402-02015%NIR3584 0 5% R0402-0201R3578 0 5% R0402-0201R3539 0 5% R0402-0201
R18624.7KR0402-02015%NI
R3527 0 5% R0402-0201
R6175 4.7KR0402-02015%R62831KR0402-02011%1/16W
RST_MB_PERST_2_ISO_R_NMB_SWB_PWR_EN_ISO_RRST_GPU_PERST_0_NRST_GPU_PERST_1_NRST_GPU_PERST_2_NFPGA_HEARTBEAT_NRST_MB_PERST_0_ISO_R_NRST_MB_PERST_1_ISO_R_NMB_SWB_PWRGDPRSNT_GPU_ISO_R1_NSYS_PWR_READY_NJP_FPGA_DEBUG_NJP_FPGA_FRC_PWRON_NJP_FPGA_LED_NFM_SOL_UART_CH_SEL_RSMB_PEX0_FPGA_SCLSMB_PEX0_FPGA_SDASMB_PEX1_FPGA_SCLSMB_PEX1_FPGA_SDASMB_PEX2_FPGA_SCLSMB_PEX2_FPGA_SDASMB_PEX3_FPGA_SCLSMB_PEX3_FPGA_SDAPRSNT_SSD0_R_NPWRGD_P12V_SSD0_RPWRGD_P3V3_SSD0_RSSD0_PWR_ENSSD0_PWRDISRST_SSD0_PERST_NSSD0_CLK_EN_NPRSNT_SSD1_R_NPWRGD_P12V_SSD1_RPWRGD_P3V3_SSD1_RSSD1_PWR_ENSSD1_PWRDISRST_SSD1_PERST_NSSD1_CLK_EN_NPRSNT_SSD3_R_NPWRGD_P12V_SSD3_RPWRGD_P3V3_SSD3_RSSD3_PWR_ENSSD3_PWRDISRST_SSD3_PERST_NSSD3_CLK_EN_NPRSNT_SSD4_R_NPWRGD_P12V_SSD4_RSSD4_PWRDISRST_SSD4_PERST_NSSD4_CLK_EN_NPRSNT_SSD5_R_NPWRGD_P12V_SSD5_RPWRGD_P3V3_SSD5_RSSD5_PWR_ENSSD5_PWRDISRST_SSD5_PERST_NSSD5_CLK_EN_NPRSNT_SSD6_R_NPWRGD_P12V_SSD6_RPWRGD_P3V3_SSD6_RSSD6_PWR_ENSSD6_PWRDISRST_SSD6_PERST_NPWRGD_P3V3_SSD4_RSSD4_PWR_ENSSD6_CLK_EN_NPRSNT_SSD7_R_NPWRGD_P12V_SSD7_RPWRGD_P3V3_SSD7_RSSD7_PWR_ENSSD7_PWRDISRST_SSD7_PERST_NSSD7_CLK_EN_NBIC_FORCE_THROTTLE_R_NRST_GPU_PERST_0_R_NRST_GPU_PERST_0_BUF_NRST_GPU_PERST_0_BUF_R_NRST_GPU_PERST_1_R_NRST_GPU_PERST_1_BUF_NRST_GPU_PERST_1_BUF_R_NRST_GPU_PERST_2_R_NRST_GPU_PERST_2_BUF_NRST_GPU_PERST_2_BUF_R_N
SMB_MB_BMC_ISO_FPGA_SCLSMB_MB_BMC_ISO_FPGA_SDASMB_BIC_FPGA_R_SCLSMB_BIC_FPGA_R_SDASMB_FPGA_ALERT_NBIC_SYS_READY_R2_NPRSNT_SSD2_R_NPWRGD_P12V_SSD2_RPWRGD_P3V3_SSD2_RSSD2_PWR_ENSSD2_PWRDISRST_SSD2_PERST_NSSD2_CLK_EN_N



5
5
4
4
3
3
2
2
1
1
D D
C C
B B
A A
FPGA_2
DVT_CHANGE DVT_CHANGE
PVT_CHANGEPVT2_BOM_CHANGEPVT2_BOM_CHANGEPRSNT_NIC0_R_N[86,170]PWRGD_P12V_NIC0_R[170,235,242]PWRGD_P3V3_NIC0_R[238,248]NIC0_AUX_PWR_EN[168]PWRGD_NIC0_PWR_GOOD_R[168]NIC0_MAIN_PWR_EN[168]RST_NIC0_PERST_R_N[170]NIC0_CLK_EN_R_N[79]PRSNT_NIC1_R_N[86,173]PWRGD_P12V_NIC1_R[173,235,242]PWRGD_P3V3_NIC1_R[238,248]NIC1_AUX_PWR_EN[171]PWRGD_NIC1_PWR_GOOD_R[171]NIC1_MAIN_PWR_EN[171]RST_NIC1_PERST_R_N[173]NIC1_CLK_EN_R_N[79]PRSNT_NIC2_R_N[86,176]PWRGD_P12V_NIC2_R[176,235,242]PWRGD_P3V3_NIC2_R[238,248]NIC2_AUX_PWR_EN[174]PWRGD_NIC2_PWR_GOOD_R[174]NIC2_MAIN_PWR_EN[174]RST_NIC2_PERST_R_N[176]NIC2_CLK_EN_R_N[79]PRSNT_NIC3_R_N[86,179]PWRGD_P12V_NIC3_R[179,235,242]PWRGD_P3V3_NIC3_R[238,248]NIC3_AUX_PWR_EN[177]PWRGD_NIC3_PWR_GOOD_R[177]NIC3_MAIN_PWR_EN[177]RST_NIC3_PERST_R_N[179]NIC3_CLK_EN_R_N[79]PRSNT_NIC4_R_N[86,182]PWRGD_P12V_NIC4_R[182,235,243]PWRGD_P3V3_NIC4_R[238,249]NIC4_AUX_PWR_EN[180]PWRGD_NIC4_PWR_GOOD_R[180]NIC4_MAIN_PWR_EN[180]RST_NIC4_PERST_R_N[182]NIC4_CLK_EN_R_N[79]PRSNT_NIC5_R_N[86,185]PWRGD_P12V_NIC5_R[185,235,243]PWRGD_P3V3_NIC5_R[238,249]NIC5_AUX_PWR_EN[183]PWRGD_NIC5_PWR_GOOD_R[183]NIC5_MAIN_PWR_EN[183]RST_NIC5_PERST_R_N[185]NIC5_CLK_EN_R_N[79]NIC6_AUX_PWR_EN [186]PWRGD_NIC6_PWR_GOOD_R [186]NIC6_MAIN_PWR_EN [186]RST_NIC6_PERST_R_N [188]NIC6_CLK_EN_R_N [79]PRSNT_NIC7_R_N [86,191]PWRGD_P12V_NIC7_R [191,235,243]PWRGD_P3V3_NIC7_R [238,249]NIC7_AUX_PWR_EN [189]PWRGD_NIC7_PWR_GOOD_R [189]NIC7_MAIN_PWR_EN [189]RST_NIC7_PERST_R_N [191]NIC7_CLK_EN_R_N [79]PRSNT_NIC0_FPGA_R_N [72]NIC0_PEX_PWR_EN_R [72]RST_PEX_NIC0_PERST_R_N [72]NIC0_MAIN_PWR_BIC_EN_R [86]PRSNT_NIC1_FPGA_R_N [72]NIC1_PEX_PWR_EN_R [72]RST_PEX_NIC1_PERST_R_N [72]NIC1_MAIN_PWR_BIC_EN_R [86]PRSNT_NIC2_FPGA_R_N [73]NIC2_PEX_PWR_EN_R [73]RST_PEX_NIC2_PERST_R_N [73]NIC2_MAIN_PWR_BIC_EN_R [86]PRSNT_NIC3_FPGA_R_N [73]NIC3_PEX_PWR_EN_R [73]RST_PEX_NIC3_PERST_R_N [73]NIC3_MAIN_PWR_BIC_EN_R [86]PRSNT_NIC4_FPGA_R_N [74]NIC4_PEX_PWR_EN_R [74]RST_PEX_NIC4_PERST_R_N [74]NIC4_MAIN_PWR_BIC_EN_R [86]PRSNT_NIC5_FPGA_R_N [74]NIC5_PEX_PWR_EN_R [74]RST_PEX_NIC5_PERST_R_N [74]NIC5_MAIN_PWR_BIC_EN_R [86]PRSNT_NIC6_R_N [86,188]PWRGD_P12V_NIC6_R [188,235,243]PWRGD_P3V3_NIC6_R [238,249]
RST_FPGA_BIC_N[116]RST_FPGA_BIC_R_N [92]RST_FPGA_BIC_N [116]RST_FT4232_R_N [64,65,122,123]PWRGD_P1V2_AUX_FPGA_R [92]RST_MB_BIC_ISO_R_N [92,132]PWRGD_PEX0_P1V8_PLL_R [217]PWRGD_PEX1_P1V8_PLL_R [217]PWRGD_PEX2_P1V8_PLL_R [218]PWRGD_PEX3_P1V8_PLL_R [218]P3V3_AUX
SizeDoc NumberRevDate: SheetofReviewerDesignerDepartmentProject
Page TitleCCBU D116 257Tuesday, August 29, 2023<project_name><Designer> GRANDTETON_SWB_20230829116 FPGA_2<Reviewer>SizeDoc NumberRevDate: SheetofReviewerDesignerDepartmentProject
Page TitleCCBU D116 257Tuesday, August 29, 2023<project_name><Designer> GRANDTETON_SWB_20230829116 FPGA_2<Reviewer>SizeDoc NumberRevDate: SheetofReviewerDesignerDepartmentProject
Page TitleCCBU D116 257Tuesday, August 29, 2023<project_name><Designer> GRANDTETON_SWB_20230829116 FPGA_2<Reviewer>
R4092 0 5% R0402-0201R4091 33 R0402-02011%R3632 33 R0402-02011%R4093 0 5% R0402-0201R3604 22 1% R0402-0201R5774 0 5% R0402-0201R3615 22 1% R0402-0201R3605 33 R0402-02011%R3640 33 R0402-02011%BANK 17/7LCMXO3LF-9400C-5BG484CU6GPR30BW20PR30AV18PR29DV19PR29BY21PR29CU17PR29AAA22PR25BW22PR25AV22PR20BR21PR20AR22PR19BP21PR19AN22PR17B||PCLKC1_0M21PR17A||PCLKT1_0M22PR16BL21PR16AK22PR14BL16PR14AL17PR7BH21PR7AH22PR3B||R_GPLLC_IND21PR3A||R_GPLLT_IND22PR2B||R_GPLLC_FBC22PR2A||R_GPLLT_FBC21PR2CF17PR2DG16PR3CD19PR3DD20PR4CE19PR4DE20PR4AE22PR4BE21PR5AF22PR5BG22PR5CF18PR5DF19PR6AG21PR6BG20PR6CG19PR6DG18PR7CG17PR7DH20PR10AH19PR10BH18PR10CH17PR10DH16PR11AJ16PR11BJ17PR11CJ18PR11DJ19PR12AJ21PR12BJ22PR12CJ20PR12DK20PR13AK19PR13BK18PR13CK17PR13DK16PR14CL19PR14DL20PR16CL22PR16DM17PR17CM20PR17DM19PR18AM16PR18BN16PR18CN17PR18DN18PR19CN20PR19DN19PR20CP22PR20DP20PR21AT22PR21BT21PR21CP19PR21DP18PR24AP17PR24BP16PR24CU22PR24DU21PR25CR20PR25DR19PR26AR18PR26BR17PR26CR16PR26DT20PR27AT19PR27BT18PR27CT17PR27DU20PR28AY22PR28BW21PR28CU19PR28DU18PR30CW19PR30DY20R4094 0 5% R0402-0201R3623 22 1% R0402-0201R55031KR0402-02011%R3631 22 1% R0402-0201R3616 33 R0402-02011%R3648 33 R0402-02011%R3639 22 1% R0402-0201R4095 0 5% R0402-0201R5780 0 5% R0402-0201R3647 22 1% R0402-0201R4096 0 5% R0402-0201R4086 22 1% R0402-0201R4087 33 R0402-02011%R3624 33 R0402-02011%R2966 0 R0402-02015%R4090 22 1% R0402-0201R4097 0 5% R0402-0201PRSNT_NIC0_R_NPWRGD_P12V_NIC0_RNIC0_AUX_PWR_ENNIC0_MAIN_PWR_ENNIC1_AUX_PWR_ENNIC1_MAIN_PWR_ENNIC2_AUX_PWR_ENNIC2_MAIN_PWR_ENNIC3_AUX_PWR_ENNIC3_MAIN_PWR_ENNIC4_AUX_PWR_ENNIC4_MAIN_PWR_ENNIC5_AUX_PWR_ENNIC5_MAIN_PWR_ENPWRGD_P3V3_NIC0_RPWRGD_NIC0_PWR_GOOD_RRST_NIC0_PERST_NNIC0_CLK_EN_NPRSNT_NIC1_R_NPWRGD_P12V_NIC1_RPWRGD_P3V3_NIC1_RPWRGD_NIC1_PWR_GOOD_RRST_NIC1_PERST_NNIC1_CLK_EN_NPRSNT_NIC2_R_NPWRGD_P12V_NIC2_RPWRGD_P3V3_NIC2_RPWRGD_NIC2_PWR_GOOD_RRST_NIC2_PERST_NNIC2_CLK_EN_NPRSNT_NIC3_R_NPWRGD_P12V_NIC3_RPWRGD_P3V3_NIC3_RPWRGD_NIC3_PWR_GOOD_RRST_NIC3_PERST_NNIC3_CLK_EN_NPRSNT_NIC4_R_NPWRGD_P12V_NIC4_RPWRGD_P3V3_NIC4_RPWRGD_NIC4_PWR_GOOD_RRST_NIC4_PERST_NNIC4_CLK_EN_NPRSNT_NIC5_R_NPWRGD_P12V_NIC5_RPWRGD_P3V3_NIC5_RPWRGD_NIC5_PWR_GOOD_RRST_NIC5_PERST_NNIC5_CLK_EN_NNIC6_AUX_PWR_ENNIC6_MAIN_PWR_ENRST_NIC6_PERST_NNIC6_CLK_EN_NNIC7_AUX_PWR_ENNIC7_MAIN_PWR_ENRST_NIC7_PERST_NNIC7_CLK_EN_NPRSNT_NIC0_FPGA_NPRSNT_NIC1_FPGA_NPRSNT_NIC2_FPGA_NPRSNT_NIC3_FPGA_NPRSNT_NIC4_FPGA_NPRSNT_NIC5_FPGA_NPRSNT_NIC6_R_NPWRGD_P12V_NIC6_RPWRGD_P3V3_NIC6_RPWRGD_NIC6_PWR_GOOD_RPRSNT_NIC7_R_NPWRGD_P12V_NIC7_RPWRGD_P3V3_NIC7_RPWRGD_NIC7_PWR_GOOD_RNIC0_PEX_PWR_EN_RRST_PEX_NIC0_PERST_R_NNIC0_MAIN_PWR_BIC_EN_RNIC1_PEX_PWR_EN_RRST_PEX_NIC1_PERST_R_NNIC1_MAIN_PWR_BIC_EN_RNIC2_PEX_PWR_EN_RRST_PEX_NIC2_PERST_R_NNIC2_MAIN_PWR_BIC_EN_RNIC3_PEX_PWR_EN_RRST_PEX_NIC3_PERST_R_NNIC3_MAIN_PWR_BIC_EN_RNIC4_PEX_PWR_EN_RRST_PEX_NIC4_PERST_R_NNIC4_MAIN_PWR_BIC_EN_RNIC5_PEX_PWR_EN_RRST_PEX_NIC5_PERST_R_NNIC5_MAIN_PWR_BIC_EN_RRST_FPGA_BIC_R_NRST_FT4232_NPWRGD_P1V2_AUX_FPGARST_MB_BIC_ISO_R_NPWRGD_PEX0_P1V8_PLL_RPWRGD_PEX1_P1V8_PLL_RPWRGD_PEX2_P1V8_PLL_RPWRGD_PEX3_P1V8_PLL_R



5
5
4
4
3
3
2
2
1
1
D D
C C
B B
A A
FPGA_3
DVT_CHANGEPVT_CHANGESSD8_PWR_EN_R[117,237,246]SSD8_PWRDIS_R[198]RST_SSD8_PERST_R_N[198]SSD8_CLK_EN_R_N[81]SSD9_PWR_EN_R[117,237,246]SSD9_PWRDIS_R[198]RST_SSD9_PERST_R_N[198]SSD9_CLK_EN_R_N[81]SSD10_PWR_EN_R[117,237,246]SSD10_PWRDIS_R[199]RST_SSD10_PERST_R_N[199]SSD10_CLK_EN_R_N[81]SSD11_PWR_EN_R[117,237,246]SSD11_PWRDIS_R[199]RST_SSD11_PERST_R_N[199]SSD11_CLK_EN_R_N[81]SSD12_PWR_EN_R[117,237,247]SSD12_PWRDIS_R[200]RST_SSD12_PERST_R_N[200]SSD12_CLK_EN_R_N[81]SSD13_PWR_EN_R[117,237,247]SSD13_PWRDIS_R[200]RST_SSD13_PERST_R_N[200]SSD13_CLK_EN_R_N[81]SSD14_PWR_EN_R[117,237,247]SSD14_PWRDIS_R[201]RST_SSD14_PERST_R_N[201]SSD14_CLK_EN_R_N[81]PRSNT_SSD8_R_N[86,198,203]PWRGD_P12V_SSD8_R[237,246]PWRGD_P3V3_SSD8_R[102,240,252]PRSNT_SSD9_R_N[86,198,203]PWRGD_P12V_SSD9_R[237,246]PWRGD_P3V3_SSD9_R[102,240,252]PRSNT_SSD10_R_N[86,199,203]PWRGD_P12V_SSD10_R[237,246]PWRGD_P3V3_SSD10_R[102,240,252]PRSNT_SSD11_R_N[86,199,203]PWRGD_P12V_SSD11_R[237,246]PWRGD_P3V3_SSD11_R[102,240,252]PRSNT_SSD12_R_N[86,200,203]PWRGD_P12V_SSD12_R[237,247]PWRGD_P3V3_SSD12_R[102,240,253]PRSNT_SSD13_R_N[86,200,203]PWRGD_P12V_SSD13_R[237,247]PWRGD_P3V3_SSD13_R[102,240,253]PRSNT_SSD14_R_N[86,201,203]PWRGD_P12V_SSD14_R[237,247]PWRGD_P3V3_SSD14_R[102,240,253]PRSNT_SSD15_R_N [86,201,203]PWRGD_P12V_SSD15_R [237,247]PWRGD_P3V3_SSD15_R [102,240,253]SSD0_PEX_PWR_EN_R [72]RST_PEX_SSD0_PERST_R_N [72]SSD0_PWRDIS_BIC_R [86]SSD1_PEX_PWR_EN_R [72]RST_PEX_SSD1_PERST_R_N [72]SSD1_PWRDIS_BIC_R [86]SSD2_PEX_PWR_EN_R [72]RST_PEX_SSD2_PERST_R_N [72]SSD2_PWRDIS_BIC_R [86]SSD3_PEX_PWR_EN_R [72]RST_PEX_SSD3_PERST_R_N [72]SSD3_PWRDIS_BIC_R [86]SSD4_PEX_PWR_EN_R [73]RST_PEX_SSD4_PERST_R_N [73]SSD4_PWRDIS_BIC_R [86]SSD5_PEX_PWR_EN_R [73]RST_PEX_SSD5_PERST_R_N [73]SSD5_PWRDIS_BIC_R [86]SSD6_PEX_PWR_EN_R [73]RST_PEX_SSD6_PERST_R_N [73]SSD15_PWR_EN_R [117,237,247]SSD15_PWRDIS_R [201]RST_SSD15_PERST_R_N [201]SSD15_CLK_EN_R_N [81]PRSNT_SSD0_FPGA_R_N [72]PRSNT_SSD1_FPGA_R_N [72]PRSNT_SSD2_FPGA_R_N [72]PRSNT_SSD3_FPGA_R_N [72]PRSNT_SSD4_FPGA_R_N [73]PRSNT_SSD5_FPGA_R_N [73]PRSNT_SSD6_FPGA_R_N [73]RST_SMB_FPGA_R_N[87]FM_PFR_LED_AMBER_R[211]FM_PFR_LED_BLUE_R[211]SSD6_PWRDIS_BIC_R [86]PU_FPGA_SN [117]PU_FPGA_SN[117]FPGA_PEX0_MODE_SEL2_R [121]FPGA_PEX0_MODE_SEL1_R [121]FPGA_PEX1_MODE_SEL2_R [121]FPGA_PEX1_MODE_SEL1_R [121]FPGA_PEX2_MODE_SEL2_R [121]FPGA_PEX2_MODE_SEL1_R [121]FPGA_PEX3_MODE_SEL2_R [121]FPGA_PEX3_MODE_SEL1_R [121]SSD0_PWR_EN_R[115,236,244]SSD1_PWR_EN_R[115,236,244]SSD2_PWR_EN_R[115,236,244]SSD3_PWR_EN_R[115,236,244]SSD4_PWR_EN_R[115,236,245]SSD5_PWR_EN_R[115,236,245]SSD6_PWR_EN_R[115,236,245]SSD7_PWR_EN_R[115,236,245]SSD8_PWR_EN_R[117,237,246]SSD9_PWR_EN_R[117,237,246]SSD10_PWR_EN_R[117,237,246]SSD11_PWR_EN_R[117,237,246]SSD12_PWR_EN_R[117,237,247]SSD13_PWR_EN_R[117,237,247]SSD14_PWR_EN_R[117,237,247]SSD15_PWR_EN_R[117,237,247]P3V3_FPGA_VCCIO2
SizeDoc NumberRevDate: SheetofReviewerDesignerDepartmentProject
Page TitleCCBU D117 257Tuesday, August 29, 2023<project_name><Designer> GRANDTETON_SWB_20230829117 FPGA_3<Reviewer>SizeDoc NumberRevDate: SheetofReviewerDesignerDepartmentProject
Page TitleCCBU D117 257Tuesday, August 29, 2023<project_name><Designer> GRANDTETON_SWB_20230829117 FPGA_3<Reviewer>SizeDoc NumberRevDate: SheetofReviewerDesignerDepartmentProject
Page TitleCCBU D117 257Tuesday, August 29, 2023<project_name><Designer> GRANDTETON_SWB_20230829117 FPGA_3<Reviewer>
R4151 0 5% R0402-0201NIR4132 0 5% R0402-0201R6416 0 5% R0402-0201R4141 0 5% R0402-0201R4117 0 5% R0402-0201R6423 0 5% R0402-0201R4146 0 5% R0402-0201R58031KR0402-02011%R683410K1/16W1%R0402-0201
R4133 0 5% R0402-0201R4142 0 5% R0402-0201R4127 0 5% R0402-0201R6421 0 5% R0402-0201R4152 0 5% R0402-0201NI
R683510K1/16W1%R0402-0201
R4134 0 5% R0402-0201
R682610K1/16W1%R0402-0201
R4118 0 5% R0402-0201R4147 0 5% R0402-0201NIR4128 0 5% R0402-0201
R683610K1/16W1%R0402-0201
R4137 0 5% R0402-0201
R682710K1/16W1%R0402-0201
R6419 0 5% R0402-0201R4129 0 5% R0402-0201R4153 0 5% R0402-0201NIR4123 0 5% R0402-0201
R683710K1/16W1%R0402-0201
R4138 0 5% R0402-0201R4148 0 5% R0402-0201NI
R682810K1/16W1%R0402-0201
R4130 0 5% R0402-0201R4143 0 5% R0402-0201R5779 0 5% R0402-0201R4124 0 5% R0402-0201R6417 0 5% R0402-0201
R683810K1/16W1%R0402-0201
BANK 22/7LCMXO3LF-9400C-5BG484CU6BPB5AAA2PB5BAB2PB5CV6PB5DU6PB7A||CSSPINAA3PB7BAB3PB7CY4PB7DW5PB8CU7PB8DT8PB8AAA4PB8BAB4PB10AAA5PB10BAB5PB10CY5PB10DY6PB13CV8PB13DU8PB16A||MCLK||CCLKT9PB16B||SO||SPISOU9PB18AAA8PB18BAB8PB21AV10PB21BW10PB22A||PCLKT2_0AA10PB22B||PCLKC2_0AB10PB24AAA11PB24BAB11PB24CV11PB24DY11PB29A||PCLKT2_1AB12PB29B||PCLKC2_1AA12PB30AAB13PB30BAA13PB33AAB14PB33BAA14PB43AAB19PB43BAA19PB44AAB20PB44BAA20PB46A||SNAB21PB46B||SI||SISPIAA21PB35AAB15PB35BAA15PB11AAA6PB11BAB6PB11CW6PB11DV7PB13AAA7PB13BAB7PB16CV9PB16DW8PB18CY8PB18DW9PB19AAA9PB19BAB9PB19CT10PB19DU10PB22CT11PB22DU11PB27AY12PB27BT12PB27CU12PB27DV12PB29CV13PB29DU13PB30CY13PB30DW13PB33CY14PB33DW14PB32AT13PB32BT14PB32CU14PB32DV14PB35CY15PB35DW15PB38AAB16PB38BAA16PB38CV15PB38DU15PB40AAB17PB40BAA17PB40CY17PB40DV16PB41AAB18PB41BAA18PB41CY18PB41DW17PB43CT15PB43DU16PB44CY19PB44DW18PB46CV17PB46DT16PB21CY9PB21DY10
R682910K1/16W1%R0402-0201
R4125 0 5% R0402-0201R4149 0 5% R0402-0201NIR6422 0 5% R0402-0201R4119 0 5% R0402-0201
R683910K1/16W1%R0402-0201
R4115 0 5% R0402-0201
R683010K1/16W1%R0402-0201
R4144 0 5% R0402-0201R4135 0 5% R0402-0201R4126 0 5% R0402-0201R4120 0 5% R0402-0201
R684010K1/16W1%R0402-0201
R6420 0 5% R0402-0201
R683110K1/16W1%R0402-0201
R4136 0 5% R0402-0201R4150 0 5% R0402-0201NIR4121 0 5% R0402-0201R4139 0 5% R0402-0201R4116 0 5% R0402-0201
R684110K1/16W1%R0402-0201
R4145 0 5% R0402-0201
R683210K1/16W1%R0402-0201
R6418 0 5% R0402-0201R4131 0 5% R0402-0201R4122 0 5% R0402-0201R4140 0 5% R0402-0201R5778 0 5% R0402-0201R683310K1/16W1%R0402-0201
PRSNT_SSD8_R_NPWRGD_P12V_SSD8_RPWRGD_P3V3_SSD8_RSSD8_PWR_ENSSD8_PWRDISRST_SSD8_PERST_NSSD8_CLK_EN_NPRSNT_SSD9_R_NPWRGD_P12V_SSD9_RPWRGD_P3V3_SSD9_RSSD9_PWR_ENSSD9_PWRDISRST_SSD9_PERST_NSSD9_CLK_EN_NPRSNT_SSD10_R_NPWRGD_P12V_SSD10_RPWRGD_P3V3_SSD10_RSSD10_PWR_ENSSD10_PWRDISRST_SSD10_PERST_NSSD10_CLK_EN_NPRSNT_SSD11_R_NPWRGD_P12V_SSD11_RPWRGD_P3V3_SSD11_RSSD11_PWR_ENSSD11_PWRDISRST_SSD11_PERST_NSSD11_CLK_EN_NPRSNT_SSD12_R_NPWRGD_P12V_SSD12_RPWRGD_P3V3_SSD12_RSSD12_PWR_ENSSD12_PWRDISRST_SSD12_PERST_NSSD12_CLK_EN_NPRSNT_SSD13_R_NPWRGD_P12V_SSD13_RPWRGD_P3V3_SSD13_RSSD13_PWR_ENSSD13_PWRDISRST_SSD13_PERST_NSSD13_CLK_EN_NPRSNT_SSD14_R_NPWRGD_P12V_SSD14_RPWRGD_P3V3_SSD14_RSSD14_PWR_ENSSD14_PWRDISRST_SSD14_PERST_NSSD14_CLK_EN_NPRSNT_SSD15_R_NPWRGD_P12V_SSD15_RPWRGD_P3V3_SSD15_RSSD15_PWR_ENSSD15_PWRDISRST_SSD15_PERST_NSSD15_CLK_EN_NPRSNT_SSD0_FPGA_NSSD0_PEX_PWR_EN_RRST_PEX_SSD0_PERST_R_NSSD0_PWRDIS_BIC_RPRSNT_SSD1_FPGA_NSSD1_PEX_PWR_EN_RRST_PEX_SSD1_PERST_R_NSSD1_PWRDIS_BIC_RPRSNT_SSD2_FPGA_NSSD2_PEX_PWR_EN_RRST_PEX_SSD2_PERST_R_NSSD2_PWRDIS_BIC_RPRSNT_SSD3_FPGA_NSSD3_PEX_PWR_EN_RRST_PEX_SSD3_PERST_R_NSSD3_PWRDIS_BIC_RPRSNT_SSD4_FPGA_NSSD4_PEX_PWR_EN_RRST_PEX_SSD4_PERST_R_NSSD4_PWRDIS_BIC_RPRSNT_SSD5_FPGA_NSSD5_PEX_PWR_EN_RRST_PEX_SSD5_PERST_R_NSSD5_PWRDIS_BIC_RPRSNT_SSD6_FPGA_NSSD6_PEX_PWR_EN_RRST_PEX_SSD6_PERST_R_NSSD14_CLK_EN_R_NRST_SSD14_PERST_R_NRST_SSD13_PERST_R_NSSD13_CLK_EN_R_NSSD13_PWR_EN_RSSD13_PWRDIS_RSSD14_PWR_EN_RSSD14_PWRDIS_RSSD12_PWR_EN_RSSD12_PWRDIS_RRST_SSD12_PERST_R_NSSD12_CLK_EN_R_NSSD11_PWR_EN_RSSD11_PWRDIS_RRST_SSD11_PERST_R_NSSD11_CLK_EN_R_NSSD10_PWR_EN_RSSD10_PWRDIS_RRST_SSD10_PERST_R_NSSD10_CLK_EN_R_NSSD9_PWR_EN_RSSD9_PWRDIS_RRST_SSD9_PERST_R_NSSD9_CLK_EN_R_NSSD8_PWR_EN_RSSD8_PWRDIS_RRST_SSD8_PERST_R_NSSD8_CLK_EN_R_NSSD15_PWR_EN_RSSD15_PWRDIS_RRST_SSD15_PERST_R_NSSD15_CLK_EN_R_NPRSNT_SSD0_FPGA_R_NPRSNT_SSD1_FPGA_R_NPRSNT_SSD2_FPGA_R_NPRSNT_SSD3_FPGA_R_NPRSNT_SSD4_FPGA_R_NPRSNT_SSD5_FPGA_R_NPRSNT_SSD6_FPGA_R_NRST_SMB_FPGA_R_NFM_PFR_LED_AMBER_RFM_PFR_LED_AMBERFM_PFR_LED_BLUE_RFM_PFR_LED_BLUESSD6_PWRDIS_BIC_RPU_FPGA_SNPU_FPGA_SNFPGA_PEX0_MODE_SEL2FPGA_PEX0_MODE_SEL2_RFPGA_PEX0_MODE_SEL1FPGA_PEX0_MODE_SEL1_RFPGA_PEX1_MODE_SEL2FPGA_PEX1_MODE_SEL2_RFPGA_PEX1_MODE_SEL1FPGA_PEX1_MODE_SEL1_RFPGA_PEX2_MODE_SEL2FPGA_PEX2_MODE_SEL2_RFPGA_PEX2_MODE_SEL1FPGA_PEX2_MODE_SEL1_RFPGA_PEX3_MODE_SEL2FPGA_PEX3_MODE_SEL2_RFPGA_PEX3_MODE_SEL1FPGA_PEX3_MODE_SEL1_R



5
5
4
4
3
3
2
2
1
1
D D
C C
B B
A A
PLACE ALL RS RESISTORS WITHIN 0.5 INCHES FROM OSC.CLK PIN LENGHT MATCH MAIN AND DEBUG PLD CLOCK +/- 25 MILS
FPGA_4
DVT_CHANGESSD7_PEX_PWR_EN_R[73]PRSNT_SSD7_FPGA_R_N[73]RST_PEX_SSD7_PERST_R_N[73]SSD7_PWRDIS_BIC_R[86]PRSNT_SSD8_FPGA_R_N[74]SSD8_PEX_PWR_EN_R[74]RST_PEX_SSD8_PERST_R_N[74]SSD8_PWRDIS_BIC_R[86]PRSNT_SSD9_FPGA_R_N[74]SSD9_PEX_PWR_EN_R[74]RST_PEX_SSD9_PERST_R_N[74]SSD9_PWRDIS_BIC_R[86]PRSNT_SSD10_FPGA_R_N[74]SSD10_PEX_PWR_EN_R[74]RST_PEX_SSD10_PERST_R_N[74]SSD10_PWRDIS_BIC_R[86] PRSNT_SSD11_FPGA_R_N [74]SSD11_PEX_PWR_EN_R [74]RST_PEX_SSD11_PERST_R_N [74]SSD11_PWRDIS_BIC_R [86]PRSNT_SSD12_FPGA_R_N [75]SSD12_PEX_PWR_EN_R [75]RST_PEX_SSD12_PERST_R_N [75]SSD12_PWRDIS_BIC_R [86]PRSNT_SSD13_FPGA_R_N [75]SSD13_PEX_PWR_EN_R [75]RST_PEX_SSD13_PERST_R_N [75]SSD13_PWRDIS_BIC_R [86]PRSNT_SSD14_FPGA_R_N[75]SSD14_PEX_PWR_EN_R[75]RST_PEX_SSD14_PERST_R_N[75]SSD14_PWRDIS_BIC_R[86]PRSNT_SSD15_FPGA_R_N[75]SSD15_PEX_PWR_EN_R[75]RST_PEX_SSD15_PERST_R_N[75]SSD15_PWRDIS_BIC_R[86]HSC_UV_R_N[86,215]HSC_D_OC_BUF_R_N[86,213,215]PRSNT_NIC6_FPGA_R_N [75]NIC6_PEX_PWR_EN_R [75]RST_PEX_NIC6_PERST_R_N [75]NIC6_MAIN_PWR_BIC_EN_R [86]PRSNT_NIC7_FPGA_R_N [75]NIC7_PEX_PWR_EN_R [75]RST_PEX_NIC7_PERST_R_N [75]NIC7_MAIN_PWR_BIC_EN_R [86]HSC_TIMER_R_N [86]SMB_ALERT_HSC_R_N [88,216]PWRGD_P12V_AUX_BUF_R[121]PWRGD_P5V_AUX_BUF_R[121]PWRGD_P3V3_AUX_BUF_R[121]PWRGD_P1V2_AUX_R[92,222]PWRGD_P3V3_R[234,241]PWRGD_P0V8_PEX0_R[223]PWRGD_P0V8_PEX1_R[223]PWRGD_P0V8_PEX2_R[226]PWRGD_P0V8_PEX3_R[226]PWRGD_P1V25_PEX0_R[229]PWRGD_P1V25_PEX1_R[230]PWRGD_P1V25_PEX2_R[231]PWRGD_P1V25_PEX3_R[232]PWRGD_P1V8_PEX_R[16,29,42,55,95,233]PWR_EN_P1V2_AUX_R[118,222]PWR_EN_P3V3_R[118,234,241]PWR_EN_PEX[118]FM_CLK_EN_R[78,79,80,81,82,83,84]RST_PEX_SYS_R_N[118]FM_SYS_THROTTLE_R[87,192]LED_POSTCODE_0 [118,212]LED_POSTCODE_1 [118,212]LED_POSTCODE_2 [118,212]LED_POSTCODE_3 [118,212]LED_POSTCODE_4 [118,212]LED_POSTCODE_5 [118,212]LED_POSTCODE_6 [118,212]LED_POSTCODE_7 [118,212]RST_PEX0_PERST_R_N [14]RST_PEX1_PERST_R_N [27]RST_PEX2_PERST_R_N [40]RST_PEX3_PERST_R_N [53]PEX0_SYS_ERR_FPGA [15]PEX1_SYS_ERR_FPGA [28]PEX2_SYS_ERR_FPGA [41]PEX3_SYS_ERR_FPGA [54]
LED_POSTCODE_0[118,212]LED_POSTCODE_1[118,212]LED_POSTCODE_2[118,212]LED_POSTCODE_3[118,212]LED_POSTCODE_4[118,212]LED_POSTCODE_5[118,212]LED_POSTCODE_6[118,212]LED_POSTCODE_7[118,212]FPGA_HEARTBEAT_N[115]RST_PEX_SYS_R_N[118]RST_PEX3_SYS_N [54]RST_PEX2_SYS_N [41]RST_PEX1_SYS_N [28]RST_PEX0_SYS_N [15]PWRGD_P3V3_AUX_R[70,121,221]PWR_EN_P1V2_AUX_R [118,222]PWR_EN_PEX_R[217,218,223,226,229,230,231,232,233]PWR_EN_PEX [118]CLK_25M_FPGA_R [118]
CLK_25M_FPGA_R [118]PWR_EN_P3V3_R[118,234,241]
MB_3V3IO_RSVD1_ISO_R[158]MB_3V3IO_RSVD3_ISO_R[158]MB_3V3IO_RSVD4_ISO_R[158]GPU_3V3IO_RSVD1_ISO_R [163]GPU_3V3IO_RSVD3_ISO_R [163]GPU_3V3IO_RSVD4_ISO_R [163]SMB_BIC_FPGA_R1_SCL[87]SMB_BIC_FPGA_R1_SDA[87] P3V3_AUXP3V3_AUXP3V3_AUXP1V8_PEXP3V3_AUXP3V3_LEDP3V3_LEDP3V3_AUXP3V3_AUXSizeDoc NumberRevDate: SheetofReviewerDesignerDepartmentProject
Page TitleCCBU D118 257Tuesday, August 29, 2023<project_name><Designer> GRANDTETON_SWB_20230829118 FPGA_4<Reviewer>SizeDoc NumberRevDate: SheetofReviewerDesignerDepartmentProject
Page TitleCCBU D118 257Tuesday, August 29, 2023<project_name><Designer> GRANDTETON_SWB_20230829118 FPGA_4<Reviewer>SizeDoc NumberRevDate: SheetofReviewerDesignerDepartmentProject
Page TitleCCBU D118 257Tuesday, August 29, 2023<project_name><Designer> GRANDTETON_SWB_20230829118 FPGA_4<Reviewer>U336SN74LVC1G07DCKRVCC5A2GND3Y4NC1R4387 0 R0402-02015%R3059 0 R0402-02015%D18 LED_BLUE<Part Number>ACD15 LED_BLUE<Part Number>ACR4168 0 5% R0402-0201
R4386 0 R0402-02015%R4157 0 5% R0402-0201NI
R6415100K1%R4388 0 R0402-02015%R3006 100 R0402-02015%
R4160 0 5% R0402-0201NIR4162 0 5% R0402-0201NIR4173 0 5% R0402-0201R3107 0 R0402-02015%R2984 49.9 R0402-02011%R4159 0 5% R0402-0201NIC36570.1UFX6SC0402-020110%25V<Part Number>R2981 49.9 R0402-02011%R2978 49.9 R0402-02011%R4161 0 5% R0402-0201NIR4389 0 R0402-02015%R4156 0 5% R0402-0201NI
R6179100K1%R6177 100K 1%
R4166 0 5% R0402-0201
R440410K1%R0402-0201<Part Number>R29874.7K5%R0402-0201NID19 LED_BLUE<Part Number>ACD16 LED_BLUE<Part Number>ACD13 LED_BLUE<Part Number>ACR6645 0 5% R0402-0201R4158 0 5% R0402-0201NI
C28420.1UF25V10%X6SU379SN74LVC1G17DCKR<Part Number>NI24531
R4171 0 5% R0402-0201
R4390 0 R0402-02015%
BANK 3BANK 4BANK 51/7LCMXO3LF-9400C-5BG484CU6APL2AD3PL2BD4PL2CF6PL2DG7PL3A||L_GPLLT_FBE4PL3B||L_GPLLC_FBF5PL3CG6PL3DH7PL4A||L_GPLLT_INC1PL4B||L_GPLLC_IND2PL4CG5PL4DH6PL5AD1PL5BE2PL5CE3PL5DF4PL13AL7PL13BK5PL13CK4PL13DK3PL14AK2PL14BK1PL16A||PCLKT4_0L1PL16B||PCLKC4_0M2PL20AP4PL20BN5PL20CN6PL20DN7PL21AR2PL21BT1PL21CP5PL21DP6PL26CT5PL26DT6PL14CL6PL14DL5PL16CL3PL16DL4PL6CG3PL6DG4PL6AE1PL6BF1PL25AT2PL25BU1PL24AR3PL24BR4PL24CR5PL24DP7PL25CR6PL25DR7PL26AT3PL26BT4PL17AM1PL17BN1PL17CM6PL17DM5PL18AN2PL18BP1PL18CN3PL18DN4PL19AP2PL19BR1PL19CP3PL19DM7PL27A||PCLKT3_0U2PL27B||PCLKC3_0V1PL27CU3PL27DU4PL28AW1PL28BW2PL28CV4PL28DU5PL29AY1PL29BAA1PL29CW3PL29DY2PL30AY3PL30BW4PL30CV5PL30DT7PL7A||PCLKT5_0G2PL7B||PCLKC5_0G1PL7CH4PL7DH3PL10AH2PL10BH1PL10CJ7PL10DJ6PL11AH5PL11BJ5PL11CJ4PL11DJ3PL12AJ2PL12BJ1PL12CK7PL12DK6
R29880R0402-02015%C28410.1UF10%16VC0402-0201R4155 0 5% R0402-0201NIR4164 0 5% R0402-0201R4174 0 5% R0402-0201
R2982 49.9 R0402-02011%R2985 49.9 R0402-02011%OSC125MHZFJ2500009<Part Number>OE1GND2OUT3VDD4 R2979 49.9 R0402-02011%R58924.7K5%R0402-0201R43844.7KR0402-02015%NI
R4169 0 5% R0402-0201
D17 LED_BLUE<Part Number>ACQ113ABSS138BKSS11G12D16D20 LED_BLUE<Part Number>ACR440533.21% R0402-0201<Part Number>D14 LED_BLUE<Part Number>ACR30670R0402-02015%NIR4154 0 5% R0402-0201NIR43854.7KR0402-02015%R4163 0 5% R0402-0201R4172 0 5% R0402-0201R4170 0 5% R0402-0201R30680R0402-02015%NIR6178 4.7K R0402-02015%
R4165 0 5% R0402-0201NI
R2983 49.9 R0402-02011%D21 LED_BLUE<Part Number>ACR2980 49.9 R0402-02011%
PWRGD_P12V_AUX_BUF_RPWRGD_P5V_AUX_BUF_RPWRGD_P3V3_AUX_BUF_RPWRGD_P1V2_AUX_RPWRGD_P3V3_RPWRGD_P0V8_PEX0_RPWRGD_P0V8_PEX1_RPWRGD_P0V8_PEX2_RPWRGD_P0V8_PEX3_RPWRGD_P1V25_PEX0_RPWRGD_P1V25_PEX1_RPWRGD_P1V25_PEX2_RPWRGD_P1V25_PEX3_RPWRGD_P1V8_PEX_RPWR_EN_P1V2_AUXPWR_EN_P3V3FM_CLK_ENRST_PEX_SYS_NFM_SYS_THROTTLEPRSNT_SSD7_FPGA_NSSD7_PEX_PWR_EN_RRST_PEX_SSD7_PERST_R_NSSD7_PWRDIS_BIC_RPRSNT_SSD8_FPGA_NSSD8_PEX_PWR_EN_RSSD8_PWRDIS_BIC_RPRSNT_SSD9_FPGA_NSSD9_PEX_PWR_EN_RRST_PEX_SSD9_PERST_R_NSSD9_PWRDIS_BIC_RPRSNT_SSD10_FPGA_NSSD10_PEX_PWR_EN_RRST_PEX_SSD10_PERST_R_NSSD10_PWRDIS_BIC_RPRSNT_SSD14_FPGA_NSSD14_PEX_PWR_EN_RRST_PEX_SSD14_PERST_R_NSSD14_PWRDIS_BIC_RRST_PEX_SSD8_PERST_R_NPRSNT_SSD15_FPGA_NSSD15_PEX_PWR_EN_RRST_PEX_SSD15_PERST_R_NSSD15_PWRDIS_BIC_RHSC_UV_R_NHSC_D_OC_BUF_R_NRST_PEX0_PERST_NRST_PEX1_PERST_NRST_PEX2_PERST_NRST_PEX3_PERST_NPEX0_SYS_ERR_FPGAPEX1_SYS_ERR_FPGAPEX2_SYS_ERR_FPGAPEX3_SYS_ERR_FPGALED_POSTCODE_0LED_POSTCODE_1LED_POSTCODE_2LED_POSTCODE_3LED_POSTCODE_4LED_POSTCODE_5LED_POSTCODE_6LED_POSTCODE_7PRSNT_SSD11_FPGA_NSSD11_PEX_PWR_EN_RRST_PEX_SSD11_PERST_R_NSSD11_PWRDIS_BIC_RPRSNT_SSD12_FPGA_NSSD12_PEX_PWR_EN_RRST_PEX_SSD12_PERST_R_NSSD12_PWRDIS_BIC_RPRSNT_SSD13_FPGA_NSSD13_PEX_PWR_EN_RRST_PEX_SSD13_PERST_R_NSSD13_PWRDIS_BIC_RPRSNT_NIC6_FPGA_NNIC6_PEX_PWR_EN_RRST_PEX_NIC6_PERST_R_NNIC6_MAIN_PWR_BIC_ENPRSNT_NIC7_FPGA_NNIC7_PEX_PWR_EN_RRST_PEX_NIC7_PERST_R_NNIC7_MAIN_PWR_BIC_ENHSC_TIMER_R_NSMB_ALERT_HSC_R_NPRSNT_SSD7_FPGA_R_NPRSNT_SSD8_FPGA_R_NPRSNT_SSD9_FPGA_R_NPRSNT_SSD10_FPGA_R_NPRSNT_SSD11_FPGA_R_NPRSNT_SSD12_FPGA_R_NPRSNT_SSD13_FPGA_R_NPRSNT_SSD14_FPGA_R_NPRSNT_SSD15_FPGA_R_NPRSNT_NIC6_FPGA_R_NPRSNT_NIC7_FPGA_R_NPWR_EN_P1V2_AUX_RPWR_EN_P3V3_RPWR_EN_PEXFM_CLK_EN_RRST_PEX_SYS_R_NFM_SYS_THROTTLE_RRST_PEX0_PERST_R_NRST_PEX1_PERST_R_NRST_PEX2_PERST_R_NRST_PEX3_PERST_R_N
LED_CONTROL_0LED_POSTCODE_R_0LED_CONTROL_1LED_POSTCODE_R_1LED_CONTROL_2LED_POSTCODE_R_2LED_CONTROL_3LED_POSTCODE_R_3LED_CONTROL_4LED_POSTCODE_R_4LED_CONTROL_5LED_POSTCODE_R_5LED_CONTROL_6LED_POSTCODE_R_6LED_CONTROL_7LED_POSTCODE_R_7FPGA_HEARTBEAT_NFPGA_HEARTBEATFPGA_DEBUG_LED_R_NFPGA_DEBUG_LEDFPGA_DEBUG_LED_NRST_PEX_SYS_BUF_NRST_PEX_SYS_BUF_R_NPWR_EN_P1V2_AUX_RPWRGD_P3V3_AUX_RPWR_EN_PEX_BUFPWR_EN_PEX_R1PWR_EN_PEX_RPWR_EN_PEXCLK_25M_FPGA_R
CLK_25M_FPGAPU_CLK_25M_FPGA_ENFM_SYS_THROTTLE
HSC_D_OC_FPGA_NSMB_BIC_FPGA_R1_SDASMB_BIC_FPGA_R1_SCL



5
5
4
4
3
3
2
2
1
1
D D
C C
B B
A A
VCCIO4
VCCIO0
VCCIO3
VCCIO5
VCC_CORE
VCCIO1
VCCIO2
FPGA_5
P3V3_FPGA_VCCIO3
P3V3_FPGA_VCCIO0P3V3_FPGA_VCCIO4P3V3_FPGA_VCCIO5P3V3_VCC_FPGA_COREP3V3_FPGA_VCCIO0P3V3_FPGA_VCCIO1P3V3_FPGA_VCCIO2P3V3_FPGA_VCCIO3P3V3_FPGA_VCCIO5P3V3_FPGA_VCCIO4P3V3_VCC_FPGA_COREP3V3_AUXP3V3_AUXP3V3_FPGA_VCCIO1P3V3_FPGA_VCCIO2P3V3_AUXP3V3_AUX
P3V3_AUXP3V3_AUXP3V3_AUX
SizeDoc NumberRevDate: SheetofReviewerDesignerDepartmentProject
Page TitleCCBU D119 257Tuesday, August 29, 2023<project_name><Designer> GRANDTETON_SWB_20230829119 FPGA_5<Reviewer>SizeDoc NumberRevDate: SheetofReviewerDesignerDepartmentProject
Page TitleCCBU D119 257Tuesday, August 29, 2023<project_name><Designer> GRANDTETON_SWB_20230829119 FPGA_5<Reviewer>SizeDoc NumberRevDate: SheetofReviewerDesignerDepartmentProject
Page TitleCCBU D119 257Tuesday, August 29, 2023<project_name><Designer> GRANDTETON_SWB_20230829119 FPGA_5<Reviewer>
C20830.01UF10%25VC20720.01UF10%25VC20740.1UFC0402_OCTAGONXA10%16VC20450.01UF10%25VC20550.01UF10%25V
C20870.01UF10%25VC20290.1UFC0402_OCTAGONXA10%16VC20840.01UF10%25VC20730.01UF10%25VC20460.01UF10%25VC20640.01UF10%25VC20560.01UF10%25V
C20880.01UF10%25VC20300.01UF10%25VC20650.01UF10%25VC20470.01UF10%25VC20570.01UF10%25VR563511%R0603_H24<Part Number>C20310.01UF10%25VC20890.01UF10%25VC207510UFC0402_OCTAGONXA20%6.3V5/7LCMXO3LF-9400C-5BG484CU6EVCC1K10VCC2K11VCC3K12VCC4K13VCC5L11VCC6L12VCC7M11VCC8M12VCC9N10VCC10N11VCC11N12VCC12N13VCCIO5_1F3VCCIO5_2J8VCCIO5_3K8VCCIO4_1L8VCCIO4_2M8VCCIO4_3M3VCCIO3_1N8VCCIO3_2P8VCCIO3_3V3VCCIO2_1R9VCCIO2_2R10VCCIO2_3R11VCCIO2_4R12VCCIO2_5R13VCCIO2_6R14VCCIO2_7W7VCCIO2_8W11VCCIO2_9W16VCCIO1_1F20VCCIO1_2J15VCCIO1_3K15VCCIO1_4L15VCCIO1_5M15VCCIO1_6M18VCCIO1_7N15VCCIO1_8P15VCCIO1_9V20VCCIO0_1C7VCCIO0_2C12VCCIO0_3C16VCCIO0_4G10VCCIO0_7H11VCCIO0_8H12VCCIO0_9H14VCCIO0_6H9VCCIO0_5G13C20660.01UF10%25VC20480.01UF10%25VC20580.01UF10%25VC203910UFC0402_OCTAGONXA20%6.3VR564111%R0603_H24<Part Number>C20320.01UF10%25V
C20760.1UFC0402_OCTAGONXA10%16V
C20490.01UF10%25VC20670.01UF10%25VC20590.01UF10%25VC20400.1UFC0402_OCTAGONXA10%16VR563711%R0603_H24<Part Number>C205010UFC0402_OCTAGONXA20%6.3VC20330.01UF10%25VR563811%R0603_H24<Part Number>
C20770.01UF10%25VC20680.01UF10%25VC20410.1UFC0402_OCTAGONXA10%16VC20600.01UF10%25V
R564011%R0603_H24<Part Number>
C20510.1UFC0402_OCTAGONXA10%16VC20340.01UF10%25V
C20780.01UF10%25VC208010UFC0402_OCTAGONXA20%6.3VC20690.01UF10%25VC206110UFC0402_OCTAGONXA20%6.3VC20420.01UF10%25VC20520.1UFC0402_OCTAGONXA10%16VC20350.01UF10%25V
C20790.01UFC0402_OCTAGONXA10%25V<Part Number>C20810.1UFC0402_OCTAGONXA10%16VC20700.01UF10%25V6/7LCMXO3LF-9400C-5BG484CU6FGND1A1GND2A22GND3B7GND4B16GND5C2GND6C11GND7E5GND8E18GND9F2GND10F21GND11H8GND12H10GND13H13GND14H15GND15J9GND16J10GND17J11GND18J12GND19J13GND20J14GND21K9GND22K14GND23K21GND24L2GND25L9GND26L10GND27L13GND28L14GND29L18GND30M4GND31M9GND32M10GND33M13GND34M14GND35N9GND36N14GND37N21GND38P9GND39P10GND40P11GND41P12GND42P13GND43P14GND44R8GND45R15GND46V2GND47V21GND48W12GND50Y16GND49Y7GND51AB1GND52AB22C20430.01UF10%25VC20620.1UFC0402_OCTAGONXA10%16VC20530.01UF10%25VC20360.01UF10%25V
R563911%R0603_H24<Part Number>C208510UFC0402_OCTAGONXA20%6.3VC203810UFC0402_OCTAGONXA20%6.3VC20820.01UF10%25VC20710.01UF10%25VC20440.01UF10%25VC20630.1UFC0402_OCTAGONXA10%16VC20540.01UF10%25VC20370.01UF10%25VR563611%R0603_H24<Part Number>C20280.1UFC0402_OCTAGONXA10%16VC20860.1UFC0402_OCTAGONXA10%16V



5
5
4
4
3
3
2
2
1
1
D D
C C
B B
A A
FPGA_JTAGENB0 :  GPIO1:   JTAG
FROM BIC UPDATE
PU FOR JTAG
FPGA_6
JTAG_FPGA_TDO [120]JTAG_FPGA_TDI [120]JTAG_FPGA_TMS [120]JTAG_FPGA_TCK [120]JTAG_BIC_EN_R[87]
JTAG_FPGA_TDI [120]JTAG_FPGA_TCK [120]JTAG_FPGA_TMS [120]FPGA_JTAGENB [120]JTAG_FPGA_TDO[120]JTAG_FPGA_TDI[120]JTAG_FPGA_TMS[120]JTAG_FPGA_TCK[120]JTAG_FPGA_TDO [120]JTAG_FPGA_TDI [120]FPGA_JTAGENB [120]JTAG_FPGA_TMS [120]JTAG_FPGA_TMS [120]
JTAG_BIC_TDO_R[87]JTAG_BIC_TDI_R[87]JTAG_BIC_TMS_R[87]JTAG_BIC_TCK_R[87]
FPGA_JTAGENB [120]JTAG_FPGA_TDO [120]
P3V3_AUX
P3V3_AUXP3V3_AUXP3V3_AUXP3V3_AUX_JTAG
SizeDoc NumberRevDate: SheetofReviewerDesignerDepartmentProject
Page TitleCCBU D120 257Tuesday, August 29, 2023<project_name><Designer> GRANDTETON_SWB_20230829120 FPGA_6<Reviewer>SizeDoc NumberRevDate: SheetofReviewerDesignerDepartmentProject
Page TitleCCBU D120 257Tuesday, August 29, 2023<project_name><Designer> GRANDTETON_SWB_20230829120 FPGA_6<Reviewer>SizeDoc NumberRevDate: SheetofReviewerDesignerDepartmentProject
Page TitleCCBU D120 257Tuesday, August 29, 2023<project_name><Designer> GRANDTETON_SWB_20230829120 FPGA_6<Reviewer>
JP2CONN8_210-HP1-080BR11122334455667788R577710K1%R0402-0201<Part Number>
R5643 0 R0402-0201R2537 33 R0402-0201 1%R2620 10K R0402-02015%NI
R4300 0 R0402-0201C24940.1UFC0402-020125VX7R10%R5644 0 R0402-0201R8754.7KR0402-02011%1/16WBANK 04/7LCMXO3LF-9400C-5BG484CU6DPT15C||TDOE8PT15D||TDIE9PT22C||TCKD10PT22D||TMSC10PT31D||PROGRAMNE15PT44C||INITNF16PT44D||DONEE17PT31C||JTAGENBE14R2621 10K R0402-02015%R4902 33 R0402-0201 1%R5645 0 R0402-0201C2811 0.1UF X7R 16V10% C0402-020174CBTLV3126U29474CBTLV3126PW2A53B81OE12OE41B32B61A2GND73A93OE104B114A124OE13VCC14R4301 0 R0402-0201
R4297 1K R0402-02011%NIC3991 10UFC060320%6.3VX6SR4298 0 R0402-0201
R2622 10K R0402-02015%R4900 33 R0402-0201 1%R4903 10K R0402-02015%R2619 10K R0402-02015%NI R6284 0 R0402-0201R4901 33 R0402-0201 1%R6411100K1% R0402-0201<Part Number>R4299 0 R0402-0201D241N5819HW12R5642 0 R0402-0201JTAG_PLD_TDOJTAG_PLD_TDIJTAG_PLD_TMSJTAG_PLD_TCK
JTAG_FPGA_R_TDOPU_FPGA_PROGRAMNTP_JTAG_PIN4JTAG_CONN_TDOJTAG_CONN_TDIJTAG_CONN_TMSJTAG_CONN_TCKTP_JTAG_PIN5JTAG_BIC_EN_RJTAG_BIC_TCK_R1JTAG_BIC_TMS_R1JTAG_BIC_TDOJTAG_BIC_TDI_R1
JTAG_FPGA_TDOJTAG_FPGA_TDIFPGA_JTAGENBJTAG_FPGA_TMSJTAG_FPGA_TMS
JTAG_FPGA_TDOJTAG_FPGA_TDIJTAG_FPGA_TMSJTAG_FPGA_TCKJTAG_BIC_TDO_RJTAG_BIC_TDI_RJTAG_BIC_TMS_RJTAG_BIC_TCK_R
FPGA_JTAGENBTP_INITNTP_DONE



5
5
4
4
3
3
2
2
1
1
D D
C C
B B
A A
FPGA_BUFFER
PWRGD_P12V_AUX_R[153,213,214,220]PWRGD_P12V_AUX_BUF_R [118]PWRGD_P5V_AUX_BUF_R [118]PWRGD_P3V3_AUX_BUF_R [118]PWRGD_P5V_AUX_R[220,221]PWRGD_P3V3_AUX_R[70,118,221]PEX0_MODE_SEL2 [15]FPGA_PEX0_MODE_SEL2_R[117]FPGA_PEX0_MODE_SEL1_R[117]PEX0_MODE_SEL1 [15]FPGA_PEX1_MODE_SEL1_R[117]PEX1_MODE_SEL1 [28]FPGA_PEX1_MODE_SEL2_R[117]PEX1_MODE_SEL2 [28]FPGA_PEX2_MODE_SEL1_R[117]PEX2_MODE_SEL1 [41]FPGA_PEX2_MODE_SEL2_R[117]PEX2_MODE_SEL2 [41]FPGA_PEX3_MODE_SEL1_R[117]PEX3_MODE_SEL1 [54]FPGA_PEX3_MODE_SEL2_R[117]PEX3_MODE_SEL2 [54]
P3V3_AUXP3V3_AUXP3V3_AUXP3V3_AUXP3V3_AUXP3V3_AUXP3V3_AUXP3V3_AUXP3V3_AUXSizeDoc NumberRevDate: SheetofReviewerDesignerDepartmentProject
Page TitleCCBU D121 257Tuesday, August 29, 2023<project_name><Designer> GRANDTETON_SWB_20230829121 FPGA_BUFFER<Reviewer>SizeDoc NumberRevDate: SheetofReviewerDesignerDepartmentProject
Page TitleCCBU D121 257Tuesday, August 29, 2023<project_name><Designer> GRANDTETON_SWB_20230829121 FPGA_BUFFER<Reviewer>SizeDoc NumberRevDate: SheetofReviewerDesignerDepartmentProject
Page TitleCCBU D121 257Tuesday, August 29, 2023<project_name><Designer> GRANDTETON_SWB_20230829121 FPGA_BUFFER<Reviewer>R64374.7KR0402-02011%  
R6407 0 5% R0402-0201R64104.7KR0402-02015%
Q236BBSS138BKS<Part Number>D23G25S24
C41890.1UF10%16VC0402-0201R6426 0 R0402-0201 5%R6435 0 R0402-0201 5%R6429 0 R0402-0201 5%R64034.7KR0402-02015%
R64394.7KR0402-02011%  
U429ASN74LVC3G34DCTR1784
R6447 0 R0402-0201 5%Q234ABSS138BKS<Part Number>S11G12D16R64314.7KR0402-02011%  R6408 0 5% R0402-0201U429CSN74LVC3G34DCTR6284Q234BBSS138BKS<Part Number>D23G25S24
R6402 33 R0402-0201
Q237ABSS138BKS<Part Number>S11G12D16 Q238ABSS138BKS<Part Number>S11G12D16
R6405 33 R0402-0201
R6440 0 R0402-0201 5%R64434.7KR0402-02011%  Q237BBSS138BKS<Part Number>D23G25S24 Q233ABSS138BKS<Part Number>S11G12D16
Q238BBSS138BKS<Part Number>D23G25S24R64334.7KR0402-02011%  Q232ABSS138BKS<Part Number>S11G12D16 R64094.7KR0402-02015%Q233BBSS138BKS<Part Number>D23G25S24Q235ABSS138BKS<Part Number>S11G12D16Q232BBSS138BKS<Part Number>D23G25S24R64454.7KR0402-02011%  R6434 0 R0402-0201 5%
R6406 0 5% R0402-0201
Q235BBSS138BKS<Part Number>D23G25S24Q239ABSS138BKS<Part Number>S11G12D16R6441 0 R0402-0201 5%R6446 0 R0402-0201 5%Q239BBSS138BKS<Part Number>D23G25S24
U429BSN74LVC3G34DCTR3584R64254.7KR0402-02011%  R64284.7KR0402-02011%  Q236ABSS138BKS<Part Number>S11G12D16
R6404 33 R0402-0201PWRGD_P12V_AUX_BUFPWRGD_P12V_AUX_BUF_RPWRGD_P5V_AUX_BUFPWRGD_P5V_AUX_BUF_RPWRGD_P3V3_AUX_BUFPWRGD_P3V3_AUX_BUF_RPWRGD_P12V_AUX_R1PWRGD_P5V_AUX_R2PWRGD_P3V3_AUX_R2FPGA_PEX0_MODE_SEL2_D_NFPGA_PEX0_MODE_SEL2_ISOFPGA_PEX0_MODE_SEL1_D_NFPGA_PEX0_MODE_SEL1_ISOFPGA_PEX1_MODE_SEL1_D_NFPGA_PEX1_MODE_SEL1_ISOFPGA_PEX1_MODE_SEL2_D_NFPGA_PEX1_MODE_SEL2_ISOFPGA_PEX2_MODE_SEL1_D_NFPGA_PEX2_MODE_SEL1_ISOFPGA_PEX2_MODE_SEL2_D_NFPGA_PEX2_MODE_SEL2_ISOFPGA_PEX3_MODE_SEL1_D_NFPGA_PEX3_MODE_SEL1_ISOFPGA_PEX3_MODE_SEL2_D_NFPGA_PEX3_MODE_SEL2_ISO



5
5
4
4
3
3
2
2
1
1
D D
C C
B B
A A
USB_TO_UART_CP2108(1/2)
BOM CHANGE
BOM CHANGE
BOM CHANGE
PVT_CHANGEUART_PEX3_SDB_R_RX[64,67,122]UART_PEX3_SDB_BUF_R_TX[67,122]
RST_FT4232_R_N [64,65,116,123]
UART_PEX2_SDB_R_RX[64,67,122]UART_PEX2_SDB_BUF_R_TX[67,122]UART_PEX1_SDB_R_RX[64,67,122]UART_PEX1_SDB_BUF_R_TX[67,122]UART_PEX0_SDB_R_RX[64,67,122]UART_PEX0_SDB_BUF_R_TX[67,122]USB2_FT4232_SDB_R_DP [70]USB2_FT4232_SDB_R_DN [70]UART_PEX3_SDB_BUF_R_TX[67,122]UART_PEX3_SDB_R_RX [64,67,122]UART_PEX2_SDB_BUF_R_TX[67,122]UART_PEX2_SDB_R_RX [64,67,122]UART_PEX1_SDB_BUF_R_TX[67,122]UART_PEX1_SDB_R_RX [64,67,122]UART_PEX0_SDB_BUF_R_TX[67,122]UART_PEX0_SDB_R_RX [64,67,122]P3V3_AUXP3V3_AUXP3V3_AUXP3V3_AUX
SizeDoc NumberRevDate: SheetofReviewerDesignerDepartmentProject
Page TitleCCBU D122 257Tuesday, August 29, 2023<project_name><Designer> GRANDTETON_SWB_20230829122 BLANK<Reviewer>SizeDoc NumberRevDate: SheetofReviewerDesignerDepartmentProject
Page TitleCCBU D122 257Tuesday, August 29, 2023<project_name><Designer> GRANDTETON_SWB_20230829122 BLANK<Reviewer>SizeDoc NumberRevDate: SheetofReviewerDesignerDepartmentProject
Page TitleCCBU D122 257Tuesday, August 29, 2023<project_name><Designer> GRANDTETON_SWB_20230829122 BLANK<Reviewer>
R6610 0 5% R0402-0201UART_BOM2C44400.1UF16V10%X7RC0402-0201UART_BOM2
J67SCONN3_TSM-103-01-S-SV-TRUART_BOM3123
R6601 0 5% R0402-0201UART_BOM2R6617 0 5% R0402-0201UART_BOM3R672549.91%NIJ65SCONN3_TSM-103-01-S-SV-TRUART_BOM3123R6615 0 5% R0402-0201UART_BOM3R6620 0 5% R0402-0201UART_BOM3R672649.91%NIR6606 0 5% R0402-0201UART_BOM2R6608 0 5% R0402-0201UART_BOM2R6604 0 5% R0402UART_BOM2R6613 0 5% R0402-0201UART_BOM3R6618 0 5% R0402-0201UART_BOM3R6605 0 5% R0402-0201UART_BOM2J66SCONN3_TSM-103-01-S-SV-TRUART_BOM3123CP2108-B03-GMRU434UART_BOM2VDD58VIO139VIO024VIOHD3VREGIN60VBUS61CTS35DCD38DSR39CTS213DCD212DSR217CTS146DCD143DSR144CTS054DCD051DSR052RI37RI211RI142RI050RX31RX215RX148RX056GPIO1521GPIO1422GPIO1323GPIO1226GPIO1127GPIO1028GPIO929GPIO830GPIO731GPIO632GPIO533GPIO434GPIO337GPIO238GPIO140GPIO041RESET#64SUSPEND#19SUSPEND20DTR310RTS36DTR218RTS214RTS147DTR145RTS055DTR053D+62D-63TX34TX216TX149TX057NC136NC035VSSHD2VSS159VSS025TH_VSSTHR6603 0 5% R0402UART_BOM2J68SCONN3_TSM-103-01-S-SV-TRUART_BOM3123
C44414.7UF25V10%X6SC0603UART_BOM2C44424.7UF25V10%X6SC0603UART_BOM2R6607 0 5% R0402-0201UART_BOM2R6619 0 5% R0402-0201UART_BOM3R6609 0 5% R0402-0201UART_BOM2R6611 0 5% R0402-0201UART_BOM2R6614 0 5% R0402-0201UART_BOM3
C44390.1UF16V10%X7RC0402-0201UART_BOM2R66024.7KUART_BOM2
R6616 0 5% R0402-0201UART_BOM3R6612 0 5% R0402-0201UART_BOM2RST_CP2108_SDB_R_NUSB2_CP2108_SDB_DPUSB2_CP2108_SDB_DNUART_PEX3_SDB_CP2108_TXUART_PEX3_SDB_CP2108_RXUART_PEX2_SDB_CP2108_TXUART_PEX2_SDB_CP2108_RXUART_PEX1_SDB_CP2108_TXUART_PEX1_SDB_CP2108_RXUART_PEX0_SDB_CP2108_TXUART_PEX0_SDB_CP2108_RXUART_PEX3_SDB_R1_RXUART_PEX3_SDB_BUF_R1_TXUART_PEX2_SDB_R1_RXUART_PEX2_SDB_BUF_R1_TXUART_PEX1_SDB_R1_RXUART_PEX1_SDB_BUF_R1_TXUART_PEX0_SDB_R1_RXUART_PEX0_SDB_BUF_R1_TX



5
5
4
4
3
3
2
2
1
1
D D
C C
B B
A A
USB_TO_UART_CP2108(2/2)
BOM CHANGE
BOM CHANGE
BOM CHANGEPVT_CHANGERST_FT4232_R_N [64,65,116,122]USB2_FT4232_CLI_R_DP [70]USB2_FT4232_CLI_R_DN [70]UART_PEX3_CLI_BUF_R_TX[68,123]UART_PEX3_CLI_R_RX [65,68,123]UART_PEX2_CLI_BUF_R_TX[68,123]UART_PEX2_CLI_R_RX [65,68,123]UART_PEX1_CLI_BUF_R_TX[68,123]UART_PEX1_CLI_R_RX [65,68,123]UART_PEX0_CLI_BUF_R_TX[68,123]UART_PEX0_CLI_R_RX [65,68,123]UART_PEX3_CLI_R_RX[65,68,123]UART_PEX3_CLI_BUF_R_TX[68,123]UART_PEX2_CLI_R_RX[65,68,123]UART_PEX2_CLI_BUF_R_TX[68,123]UART_PEX1_CLI_R_RX[65,68,123]UART_PEX1_CLI_BUF_R_TX[68,123]UART_PEX0_CLI_R_RX[65,68,123]UART_PEX0_CLI_BUF_R_TX[68,123]
P3V3_AUXP3V3_AUXP3V3_AUXP3V3_AUX
SizeDoc NumberRevDate: SheetofReviewerDesignerDepartmentProject
Page TitleCCBU D123 257Tuesday, August 29, 2023<project_name><Designer> GRANDTETON_SWB_20230829123 BLANK<Reviewer>SizeDoc NumberRevDate: SheetofReviewerDesignerDepartmentProject
Page TitleCCBU D123 257Tuesday, August 29, 2023<project_name><Designer> GRANDTETON_SWB_20230829123 BLANK<Reviewer>SizeDoc NumberRevDate: SheetofReviewerDesignerDepartmentProject
Page TitleCCBU D123 257Tuesday, August 29, 2023<project_name><Designer> GRANDTETON_SWB_20230829123 BLANK<Reviewer>
C44440.1UF16V10%X7RC0402-0201UART_BOM2R6629 0 5% R0402-0201UART_BOM2R6633 0 5% R0402-0201UART_BOM3R6637 0 5% R0402-0201UART_BOM3
R66214.7KUART_BOM2C44454.7UF25V10%X6SC0603UART_BOM2R6624 0 5% R0402UART_BOM2J70SCONN3_TSM-103-01-S-SV-TRUART_BOM3123J72SCONN3_TSM-103-01-S-SV-TRUART_BOM3123R6630 0 5% R0402-0201UART_BOM2C44460.1UF16V10%X7RC0402-0201UART_BOM2R6634 0 5% R0402-0201UART_BOM3R6638 0 5% R0402-0201UART_BOM3R6625 0 5% R0402-0201UART_BOM2R6631 0 5% R0402-0201UART_BOM2R6626 0 5% R0402-0201UART_BOM2R672349.91%NIR6622 0 5% R0402-0201UART_BOM2
R6635 0 5% R0402-0201UART_BOM3R6639 0 5% R0402-0201UART_BOM3R6632 0 5% R0402-0201UART_BOM2R672449.91%NIJ71SCONN3_TSM-103-01-S-SV-TRUART_BOM3123R6627 0 5% R0402-0201UART_BOM2J73SCONN3_TSM-103-01-S-SV-TRUART_BOM3123CP2108-B03-GMRU435UART_BOM2VDD58VIO139VIO024VIOHD3VREGIN60VBUS61CTS35DCD38DSR39CTS213DCD212DSR217CTS146DCD143DSR144CTS054DCD051DSR052RI37RI211RI142RI050RX31RX215RX148RX056GPIO1521GPIO1422GPIO1323GPIO1226GPIO1127GPIO1028GPIO929GPIO830GPIO731GPIO632GPIO533GPIO434GPIO337GPIO238GPIO140GPIO041RESET#64SUSPEND#19SUSPEND20DTR310RTS36DTR218RTS214RTS147DTR145RTS055DTR053D+62D-63TX34TX216TX149TX057NC136NC035VSSHD2VSS159VSS025TH_VSSTHR6636 0 5% R0402-0201UART_BOM3R6640 0 5% R0402-0201UART_BOM3R6628 0 5% R0402-0201UART_BOM2C44434.7UF25V10%X6SC0603UART_BOM2R6623 0 5% R0402UART_BOM2RST_CP2108_CLI_R_NUSB2_CP2108_CLI_DPUSB2_CP2108_CLI_DNUART_PEX3_CLI_CP2108_TXUART_PEX3_CLI_CP2108_RXUART_PEX2_CLI_CP2108_TXUART_PEX2_CLI_CP2108_RXUART_PEX1_CLI_CP2108_TXUART_PEX1_CLI_CP2108_RXUART_PEX0_CLI_CP2108_TXUART_PEX0_CLI_CP2108_RXUART_PEX3_CLI_R1_RXUART_PEX3_CLI_BUF_R1_TXUART_PEX2_CLI_R1_RXUART_PEX2_CLI_BUF_R1_TXUART_PEX1_CLI_R1_RXUART_PEX1_CLI_BUF_R1_TXUART_PEX0_CLI_R1_RXUART_PEX0_CLI_BUF_R1_TX



5
5
4
4
3
3
2
2
1
1
D D
C C
B B
A A
EXAMAX_10P8C_J3_GPU24(1/5)
DVT_CHANGEP5E_PEX0_STN7_RX_DN<112>[13]P5E_PEX0_STN7_RX_DP<112>[13]P5E_PEX0_STN4_RX_DN<79>[12]P5E_PEX0_STN4_RX_DP<79>[12]P5E_PEX0_STN7_TX_C_DN<112>[13]P5E_PEX0_STN7_TX_C_DP<112>[13]P5E_PEX0_STN4_TX_C_DN<79>[12]P5E_PEX0_STN4_TX_C_DP<79>[12]P5E_PEX0_STN7_RX_DN<120>[13]P5E_PEX0_STN7_RX_DP<120>[13]P5E_PEX0_STN4_RX_DN<71>[12]P5E_PEX0_STN4_RX_DP<71>[12]P5E_PEX0_STN7_TX_C_DN<120>[13]P5E_PEX0_STN7_TX_C_DP<120>[13]P5E_PEX0_STN4_TX_C_DN<71>[12]P5E_PEX0_STN4_TX_C_DP<71>[12]P5E_PEX0_STN7_RX_DN<113>[13]P5E_PEX0_STN7_RX_DP<113>[13]P5E_PEX0_STN4_RX_DN<78>[12]P5E_PEX0_STN4_RX_DP<78>[12]P5E_PEX0_STN7_TX_C_DN<113>[13]P5E_PEX0_STN7_TX_C_DP<113>[13]P5E_PEX0_STN4_TX_C_DN<78>[12]P5E_PEX0_STN4_TX_C_DP<78>[12]P5E_PEX0_STN4_RX_DN<70>[12]P5E_PEX0_STN4_RX_DP<70>[12]P5E_PEX0_STN4_TX_C_DN<70>[12]P5E_PEX0_STN4_TX_C_DP<70>[12]RST_GPU_PERST_2_BUF_R_N[115]PRSNT_GPU_D_N[164]
PRSNT_GPU_N[127,164]PRSNT_GPU_ISO_R_N [88]PRSNT_GPU_ISO_R1_N [115]
P5E_PEX0_STN7_RX_DN<121>[13]P5E_PEX0_STN7_RX_DP<121>[13]P5E_PEX0_STN7_TX_C_DP<121>[13]P5E_PEX0_STN7_TX_C_DN<121>[13]
P3V3_AUXP3V3_AUXSizeDoc NumberRevDate: SheetofReviewerDesignerDepartmentProject
Page TitleCCBU D124 257Tuesday, August 29, 2023<project_name><Designer> GRANDTETON_SWB_20230829124 EXAMAX_10P8C_J3_GPU24(1/5)<Reviewer>SizeDoc NumberRevDate: SheetofReviewerDesignerDepartmentProject
Page TitleCCBU D124 257Tuesday, August 29, 2023<project_name><Designer> GRANDTETON_SWB_20230829124 EXAMAX_10P8C_J3_GPU24(1/5)<Reviewer>SizeDoc NumberRevDate: SheetofReviewerDesignerDepartmentProject
Page TitleCCBU D124 257Tuesday, August 29, 2023<project_name><Designer> GRANDTETON_SWB_20230829124 EXAMAX_10P8C_J3_GPU24(1/5)<Reviewer>R1783 0 R0402-0201 5%R17814.7KR0402-02011%  R17824.7KR0402-02011%  Q19ABSS138BKS<Part Number>S11G12D16 BA IHGFEDC J K L M NO PQ RST U V W X Y Z1
2
1/5J3ACONN270_10146445-101LFA2A2B1B1B2B2C1C1C2C2D1D1D2D2E1E1E2E2F1F1F2F2G1G1G2G2H1H1H2H2I1I1I2I2J1J1J2J2K1K1K2K2L1L1L2L2M1M1M1_2M1_2M2_2M2_2N1_1N1_1N2N2N2_1N2_1O1O1O2O2P1P1P2P2Q1Q1Q2Q2R1R1R2R2S1S1S2S2T1T1T2T2U1U1U2U2V1V1V2V2W1W1W2W2X1X1X2X2Y1Y1Y2Y2Z1Z1Z2Z2A1A1
Q19BBSS138BKS<Part Number>D23G25S24R6147 0 R0402-0201 5%
P5E_PEX0_STN7_RX_DN<112>P5E_PEX0_STN7_RX_DP<112>P5E_PEX0_STN4_RX_DN<79>P5E_PEX0_STN4_RX_DP<79>P5E_PEX0_STN7_TX_C_DN<112>P5E_PEX0_STN7_TX_C_DP<112>P5E_PEX0_STN4_TX_C_DN<79>P5E_PEX0_STN4_TX_C_DP<79>P5E_PEX0_STN7_RX_DN<120>P5E_PEX0_STN7_RX_DP<120>P5E_PEX0_STN4_RX_DN<71>P5E_PEX0_STN4_RX_DP<71>P5E_PEX0_STN7_TX_C_DN<120>P5E_PEX0_STN7_TX_C_DP<120>P5E_PEX0_STN4_TX_C_DN<71>P5E_PEX0_STN4_TX_C_DP<71>P5E_PEX0_STN7_RX_DN<113>P5E_PEX0_STN7_RX_DP<113>P5E_PEX0_STN4_RX_DN<78>P5E_PEX0_STN4_RX_DP<78>P5E_PEX0_STN7_TX_C_DN<113>P5E_PEX0_STN7_TX_C_DP<113>P5E_PEX0_STN4_TX_C_DN<78>P5E_PEX0_STN4_TX_C_DP<78>P5E_PEX0_STN4_RX_DN<70>P5E_PEX0_STN4_RX_DP<70>P5E_PEX0_STN4_TX_C_DN<70>P5E_PEX0_STN4_TX_C_DP<70>PRSNT_GPU_D_NRST_GPU_PERST_2_BUF_R_N
PRSNT_GPU_ISOPRSNT_GPU_ISO_N
P5E_PEX0_STN7_RX_DN<121>P5E_PEX0_STN7_RX_DP<121>P5E_PEX0_STN7_TX_C_DP<121>P5E_PEX0_STN7_TX_C_DN<121>



5
5
4
4
3
3
2
2
1
1
D D
C C
B B
A A
EXAMAX_10P8C_J3_GPU24(2/5)
P5E_PEX0_STN7_RX_DN<115>[13]P5E_PEX0_STN7_RX_DP<115>[13]P5E_PEX0_STN4_RX_DN<76>[12]P5E_PEX0_STN4_RX_DP<76>[12]P5E_PEX0_STN7_TX_C_DN<115>[13]P5E_PEX0_STN7_TX_C_DP<115>[13]P5E_PEX0_STN4_TX_C_DN<76>[12]P5E_PEX0_STN4_TX_C_DP<76>[12]P5E_PEX0_STN7_RX_DN<123>[13]P5E_PEX0_STN7_RX_DP<123>[13]P5E_PEX0_STN4_RX_DN<68>[12]P5E_PEX0_STN4_RX_DP<68>[12]P5E_PEX0_STN7_TX_C_DN<123>[13]P5E_PEX0_STN7_TX_C_DP<123>[13]P5E_PEX0_STN4_TX_C_DN<68>[12]P5E_PEX0_STN4_TX_C_DP<68>[12]P5E_PEX0_STN7_RX_DN<114>[13]P5E_PEX0_STN7_RX_DP<114>[13]P5E_PEX0_STN4_RX_DN<77>[12]P5E_PEX0_STN4_RX_DP<77>[12]P5E_PEX0_STN4_TX_C_DN<77>[12]P5E_PEX0_STN4_TX_C_DP<77>[12]P5E_PEX0_STN4_RX_DN<69>[12]P5E_PEX0_STN4_RX_DP<69>[12]P5E_PEX0_STN4_TX_C_DN<69>[12]P5E_PEX0_STN4_TX_C_DP<69>[12]GPU_BASE_PWR_EN_R[164]P5E_PEX0_STN7_RX_DP<122>[13]P5E_PEX0_STN7_RX_DN<122>[13]P5E_PEX0_STN7_TX_C_DP<122>[13]P5E_PEX0_STN7_TX_C_DN<122>[13]P5E_PEX0_STN7_TX_C_DN<114>[13]P5E_PEX0_STN7_TX_C_DP<114>[13]GPU_HGX_DETECT_N[164]
SizeDoc NumberRevDate: SheetofReviewerDesignerDepartmentProject
Page TitleCCBU D125 257Tuesday, August 29, 2023<project_name><Designer> GRANDTETON_SWB_20230829125 EXAMAX_10P8C_J3_GPU24(2/5)<Reviewer>SizeDoc NumberRevDate: SheetofReviewerDesignerDepartmentProject
Page TitleCCBU D125 257Tuesday, August 29, 2023<project_name><Designer> GRANDTETON_SWB_20230829125 EXAMAX_10P8C_J3_GPU24(2/5)<Reviewer>SizeDoc NumberRevDate: SheetofReviewerDesignerDepartmentProject
Page TitleCCBU D125 257Tuesday, August 29, 2023<project_name><Designer> GRANDTETON_SWB_20230829125 EXAMAX_10P8C_J3_GPU24(2/5)<Reviewer>
BA IHGFEDC J K L M NO PQ R S T U V W X Y Z432/5J3BCONN270_10146445-101LFA4A4B4B4C4C4D4D4E4E4F4F4G4G4H4H4I4I4J4J4K4K4L4L4M1_4M1_4M2_4M2_4N4N4O4O4P4P4Q4Q4R4R4S4S4T4T4U4U4V4V4W4W4X4X4Y4Y4Z4Z4A3A3B3B3C3C3D3D3E3E3F3F3G3G3H3H3I3I3J3J3K3K3L3L3M3M3N1_3N1_3N2_3N2_3O3O3P3P3Q3Q3R3R3S3S3T3T3U3U3V3V3W3W3X3X3Y3Y3Z3Z3P5E_PEX0_STN7_RX_DN<115>P5E_PEX0_STN7_RX_DP<115>P5E_PEX0_STN4_RX_DN<76>P5E_PEX0_STN4_RX_DP<76>P5E_PEX0_STN7_TX_C_DN<115>P5E_PEX0_STN7_TX_C_DP<115>P5E_PEX0_STN4_TX_C_DN<76>P5E_PEX0_STN4_TX_C_DP<76>P5E_PEX0_STN7_RX_DN<123>P5E_PEX0_STN7_RX_DP<123>P5E_PEX0_STN4_RX_DN<68>P5E_PEX0_STN4_RX_DP<68>P5E_PEX0_STN7_TX_C_DN<123>P5E_PEX0_STN7_TX_C_DP<123>P5E_PEX0_STN4_TX_C_DN<68>P5E_PEX0_STN4_TX_C_DP<68>P5E_PEX0_STN7_RX_DN<114>P5E_PEX0_STN7_RX_DP<114>P5E_PEX0_STN4_RX_DN<77>P5E_PEX0_STN4_RX_DP<77>P5E_PEX0_STN4_TX_C_DN<77>P5E_PEX0_STN4_TX_C_DP<77>P5E_PEX0_STN4_RX_DN<69>P5E_PEX0_STN4_RX_DP<69>P5E_PEX0_STN4_TX_C_DN<69>P5E_PEX0_STN4_TX_C_DP<69>GPU_BASE_PWR_EN_RP5E_PEX0_STN7_RX_DP<122>P5E_PEX0_STN7_RX_DN<122>P5E_PEX0_STN7_TX_C_DP<122>P5E_PEX0_STN7_TX_C_DN<122>P5E_PEX0_STN7_TX_C_DN<114>P5E_PEX0_STN7_TX_C_DP<114>GPU_HGX_DETECT_N



5
5
4
4
3
3
2
2
1
1
D D
C C
B B
A A
EXAMAX_10P8C_J3_GPU24(3/5)
P5E_PEX0_STN7_RX_DN<117>[13]P5E_PEX0_STN7_RX_DP<117>[13]P5E_PEX0_STN4_RX_DN<74>[12]P5E_PEX0_STN4_RX_DP<74>[12]P5E_PEX0_STN7_TX_C_DN<117>[13]P5E_PEX0_STN7_TX_C_DP<117>[13]P5E_PEX0_STN4_TX_C_DN<74>[12]P5E_PEX0_STN4_TX_C_DP<74>[12]P5E_PEX0_STN7_RX_DN<125>[13]P5E_PEX0_STN7_RX_DP<125>[13]P5E_PEX0_STN4_RX_DN<66>[12]P5E_PEX0_STN4_RX_DP<66>[12]P5E_PEX0_STN7_TX_C_DN<125>[13]P5E_PEX0_STN7_TX_C_DP<125>[13]P5E_PEX0_STN4_TX_C_DN<66>[12]P5E_PEX0_STN4_TX_C_DP<66>[12]P5E_PEX0_STN7_RX_DN<116>[13]P5E_PEX0_STN7_RX_DP<116>[13]P5E_PEX0_STN4_RX_DN<75>[12]P5E_PEX0_STN4_RX_DP<75>[12]P5E_PEX0_STN7_TX_C_DN<116>[13]P5E_PEX0_STN7_TX_C_DP<116>[13]P5E_PEX0_STN4_TX_C_DN<75>[12]P5E_PEX0_STN4_TX_C_DP<75>[12]P5E_PEX0_STN7_RX_DN<124>[13]P5E_PEX0_STN7_RX_DP<124>[13]P5E_PEX0_STN4_RX_DN<67>[12]P5E_PEX0_STN4_RX_DP<67>[12]P5E_PEX0_STN7_TX_C_DN<124>[13]P5E_PEX0_STN7_TX_C_DP<124>[13]P5E_PEX0_STN4_TX_C_DN<67>[12]P5E_PEX0_STN4_TX_C_DP<67>[12]RST_GPU_PERST_1_BUF_R_N[115]GPU_BASE_PWR_GD[164]
SizeDoc NumberRevDate: SheetofReviewerDesignerDepartmentProject
Page TitleCCBU D126 257Tuesday, August 29, 2023<project_name><Designer> GRANDTETON_SWB_20230829126 EXAMAX_10P8C_J3_GPU24(3/5)<Reviewer>SizeDoc NumberRevDate: SheetofReviewerDesignerDepartmentProject
Page TitleCCBU D126 257Tuesday, August 29, 2023<project_name><Designer> GRANDTETON_SWB_20230829126 EXAMAX_10P8C_J3_GPU24(3/5)<Reviewer>SizeDoc NumberRevDate: SheetofReviewerDesignerDepartmentProject
Page TitleCCBU D126 257Tuesday, August 29, 2023<project_name><Designer> GRANDTETON_SWB_20230829126 EXAMAX_10P8C_J3_GPU24(3/5)<Reviewer>
BA IHGFEDC J K L M NO PQ RST U V W X Y Z563/5J3CCONN270_10146445-101LFA6A6B6B6C6C6D6D6E6E6F6F6G6G6H6H6I6I6J6J6K6K6L6L6M1_6M1_6M2_6M2_6N6N6O6O6P6P6Q6Q6R6R6S6S6T6T6U6U6V6V6W6W6X6X6Y6Y6Z6Z6A5A5B5B5C5C5D5D5E5E5F5F5G5G5H5H5I5I5J5J5K5K5L5L5M5M5N1_5N1_5N2_5N2_5O5O5P5P5Q5Q5R5R5S5S5T5T5U5U5V5V5W5W5X5X5Y5Y5Z5Z5P5E_PEX0_STN7_RX_DN<117>P5E_PEX0_STN7_RX_DP<117>P5E_PEX0_STN4_RX_DN<74>P5E_PEX0_STN4_RX_DP<74>P5E_PEX0_STN7_TX_C_DN<117>P5E_PEX0_STN7_TX_C_DP<117>P5E_PEX0_STN4_TX_C_DN<74>P5E_PEX0_STN4_TX_C_DP<74>P5E_PEX0_STN7_RX_DN<125>P5E_PEX0_STN7_RX_DP<125>P5E_PEX0_STN4_RX_DN<66>P5E_PEX0_STN4_RX_DP<66>P5E_PEX0_STN7_TX_C_DN<125>P5E_PEX0_STN7_TX_C_DP<125>P5E_PEX0_STN4_TX_C_DN<66>P5E_PEX0_STN4_TX_C_DP<66>P5E_PEX0_STN7_RX_DN<116>P5E_PEX0_STN7_RX_DP<116>P5E_PEX0_STN4_RX_DN<75>P5E_PEX0_STN4_RX_DP<75>P5E_PEX0_STN7_TX_C_DN<116>P5E_PEX0_STN7_TX_C_DP<116>P5E_PEX0_STN4_TX_C_DN<75>P5E_PEX0_STN4_TX_C_DP<75>P5E_PEX0_STN7_RX_DN<124>P5E_PEX0_STN7_RX_DP<124>P5E_PEX0_STN4_RX_DN<67>P5E_PEX0_STN4_RX_DP<67>P5E_PEX0_STN7_TX_C_DN<124>P5E_PEX0_STN7_TX_C_DP<124>P5E_PEX0_STN4_TX_C_DN<67>P5E_PEX0_STN4_TX_C_DP<67>GPU_BASE_PWR_GDRST_GPU_PERST_1_BUF_R_N



5
5
4
4
3
3
2
2
1
1
D D
C C
B B
A A
EXAMAX_10P8C_J3_GPU24(4/5)
P5E_PEX0_STN7_RX_DN<119>[13]P5E_PEX0_STN7_RX_DP<119>[13]P5E_PEX0_STN4_RX_DN<72>[12]P5E_PEX0_STN4_RX_DP<72>[12]P5E_PEX0_STN7_TX_C_DN<119>[13]P5E_PEX0_STN7_TX_C_DP<119>[13]P5E_PEX0_STN4_TX_C_DN<72>[12]P5E_PEX0_STN4_TX_C_DP<72>[12]P5E_PEX0_STN7_RX_DN<127>[13]P5E_PEX0_STN7_RX_DP<127>[13]P5E_PEX0_STN4_RX_DN<64>[12]P5E_PEX0_STN4_RX_DP<64>[12]P5E_PEX0_STN7_TX_C_DN<127>[13]P5E_PEX0_STN7_TX_C_DP<127>[13]P5E_PEX0_STN4_TX_C_DN<64>[12]P5E_PEX0_STN4_TX_C_DP<64>[12]P5E_PEX0_STN7_RX_DN<118>[13]P5E_PEX0_STN7_RX_DP<118>[13]P5E_PEX0_STN4_RX_DN<73>[12]P5E_PEX0_STN4_RX_DP<73>[12]P5E_PEX0_STN7_TX_C_DN<118>[13]P5E_PEX0_STN7_TX_C_DP<118>[13]P5E_PEX0_STN4_TX_C_DN<73>[12]P5E_PEX0_STN4_TX_C_DP<73>[12]P5E_PEX0_STN7_RX_DN<126>[13]P5E_PEX0_STN7_RX_DP<126>[13]P5E_PEX0_STN4_RX_DN<65>[12]P5E_PEX0_STN4_RX_DP<65>[12]P5E_PEX0_STN7_TX_C_DN<126>[13]P5E_PEX0_STN7_TX_C_DP<126>[13]P5E_PEX0_STN4_TX_C_DN<65>[12]P5E_PEX0_STN4_TX_C_DP<65>[12]GPU_BASE_ID1_R[164]PRSNT_GPU_N[124,164]
SizeDoc NumberRevDate: SheetofReviewerDesignerDepartmentProject
Page TitleCCBU D127 257Tuesday, August 29, 2023<project_name><Designer> GRANDTETON_SWB_20230829127 EXAMAX_10P8C_J3_GPU24(4/5)<Reviewer>SizeDoc NumberRevDate: SheetofReviewerDesignerDepartmentProject
Page TitleCCBU D127 257Tuesday, August 29, 2023<project_name><Designer> GRANDTETON_SWB_20230829127 EXAMAX_10P8C_J3_GPU24(4/5)<Reviewer>SizeDoc NumberRevDate: SheetofReviewerDesignerDepartmentProject
Page TitleCCBU D127 257Tuesday, August 29, 2023<project_name><Designer> GRANDTETON_SWB_20230829127 EXAMAX_10P8C_J3_GPU24(4/5)<Reviewer>
BA IHGFEDC J K L M NO PQ RST U V W X Y Z784/5J3DCONN270_10146445-101LFA8A8B8B8C8C8D8D8E8E8F8F8G8G8H8H8I8I8J8J8K8K8L8L8M1_8M1_8M2_8M2_8N8N8O8O8P8P8Q8Q8R8R8S8S8T8T8U8U8V8V8W8W8X8X8Y8Y8Z8Z8A7A7B7B7C7C7D7D7E7E7F7F7G7G7H7H7I7I7J7J7K7K7L7L7M7M7N1_7N1_7N2_7N2_7O7O7P7P7Q7Q7R7R7S7S7T7T7U7U7V7V7W7W7X7X7Y7Y7Z7Z7P5E_PEX0_STN7_RX_DN<119>P5E_PEX0_STN7_RX_DP<119>P5E_PEX0_STN4_RX_DN<72>P5E_PEX0_STN4_RX_DP<72>P5E_PEX0_STN7_TX_C_DN<119>P5E_PEX0_STN7_TX_C_DP<119>P5E_PEX0_STN4_TX_C_DN<72>P5E_PEX0_STN4_TX_C_DP<72>P5E_PEX0_STN7_RX_DN<127>P5E_PEX0_STN7_RX_DP<127>P5E_PEX0_STN4_RX_DN<64>P5E_PEX0_STN4_RX_DP<64>P5E_PEX0_STN7_TX_C_DN<127>P5E_PEX0_STN7_TX_C_DP<127>P5E_PEX0_STN4_TX_C_DN<64>P5E_PEX0_STN4_TX_C_DP<64>P5E_PEX0_STN7_RX_DN<118>P5E_PEX0_STN7_RX_DP<118>P5E_PEX0_STN4_RX_DN<73>P5E_PEX0_STN4_RX_DP<73>P5E_PEX0_STN7_TX_C_DN<118>P5E_PEX0_STN7_TX_C_DP<118>P5E_PEX0_STN4_TX_C_DN<73>P5E_PEX0_STN4_TX_C_DP<73>P5E_PEX0_STN7_RX_DN<126>P5E_PEX0_STN7_RX_DP<126>P5E_PEX0_STN4_RX_DN<65>P5E_PEX0_STN4_RX_DP<65>P5E_PEX0_STN7_TX_C_DN<126>P5E_PEX0_STN7_TX_C_DP<126>P5E_PEX0_STN4_TX_C_DN<65>P5E_PEX0_STN4_TX_C_DP<65>GPU_BASE_ID1_RPRSNT_GPU_N



5
5
4
4
3
3
2
2
1
1
D D
C C
B B
A A
EXAMAX_10P8C_J3_GPU24(5/5)
P2E_GPU_FPGA_PEX_TX_DN<0>[133]P2E_GPU_FPGA_PEX_TX_DP<0>[133]P2E_GPU_FPGA_PEX_RX_DN<0>[133]P2E_GPU_FPGA_PEX_RX_DP<0>[133]GPU_BASE_FPGA_READY[164]GPU_PEX_STRAP1_R[164]CLK_100M_GPU_FPGA_REF_DN[133]CLK_100M_GPU_FPGA_REF_DP[133]CLK_100M_DB2000QL_GPU_REF1_R_DN[79]CLK_100M_DB2000QL_GPU_REF1_R_DP[79]SMB_GPU_1_R_SCL[164]SMB_GPU_1_R_SDA[164]P4E_PEX0_STN3_RX_DN<48>[11]P4E_PEX0_STN3_RX_DP<48>[11]P4E_PEX0_STN3_TX_C_DN<48>[11]P4E_PEX0_STN3_TX_C_DP<48>[11]RST_GPU_PERST_0_BUF_R_N[115]RST_GPU_FPGA_PEX_RST_R_N[164]GPU_THERM_OVERT_N[164]GPU_PEX_STRAP0_R[164]GPU_PWR_BRAKE_R_N[164]GPU_BASE_ID0_R[164]CLK_100M_DB2000QL_GPU_REF2_R_DN[79]CLK_100M_DB2000QL_GPU_REF2_R_DP[79]USB2_GPU_HMC_DN[76,91]USB2_GPU_HMC_DP[76,91]CLK_100M_DB2000QL_GPU_REF0_R_DN[79]CLK_100M_DB2000QL_GPU_REF0_R_DP[79]SMB_GPU_2_R_SCL[164]SMB_GPU_2_R_SDA[164]P4E_PEX0_STN3_RX_DN<49>[11]P4E_PEX0_STN3_RX_DP<49>[11]P4E_PEX0_STN3_TX_C_DN<49>[11]P4E_PEX0_STN3_TX_C_DP<49>[11]
SizeDoc NumberRevDate: SheetofReviewerDesignerDepartmentProject
Page TitleCCBU D128 257Tuesday, August 29, 2023<project_name><Designer> GRANDTETON_SWB_20230829128 EXAMAX_10P8C_J3_GPU24(5/5)<Reviewer>SizeDoc NumberRevDate: SheetofReviewerDesignerDepartmentProject
Page TitleCCBU D128 257Tuesday, August 29, 2023<project_name><Designer> GRANDTETON_SWB_20230829128 EXAMAX_10P8C_J3_GPU24(5/5)<Reviewer>SizeDoc NumberRevDate: SheetofReviewerDesignerDepartmentProject
Page TitleCCBU D128 257Tuesday, August 29, 2023<project_name><Designer> GRANDTETON_SWB_20230829128 EXAMAX_10P8C_J3_GPU24(5/5)<Reviewer>
N ZA I OH PG QF RE SDB TC U VJ K WL XM Y1095/5J3ECONN270_10146445-101LFA10A10B10B10C10C10D10D10E10E10F10F10G10G10H10H10I10I10J10J10K10K10L10L10M1_10M1_10M2_10M2_10N10N10O10O10P10P10Q10Q10R10R10S10S10T10T10U10U10V10V10W10W10X10X10Y10Y10Z10Z10A9A9B9B9C9C9D9D9E9E9F9F9G9G9H9H9I9I9J9J9K9K9L9L9M9M9N1_9N1_9N2_9N2_9O9O9P9P9Q9Q9R9R9S9S9T9T9U9U9V9V9W9W9X9X9Y9Y9Z9Z9P2E_GPU_FPGA_PEX_TX_DN<0>P2E_GPU_FPGA_PEX_TX_DP<0>P2E_GPU_FPGA_PEX_RX_DN<0>P2E_GPU_FPGA_PEX_RX_DP<0>GPU_BASE_FPGA_READYGPU_PEX_STRAP1_RCLK_100M_GPU_FPGA_REF_DNCLK_100M_GPU_FPGA_REF_DPCLK_100M_DB2000QL_GPU_REF1_R_DNCLK_100M_DB2000QL_GPU_REF1_R_DPSMB_GPU_1_R_SCLSMB_GPU_1_R_SDAP4E_PEX0_STN3_RX_DN<48>P4E_PEX0_STN3_RX_DP<48>P4E_PEX0_STN3_TX_C_DN<48>P4E_PEX0_STN3_TX_C_DP<48>RST_GPU_PERST_0_BUF_R_NRST_GPU_FPGA_PEX_RST_R_NGPU_THERM_OVERT_NGPU_PEX_STRAP0_RGPU_PWR_BRAKE_R_NGPU_BASE_ID0_RCLK_100M_DB2000QL_GPU_REF2_R_DNCLK_100M_DB2000QL_GPU_REF2_R_DPUSB2_GPU_HMC_DNUSB2_GPU_HMC_DPCLK_100M_DB2000QL_GPU_REF0_R_DNCLK_100M_DB2000QL_GPU_REF0_R_DPSMB_GPU_2_R_SCLSMB_GPU_2_R_SDAP4E_PEX0_STN3_RX_DN<49>P4E_PEX0_STN3_RX_DP<49>P4E_PEX0_STN3_TX_C_DN<49>P4E_PEX0_STN3_TX_C_DP<49>



5
5
4
4
3
3
2
2
1
1
D D
C C
B B
A A
Open Drain Buffer
Open Drain Buffer
Open Drain Buffer
EXAMAX_10P8C_J11_CPU1(1/5)
DVT_CHANGEP5E_PEX0_STN6_TX_C_DN<111>[13]P5E_PEX0_STN6_TX_C_DP<111>[13]P5E_PEX0_STN5_TX_C_DN<80>[12]P5E_PEX0_STN5_TX_C_DP<80>[12]P5E_PEX0_STN6_RX_DN<111>[13]P5E_PEX0_STN6_RX_DP<111>[13]P5E_PEX0_STN5_RX_DN<80>[12]P5E_PEX0_STN5_RX_DP<80>[12]P5E_PEX0_STN6_TX_C_DN<103>[13]P5E_PEX0_STN6_TX_C_DP<103>[13]P5E_PEX0_STN5_TX_C_DN<88>[12]P5E_PEX0_STN5_TX_C_DP<88>[12]P5E_PEX0_STN6_RX_DN<103>[13]P5E_PEX0_STN6_RX_DP<103>[13]P5E_PEX0_STN5_RX_DN<88>[12]P5E_PEX0_STN5_RX_DP<88>[12]P5E_PEX0_STN6_TX_C_DN<110>[13]P5E_PEX0_STN6_TX_C_DP<110>[13]P5E_PEX0_STN5_TX_C_DN<81>[12]P5E_PEX0_STN5_TX_C_DP<81>[12]P5E_PEX0_STN6_RX_DN<110>[13]P5E_PEX0_STN6_RX_DP<110>[13]P5E_PEX0_STN5_RX_DN<81>[12]P5E_PEX0_STN5_RX_DP<81>[12]P5E_PEX0_STN6_TX_C_DN<102>[13]P5E_PEX0_STN6_TX_C_DP<102>[13]P5E_PEX0_STN5_TX_C_DN<89>[12]P5E_PEX0_STN5_TX_C_DP<89>[12]P5E_PEX0_STN6_RX_DN<102>[13]P5E_PEX0_STN6_RX_DP<102>[13]P5E_PEX0_STN5_RX_DN<89>[12]P5E_PEX0_STN5_RX_DP<89>[12]RST_MB_PERST_2_N[129,164]RST_MB_PERST_0_N[133,164]RST_MB_PERST_0_ISO_R_N [115]RST_MB_PERST_1_N[131,164]RST_MB_PERST_1_ISO_R_N [115]RST_MB_PERST_2_N[129,164]RST_MB_PERST_2_ISO_R_N [115]MB_SWB_PWR_EN[154,167]MB_SWB_PWR_EN_ISO_R [115]MB_SWB_PWRGD_BUF_R [155]MB_SWB_PWRGD[115]
PRSNT_GPU_D_R_N[164]P3V3_AUXP3V3_AUXP3V3_AUXP3V3_AUXP3V3_AUXP3V3_AUXP3V3_AUXP3V3_AUXP3V3_AUXSizeDoc NumberRevDate: SheetofReviewerDesignerDepartmentProject
Page TitleCCBU D129 257Tuesday, August 29, 2023<project_name><Designer> GRANDTETON_SWB_20230829129 EXAMAX_10P8C_J11_CPU1(1/5)<Reviewer>SizeDoc NumberRevDate: SheetofReviewerDesignerDepartmentProject
Page TitleCCBU D129 257Tuesday, August 29, 2023<project_name><Designer> GRANDTETON_SWB_20230829129 EXAMAX_10P8C_J11_CPU1(1/5)<Reviewer>SizeDoc NumberRevDate: SheetofReviewerDesignerDepartmentProject
Page TitleCCBU D129 257Tuesday, August 29, 2023<project_name><Designer> GRANDTETON_SWB_20230829129 EXAMAX_10P8C_J11_CPU1(1/5)<Reviewer>C27460.1UFC0402-0201R179733R0402-02011%R6314100K1% R0402-0201<Part Number>U145SN74LVC2G07DCKR1A12A31Y62Y4GND2VCC5C27450.1UFC0402-0201R6299100K1% R0402-0201<Part Number>R180033 R0402-02011%C27440.1UFC0402-0201R17864.7KR0402-02015%R6301100K1% R0402-0201<Part Number>U144SN74LVC2G07DCKR1A12A31Y62Y4GND2VCC5R17964.7KR0402-02015%NIR6300100K1% R0402-0201<Part Number>R179433 R0402-02011%U143SN74LVC2G07DCKR1A12A31Y62Y4GND2VCC5R17854.7KR0402-02015%NIR17904.7KR0402-02015%NIR17984.7KR0402-02015%R178833 R0402-02011%BA IHGFEDC J K L M NO PQ RST U V W X Y Z1
2
1/5J11ACONN270_10146445-101LFA2A2B1B1B2B2C1C1C2C2D1D1D2D2E1E1E2E2F1F1F2F2G1G1G2G2H1H1H2H2I1I1I2I2J1J1J2J2K1K1K2K2L1L1L2L2M1M1M1_2M1_2M2_2M2_2N1_1N1_1N2N2N2_1N2_1O1O1O2O2P1P1P2P2Q1Q1Q2Q2R1R1R2R2S1S1S2S2T1T1T2T2U1U1U2U2V1V1V2V2W1W1W2W2X1X1X2X2Y1Y1Y2Y2Z1Z1Z2Z2A1A1R17914.7KR0402-02015%NIR17874.7KR0402-02015%R17924.7KR0402-02015%R179533 R0402-02011%R17844.7KR0402-02015%NIR17934.7KR0402-02015%R6448100K1% R0402-0201<Part Number>R178933 R0402-02011%P5E_PEX0_STN6_TX_C_DN<111>P5E_PEX0_STN6_TX_C_DP<111>P5E_PEX0_STN5_TX_C_DN<80>P5E_PEX0_STN5_TX_C_DP<80>P5E_PEX0_STN6_RX_DN<111>P5E_PEX0_STN6_RX_DP<111>P5E_PEX0_STN5_RX_DN<80>P5E_PEX0_STN5_RX_DP<80>P5E_PEX0_STN6_TX_C_DN<103>P5E_PEX0_STN6_TX_C_DP<103>P5E_PEX0_STN5_TX_C_DN<88>P5E_PEX0_STN5_TX_C_DP<88>P5E_PEX0_STN6_RX_DN<103>P5E_PEX0_STN6_RX_DP<103>P5E_PEX0_STN5_RX_DN<88>P5E_PEX0_STN5_RX_DP<88>P5E_PEX0_STN6_TX_C_DN<110>P5E_PEX0_STN6_TX_C_DP<110>P5E_PEX0_STN5_TX_C_DN<81>P5E_PEX0_STN5_TX_C_DP<81>P5E_PEX0_STN6_RX_DN<110>P5E_PEX0_STN6_RX_DP<110>P5E_PEX0_STN5_RX_DN<81>P5E_PEX0_STN5_RX_DP<81>P5E_PEX0_STN6_TX_C_DN<102>P5E_PEX0_STN6_TX_C_DP<102>P5E_PEX0_STN5_TX_C_DN<89>P5E_PEX0_STN5_TX_C_DP<89>P5E_PEX0_STN6_RX_DN<102>P5E_PEX0_STN6_RX_DP<102>P5E_PEX0_STN5_RX_DN<89>P5E_PEX0_STN5_RX_DP<89>RST_MB_PERST_2_NRST_MB_PERST_0_NRST_MB_PERST_0_ISO_NRST_MB_PERST_1_NRST_MB_PERST_1_ISO_NRST_MB_PERST_2_NRST_MB_PERST_2_ISO_NMB_SWB_PWR_ENMB_SWB_PWR_EN_ISOMB_SWB_PWRGD_BUFMB_SWB_PWRGDMB_SWB_PWRGD_R
PRSNT_GPU_D_R_N



5
5
4
4
3
3
2
2
1
1
D D
C C
B B
A A
EXAMAX_10P8C_J11_CPU1(2/5)
P5E_PEX0_STN6_TX_C_DN<108>[13]P5E_PEX0_STN6_TX_C_DP<108>[13]P5E_PEX0_STN5_TX_C_DN<83>[12]P5E_PEX0_STN5_TX_C_DP<83>[12]P5E_PEX0_STN6_RX_DN<108>[13]P5E_PEX0_STN6_RX_DP<108>[13]P5E_PEX0_STN5_RX_DN<83>[12]P5E_PEX0_STN5_RX_DP<83>[12]P5E_PEX0_STN6_TX_C_DN<100>[13]P5E_PEX0_STN6_TX_C_DP<100>[13]P5E_PEX0_STN5_TX_C_DN<91>[12]P5E_PEX0_STN5_TX_C_DP<91>[12]P5E_PEX0_STN6_RX_DN<100>[13]P5E_PEX0_STN6_RX_DP<100>[13]P5E_PEX0_STN5_RX_DN<91>[12]P5E_PEX0_STN5_RX_DP<91>[12]P5E_PEX0_STN6_TX_C_DN<109>[13]P5E_PEX0_STN6_TX_C_DP<109>[13]P5E_PEX0_STN5_TX_C_DN<82>[12]P5E_PEX0_STN5_TX_C_DP<82>[12]P5E_PEX0_STN6_RX_DN<109>[13]P5E_PEX0_STN6_RX_DP<109>[13]P5E_PEX0_STN5_RX_DN<82>[12]P5E_PEX0_STN5_RX_DP<82>[12]P5E_PEX0_STN6_TX_C_DN<101>[13]P5E_PEX0_STN6_TX_C_DP<101>[13]P5E_PEX0_STN5_TX_C_DN<90>[12]P5E_PEX0_STN5_TX_C_DP<90>[12]P5E_PEX0_STN6_RX_DN<101>[13]P5E_PEX0_STN6_RX_DP<101>[13]P5E_PEX0_STN5_RX_DN<90>[12]P5E_PEX0_STN5_RX_DP<90>[12]GPU_BASE_PWR_EN[164]GPU_HGX_DETECT_R_N[164]
SizeDoc NumberRevDate: SheetofReviewerDesignerDepartmentProject
Page TitleCCBU D130 257Tuesday, August 29, 2023<project_name><Designer> GRANDTETON_SWB_20230829130 EXAMAX_10P8C_J11_CPU1(2/5)<Reviewer>SizeDoc NumberRevDate: SheetofReviewerDesignerDepartmentProject
Page TitleCCBU D130 257Tuesday, August 29, 2023<project_name><Designer> GRANDTETON_SWB_20230829130 EXAMAX_10P8C_J11_CPU1(2/5)<Reviewer>SizeDoc NumberRevDate: SheetofReviewerDesignerDepartmentProject
Page TitleCCBU D130 257Tuesday, August 29, 2023<project_name><Designer> GRANDTETON_SWB_20230829130 EXAMAX_10P8C_J11_CPU1(2/5)<Reviewer>
BA IHGFEDC J K L M NO PQ R S T U V W X Y Z432/5J11BCONN270_10146445-101LFA4A4B4B4C4C4D4D4E4E4F4F4G4G4H4H4I4I4J4J4K4K4L4L4M1_4M1_4M2_4M2_4N4N4O4O4P4P4Q4Q4R4R4S4S4T4T4U4U4V4V4W4W4X4X4Y4Y4Z4Z4A3A3B3B3C3C3D3D3E3E3F3F3G3G3H3H3I3I3J3J3K3K3L3L3M3M3N1_3N1_3N2_3N2_3O3O3P3P3Q3Q3R3R3S3S3T3T3U3U3V3V3W3W3X3X3Y3Y3Z3Z3P5E_PEX0_STN6_TX_C_DN<108>P5E_PEX0_STN6_TX_C_DP<108>P5E_PEX0_STN5_TX_C_DN<83>P5E_PEX0_STN5_TX_C_DP<83>P5E_PEX0_STN6_RX_DN<108>P5E_PEX0_STN6_RX_DP<108>P5E_PEX0_STN5_RX_DN<83>P5E_PEX0_STN5_RX_DP<83>P5E_PEX0_STN6_TX_C_DN<100>P5E_PEX0_STN6_TX_C_DP<100>P5E_PEX0_STN5_TX_C_DN<91>P5E_PEX0_STN5_TX_C_DP<91>P5E_PEX0_STN6_RX_DN<100>P5E_PEX0_STN6_RX_DP<100>P5E_PEX0_STN5_RX_DN<91>P5E_PEX0_STN5_RX_DP<91>P5E_PEX0_STN6_TX_C_DN<109>P5E_PEX0_STN6_TX_C_DP<109>P5E_PEX0_STN5_TX_C_DN<82>P5E_PEX0_STN5_TX_C_DP<82>P5E_PEX0_STN6_RX_DN<109>P5E_PEX0_STN6_RX_DP<109>P5E_PEX0_STN5_RX_DN<82>P5E_PEX0_STN5_RX_DP<82>P5E_PEX0_STN6_TX_C_DN<101>P5E_PEX0_STN6_TX_C_DP<101>P5E_PEX0_STN5_TX_C_DN<90>P5E_PEX0_STN5_TX_C_DP<90>P5E_PEX0_STN6_RX_DN<101>P5E_PEX0_STN6_RX_DP<101>P5E_PEX0_STN5_RX_DN<90>P5E_PEX0_STN5_RX_DP<90>GPU_HGX_DETECT_R_NGPU_BASE_PWR_EN



5
5
4
4
3
3
2
2
1
1
D D
C C
B B
A A
EXAMAX_10P8C_J11_CPU1(3/5)
P5E_PEX0_STN6_TX_C_DN<106>[13]P5E_PEX0_STN6_TX_C_DP<106>[13]P5E_PEX0_STN5_TX_C_DN<85>[12]P5E_PEX0_STN5_TX_C_DP<85>[12]P5E_PEX0_STN6_RX_DN<106>[13]P5E_PEX0_STN6_RX_DP<106>[13]P5E_PEX0_STN5_RX_DN<85>[12]P5E_PEX0_STN5_RX_DP<85>[12]P5E_PEX0_STN6_TX_C_DN<98>[13]P5E_PEX0_STN6_TX_C_DP<98>[13]P5E_PEX0_STN5_TX_C_DN<93>[12]P5E_PEX0_STN5_TX_C_DP<93>[12]P5E_PEX0_STN6_RX_DN<98>[13]P5E_PEX0_STN6_RX_DP<98>[13]P5E_PEX0_STN5_RX_DN<93>[12]P5E_PEX0_STN5_RX_DP<93>[12]P5E_PEX0_STN6_TX_C_DN<107>[13]P5E_PEX0_STN6_TX_C_DP<107>[13]P5E_PEX0_STN5_TX_C_DN<84>[12]P5E_PEX0_STN5_TX_C_DP<84>[12]P5E_PEX0_STN6_RX_DN<107>[13]P5E_PEX0_STN6_RX_DP<107>[13]P5E_PEX0_STN5_RX_DN<84>[12]P5E_PEX0_STN5_RX_DP<84>[12]P5E_PEX0_STN6_TX_C_DN<99>[13]P5E_PEX0_STN6_TX_C_DP<99>[13]P5E_PEX0_STN5_TX_C_DN<92>[12]P5E_PEX0_STN5_TX_C_DP<92>[12]P5E_PEX0_STN6_RX_DN<99>[13]P5E_PEX0_STN6_RX_DP<99>[13]P5E_PEX0_STN5_RX_DN<92>[12]P5E_PEX0_STN5_RX_DP<92>[12]RST_MB_PERST_1_N[129,164]GPU_BASE_PWR_GD_R[164]
SizeDoc NumberRevDate: SheetofReviewerDesignerDepartmentProject
Page TitleCCBU D131 257Tuesday, August 29, 2023<project_name><Designer> GRANDTETON_SWB_20230829131 EXAMAX_10P8C_J11_CPU1(3/5)<Reviewer>SizeDoc NumberRevDate: SheetofReviewerDesignerDepartmentProject
Page TitleCCBU D131 257Tuesday, August 29, 2023<project_name><Designer> GRANDTETON_SWB_20230829131 EXAMAX_10P8C_J11_CPU1(3/5)<Reviewer>SizeDoc NumberRevDate: SheetofReviewerDesignerDepartmentProject
Page TitleCCBU D131 257Tuesday, August 29, 2023<project_name><Designer> GRANDTETON_SWB_20230829131 EXAMAX_10P8C_J11_CPU1(3/5)<Reviewer>
BA IHGFEDC J K L M NO PQ RST U V W X Y Z563/5J11CCONN270_10146445-101LFA6A6B6B6C6C6D6D6E6E6F6F6G6G6H6H6I6I6J6J6K6K6L6L6M1_6M1_6M2_6M2_6N6N6O6O6P6P6Q6Q6R6R6S6S6T6T6U6U6V6V6W6W6X6X6Y6Y6Z6Z6A5A5B5B5C5C5D5D5E5E5F5F5G5G5H5H5I5I5J5J5K5K5L5L5M5M5N1_5N1_5N2_5N2_5O5O5P5P5Q5Q5R5R5S5S5T5T5U5U5V5V5W5W5X5X5Y5Y5Z5Z5P5E_PEX0_STN6_TX_C_DN<106>P5E_PEX0_STN6_TX_C_DP<106>P5E_PEX0_STN5_TX_C_DN<85>P5E_PEX0_STN5_TX_C_DP<85>P5E_PEX0_STN6_RX_DN<106>P5E_PEX0_STN6_RX_DP<106>P5E_PEX0_STN5_RX_DN<85>P5E_PEX0_STN5_RX_DP<85>P5E_PEX0_STN6_TX_C_DN<98>P5E_PEX0_STN6_TX_C_DP<98>P5E_PEX0_STN5_TX_C_DN<93>P5E_PEX0_STN5_TX_C_DP<93>P5E_PEX0_STN6_RX_DN<98>P5E_PEX0_STN6_RX_DP<98>P5E_PEX0_STN5_RX_DN<93>P5E_PEX0_STN5_RX_DP<93>P5E_PEX0_STN6_TX_C_DN<107>P5E_PEX0_STN6_TX_C_DP<107>P5E_PEX0_STN5_TX_C_DN<84>P5E_PEX0_STN5_TX_C_DP<84>P5E_PEX0_STN6_RX_DN<107>P5E_PEX0_STN6_RX_DP<107>P5E_PEX0_STN5_RX_DN<84>P5E_PEX0_STN5_RX_DP<84>P5E_PEX0_STN6_TX_C_DN<99>P5E_PEX0_STN6_TX_C_DP<99>P5E_PEX0_STN5_TX_C_DN<92>P5E_PEX0_STN5_TX_C_DP<92>P5E_PEX0_STN6_RX_DN<99>P5E_PEX0_STN6_RX_DP<99>P5E_PEX0_STN5_RX_DN<92>P5E_PEX0_STN5_RX_DP<92>RST_MB_PERST_1_NGPU_BASE_PWR_GD_R



5
5
4
4
3
3
2
2
1
1
D D
C C
B B
A A
Open Drain Buffer
From CPU To BIC
EXAMAX_10P8C_J11_CPU1(4/5)
DVT_CHANGEPVT_CHANGE
P5E_PEX0_STN6_TX_C_DN<104>[13]P5E_PEX0_STN6_TX_C_DP<104>[13]P5E_PEX0_STN5_TX_C_DN<87>[12]P5E_PEX0_STN5_TX_C_DP<87>[12]P5E_PEX0_STN6_RX_DN<104>[13]P5E_PEX0_STN6_RX_DP<104>[13]P5E_PEX0_STN5_RX_DN<87>[12]P5E_PEX0_STN5_RX_DP<87>[12]P5E_PEX0_STN6_TX_C_DN<96>[13]P5E_PEX0_STN6_TX_C_DP<96>[13]P5E_PEX0_STN5_TX_C_DN<95>[12]P5E_PEX0_STN5_TX_C_DP<95>[12]P5E_PEX0_STN6_RX_DN<96>[13]P5E_PEX0_STN6_RX_DP<96>[13]P5E_PEX0_STN5_RX_DN<95>[12]P5E_PEX0_STN5_RX_DP<95>[12]P5E_PEX0_STN6_TX_C_DN<105>[13]P5E_PEX0_STN6_TX_C_DP<105>[13]P5E_PEX0_STN5_TX_C_DN<86>[12]P5E_PEX0_STN5_TX_C_DP<86>[12]P5E_PEX0_STN6_RX_DN<105>[13]P5E_PEX0_STN6_RX_DP<105>[13]P5E_PEX0_STN5_RX_DN<86>[12]P5E_PEX0_STN5_RX_DP<86>[12]P5E_PEX0_STN6_TX_C_DN<97>[13]P5E_PEX0_STN6_TX_C_DP<97>[13]P5E_PEX0_STN5_TX_C_DN<94>[12]P5E_PEX0_STN5_TX_C_DP<94>[12]P5E_PEX0_STN6_RX_DN<97>[13]P5E_PEX0_STN6_RX_DP<97>[13]P5E_PEX0_STN5_RX_DN<94>[12]P5E_PEX0_STN5_RX_DP<94>[12]GPU_BASE_ID1[164]PRSNT_SWB_C_N[132]MB_BMC_MON[138,165]MB_BMC_MON_ISO_R [87]RST_MB_BIC_N[156,167]RST_MB_BIC_ISO_R_N [92,116]MB_BIC_MON[87]RST_MB_BMC_N[88]BIC_SYS_READY_R_N[88]MB_BIC_MON_BUF_R [138]RST_MB_BMC_BUF_R_N [157]MB_BIC_READY_BUF_R_N [155]BIC_SYS_READY_R2_N [115]
PRSNT_SWB_C_N[132]P3V3_AUXP3V3_AUXP3V3_AUXP3V3_AUXP3V3_AUXP3V3_AUXSizeDoc NumberRevDate: SheetofReviewerDesignerDepartmentProject
Page TitleCCBU D132 257Tuesday, August 29, 2023<project_name><Designer> GRANDTETON_SWB_20230829132 EXAMAX_10P8C_J11_CPU1(4/5)<Reviewer>SizeDoc NumberRevDate: SheetofReviewerDesignerDepartmentProject
Page TitleCCBU D132 257Tuesday, August 29, 2023<project_name><Designer> GRANDTETON_SWB_20230829132 EXAMAX_10P8C_J11_CPU1(4/5)<Reviewer>SizeDoc NumberRevDate: SheetofReviewerDesignerDepartmentProject
Page TitleCCBU D132 257Tuesday, August 29, 2023<project_name><Designer> GRANDTETON_SWB_20230829132 EXAMAX_10P8C_J11_CPU1(4/5)<Reviewer>
R18044.7KR0402-02015%U308BSN74LVC3G34DCTR3584R182133 R0402-02011%R18094.7KR0402-02015%R18061KR0402-02011%R6298100K1% R0402-0201<Part Number>R180833 R0402-02011%R18054.7KR0402-02015%R1818 33 R0402-02011%R18104.7KR0402-02015%R18144.7KR0402-02015%NI
R180205%R0402-0201<Part Number>R18114.7KR0402-02015%U308CSN74LVC3G34DCTR6284C27040.1UF10%16VC0402-0201R18124.7KR0402-02015%NIC27470.1UFC0402-0201R1820 33 R0402-02011%R18134.7KR0402-02015%NIU308ASN74LVC3G34DCTR1784R181533 R0402-02011%U146SN74LVC2G07DCKR1A12A31Y62Y4GND2VCC5R1816 33 R0402-02011%R180733 R0402-02011%R181733 R0402-02011%BA IHGFEDC J K L M NO PQ RST U V W X Y Z784/5J11DCONN270_10146445-101LFA8A8B8B8C8C8D8D8E8E8F8F8G8G8H8H8I8I8J8J8K8K8L8L8M1_8M1_8M2_8M2_8N8N8O8O8P8P8Q8Q8R8R8S8S8T8T8U8U8V8V8W8W8X8X8Y8Y8Z8Z8A7A7B7B7C7C7D7D7E7E7F7F7G7G7H7H7I7I7J7J7K7K7L7L7M7M7N1_7N1_7N2_7N2_7O7O7P7P7Q7Q7R7R7S7S7T7T7U7U7V7V7W7W7X7X7Y7Y7Z7Z7R18034.7K5%NIR181933 R0402-02011%
P5E_PEX0_STN6_TX_C_DN<104>P5E_PEX0_STN6_TX_C_DP<104>P5E_PEX0_STN5_TX_C_DN<87>P5E_PEX0_STN5_TX_C_DP<87>P5E_PEX0_STN6_RX_DN<104>P5E_PEX0_STN6_RX_DP<104>P5E_PEX0_STN5_RX_DN<87>P5E_PEX0_STN5_RX_DP<87>P5E_PEX0_STN6_TX_C_DN<96>P5E_PEX0_STN6_TX_C_DP<96>P5E_PEX0_STN5_TX_C_DN<95>P5E_PEX0_STN5_TX_C_DP<95>P5E_PEX0_STN6_RX_DN<96>P5E_PEX0_STN6_RX_DP<96>P5E_PEX0_STN5_RX_DN<95>P5E_PEX0_STN5_RX_DP<95>P5E_PEX0_STN6_TX_C_DN<105>P5E_PEX0_STN6_TX_C_DP<105>P5E_PEX0_STN5_TX_C_DN<86>P5E_PEX0_STN5_TX_C_DP<86>P5E_PEX0_STN6_RX_DN<105>P5E_PEX0_STN6_RX_DP<105>P5E_PEX0_STN5_RX_DN<86>P5E_PEX0_STN5_RX_DP<86>P5E_PEX0_STN6_TX_C_DN<97>P5E_PEX0_STN6_TX_C_DP<97>P5E_PEX0_STN5_TX_C_DN<94>P5E_PEX0_STN5_TX_C_DP<94>P5E_PEX0_STN6_RX_DN<97>P5E_PEX0_STN6_RX_DP<97>P5E_PEX0_STN5_RX_DN<94>P5E_PEX0_STN5_RX_DP<94>GPU_BASE_ID1PRSNT_SWB_C_NMB_BMC_MONMB_BMC_MON_ISORST_MB_BIC_NRST_MB_BIC_ISO_NMB_BIC_R_MONMB_BIC_MON_BUFMB_BIC_MON_BUF_RRST_MB_BMC_R_NRST_MB_BMC_BUF_NRST_MB_BMC_BUF_R_NBIC_SYS_READY_R1_NMB_BIC_READY_BUF_NMB_BIC_READY_BUF_R_N



5
5
4
4
3
3
2
2
1
1
D D
C C
B B
A A
EXAMAX_10P8C_J11_CPU1(5/5)
RST_GPU_FPGA_PEX_RST_N[164]GPU_PEX_STRAP0[164]GPU_PWR_BRAKE_N[164]GPU_BASE_ID0[164]CLK_100M_MB_0_DN[83]CLK_100M_MB_0_DP[83]SMB_GPU_2_SCL[164]SMB_GPU_1_SCL[164]P2E_GPU_FPGA_PEX_RX_DN<0>[128]P2E_GPU_FPGA_PEX_RX_DP<0>[128]GPU_PEX_STRAP1[164]CLK_100M_GPU_FPGA_REF_DN[128]CLK_100M_GPU_FPGA_REF_DP[128]RST_MB_PERST_0_N[129,164]P2E_GPU_FPGA_PEX_TX_DN<0>[128]P2E_GPU_FPGA_PEX_TX_DP<0>[128]GPU_BASE_FPGA_READY_R[164]SMB_GPU_1_SDA[164]USB2_MB_BMC_DN[76,91]USB2_MB_BMC_DP[76,91]SMB_GPU_2_SDA[164]GPU_THERM_OVERT_R_N[164]CLK_100M_MB_1_DN[84]CLK_100M_MB_1_DP[84]
SizeDoc NumberRevDate: SheetofReviewerDesignerDepartmentProject
Page TitleCCBU D133 257Tuesday, August 29, 2023<project_name><Designer> GRANDTETON_SWB_20230829133 EXAMAX_10P8C_J11_CPU1(5/5)<Reviewer>SizeDoc NumberRevDate: SheetofReviewerDesignerDepartmentProject
Page TitleCCBU D133 257Tuesday, August 29, 2023<project_name><Designer> GRANDTETON_SWB_20230829133 EXAMAX_10P8C_J11_CPU1(5/5)<Reviewer>SizeDoc NumberRevDate: SheetofReviewerDesignerDepartmentProject
Page TitleCCBU D133 257Tuesday, August 29, 2023<project_name><Designer> GRANDTETON_SWB_20230829133 EXAMAX_10P8C_J11_CPU1(5/5)<Reviewer>
N ZA I OH PG QF RE SDB TC U VJ K WL XM Y1095/5J11ECONN270_10146445-101LFA10A10B10B10C10C10D10D10E10E10F10F10G10G10H10H10I10I10J10J10K10K10L10L10M1_10M1_10M2_10M2_10N10N10O10O10P10P10Q10Q10R10R10S10S10T10T10U10U10V10V10W10W10X10X10Y10Y10Z10Z10A9A9B9B9C9C9D9D9E9E9F9F9G9G9H9H9I9I9J9J9K9K9L9L9M9M9N1_9N1_9N2_9N2_9O9O9P9P9Q9Q9R9R9S9S9T9T9U9U9V9V9W9W9X9X9Y9Y9Z9Z9RST_GPU_FPGA_PEX_RST_NGPU_THERM_OVERT_R_NGPU_PEX_STRAP0GPU_PWR_BRAKE_NGPU_BASE_ID0USB2_MB_BMC_DNUSB2_MB_BMC_DPCLK_100M_MB_0_DNCLK_100M_MB_0_DPSMB_GPU_2_SCLSMB_GPU_2_SDASMB_GPU_1_SCLSMB_GPU_1_SDAP2E_GPU_FPGA_PEX_TX_DN<0>P2E_GPU_FPGA_PEX_TX_DP<0>P2E_GPU_FPGA_PEX_RX_DN<0>P2E_GPU_FPGA_PEX_RX_DP<0>GPU_BASE_FPGA_READY_RGPU_PEX_STRAP1CLK_100M_GPU_FPGA_REF_DNCLK_100M_GPU_FPGA_REF_DPRST_MB_PERST_0_NCLK_100M_MB_1_DNCLK_100M_MB_1_DPTP_CLK_100M_MB_2_DNTP_CLK_100M_MB_2_DP



5
5
4
4
3
3
2
2
1
1
D D
C C
B B
A A
EXAMAX_10P8C_J12_CPU1(1/5)
P5E_PEX1_STN6_TX_C_DN<111>[26]P5E_PEX1_STN6_TX_C_DP<111>[26]P5E_PEX1_STN5_TX_C_DN<80>[25]P5E_PEX1_STN5_TX_C_DP<80>[25]P5E_PEX1_STN6_RX_DN<111>[26]P5E_PEX1_STN6_RX_DP<111>[26]P5E_PEX1_STN5_RX_DN<80>[25]P5E_PEX1_STN5_RX_DP<80>[25]P5E_PEX1_STN6_TX_C_DN<103>[26]P5E_PEX1_STN6_TX_C_DP<103>[26]P5E_PEX1_STN5_TX_C_DN<88>[25]P5E_PEX1_STN5_TX_C_DP<88>[25]P5E_PEX1_STN6_RX_DN<103>[26]P5E_PEX1_STN6_RX_DP<103>[26]P5E_PEX1_STN5_RX_DN<88>[25]P5E_PEX1_STN5_RX_DP<88>[25]P5E_PEX1_STN6_TX_C_DN<110>[26]P5E_PEX1_STN6_TX_C_DP<110>[26]P5E_PEX1_STN5_TX_C_DN<81>[25]P5E_PEX1_STN5_TX_C_DP<81>[25]P5E_PEX1_STN6_RX_DN<110>[26]P5E_PEX1_STN6_RX_DP<110>[26]P5E_PEX1_STN5_RX_DN<81>[25]P5E_PEX1_STN5_RX_DP<81>[25]P5E_PEX1_STN6_TX_C_DN<102>[26]P5E_PEX1_STN6_TX_C_DP<102>[26]P5E_PEX1_STN5_TX_C_DN<89>[25]P5E_PEX1_STN5_TX_C_DP<89>[25]P5E_PEX1_STN6_RX_DN<102>[26]P5E_PEX1_STN6_RX_DP<102>[26]P5E_PEX1_STN5_RX_DN<89>[25]P5E_PEX1_STN5_RX_DP<89>[25]GPU_FPGA_EROT_RECOV_N[165]GPU_FPGA_EROT_FATALERR_R_N[165]
SizeDoc NumberRevDate: SheetofReviewerDesignerDepartmentProject
Page TitleCCBU D134 257Tuesday, August 29, 2023<project_name><Designer> GRANDTETON_SWB_20230829134 EXAMAX_10P8C_J12_CPU1(1/5)<Reviewer>SizeDoc NumberRevDate: SheetofReviewerDesignerDepartmentProject
Page TitleCCBU D134 257Tuesday, August 29, 2023<project_name><Designer> GRANDTETON_SWB_20230829134 EXAMAX_10P8C_J12_CPU1(1/5)<Reviewer>SizeDoc NumberRevDate: SheetofReviewerDesignerDepartmentProject
Page TitleCCBU D134 257Tuesday, August 29, 2023<project_name><Designer> GRANDTETON_SWB_20230829134 EXAMAX_10P8C_J12_CPU1(1/5)<Reviewer>
BA IHGFEDC J K L M NO PQ RST U V W X Y Z1
2
1/5J12ACONN270_10146445-101LFA2A2B1B1B2B2C1C1C2C2D1D1D2D2E1E1E2E2F1F1F2F2G1G1G2G2H1H1H2H2I1I1I2I2J1J1J2J2K1K1K2K2L1L1L2L2M1M1M1_2M1_2M2_2M2_2N1_1N1_1N2N2N2_1N2_1O1O1O2O2P1P1P2P2Q1Q1Q2Q2R1R1R2R2S1S1S2S2T1T1T2T2U1U1U2U2V1V1V2V2W1W1W2W2X1X1X2X2Y1Y1Y2Y2Z1Z1Z2Z2A1A1P5E_PEX1_STN6_TX_C_DN<111>P5E_PEX1_STN6_TX_C_DP<111>P5E_PEX1_STN5_TX_C_DN<80>P5E_PEX1_STN5_TX_C_DP<80>P5E_PEX1_STN6_RX_DN<111>P5E_PEX1_STN6_RX_DP<111>P5E_PEX1_STN5_RX_DN<80>P5E_PEX1_STN5_RX_DP<80>P5E_PEX1_STN6_TX_C_DN<103>P5E_PEX1_STN6_TX_C_DP<103>P5E_PEX1_STN5_TX_C_DN<88>P5E_PEX1_STN5_TX_C_DP<88>P5E_PEX1_STN6_RX_DN<103>P5E_PEX1_STN6_RX_DP<103>P5E_PEX1_STN5_RX_DN<88>P5E_PEX1_STN5_RX_DP<88>P5E_PEX1_STN6_TX_C_DN<110>P5E_PEX1_STN6_TX_C_DP<110>P5E_PEX1_STN5_TX_C_DN<81>P5E_PEX1_STN5_TX_C_DP<81>P5E_PEX1_STN6_RX_DN<110>P5E_PEX1_STN6_RX_DP<110>P5E_PEX1_STN5_RX_DN<81>P5E_PEX1_STN5_RX_DP<81>P5E_PEX1_STN6_TX_C_DN<102>P5E_PEX1_STN6_TX_C_DP<102>P5E_PEX1_STN5_TX_C_DN<89>P5E_PEX1_STN5_TX_C_DP<89>P5E_PEX1_STN6_RX_DN<102>P5E_PEX1_STN6_RX_DP<102>P5E_PEX1_STN5_RX_DN<89>P5E_PEX1_STN5_RX_DP<89>GPU_FPGA_EROT_FATALERR_R_NGPU_FPGA_EROT_RECOV_N



5
5
4
4
3
3
2
2
1
1
D D
C C
B B
A A
EXAMAX_10P8C_J12_CPU1(2/5)
P5E_PEX1_STN6_TX_C_DN<108>[26]P5E_PEX1_STN6_TX_C_DP<108>[26]P5E_PEX1_STN5_TX_C_DN<83>[25]P5E_PEX1_STN5_TX_C_DP<83>[25]P5E_PEX1_STN6_RX_DN<108>[26]P5E_PEX1_STN6_RX_DP<108>[26]P5E_PEX1_STN5_RX_DN<83>[25]P5E_PEX1_STN5_RX_DP<83>[25]P5E_PEX1_STN6_TX_C_DN<100>[26]P5E_PEX1_STN6_TX_C_DP<100>[26]P5E_PEX1_STN5_TX_C_DN<91>[25]P5E_PEX1_STN5_TX_C_DP<91>[25]P5E_PEX1_STN6_RX_DN<100>[26]P5E_PEX1_STN6_RX_DP<100>[26]P5E_PEX1_STN5_RX_DN<91>[25]P5E_PEX1_STN5_RX_DP<91>[25]P5E_PEX1_STN6_TX_C_DN<109>[26]P5E_PEX1_STN6_TX_C_DP<109>[26]P5E_PEX1_STN5_TX_C_DN<82>[25]P5E_PEX1_STN5_TX_C_DP<82>[25]P5E_PEX1_STN6_RX_DN<109>[26]P5E_PEX1_STN6_RX_DP<109>[26]P5E_PEX1_STN5_RX_DN<82>[25]P5E_PEX1_STN5_RX_DP<82>[25]P5E_PEX1_STN6_TX_C_DN<101>[26]P5E_PEX1_STN6_TX_C_DP<101>[26]P5E_PEX1_STN5_TX_C_DN<90>[25]P5E_PEX1_STN5_TX_C_DP<90>[25]P5E_PEX1_STN6_RX_DN<101>[26]P5E_PEX1_STN6_RX_DP<101>[26]P5E_PEX1_STN5_RX_DN<90>[25]P5E_PEX1_STN5_RX_DP<90>[25]GPU_3V3IO_RSVD0_FFU_R[165]PRSNT_GPU_HMC_R_N[165]
SizeDoc NumberRevDate: SheetofReviewerDesignerDepartmentProject
Page TitleCCBU D135 257Tuesday, August 29, 2023<project_name><Designer> GRANDTETON_SWB_20230829135 EXAMAX_10P8C_J12_CPU1(2/5)<Reviewer>SizeDoc NumberRevDate: SheetofReviewerDesignerDepartmentProject
Page TitleCCBU D135 257Tuesday, August 29, 2023<project_name><Designer> GRANDTETON_SWB_20230829135 EXAMAX_10P8C_J12_CPU1(2/5)<Reviewer>SizeDoc NumberRevDate: SheetofReviewerDesignerDepartmentProject
Page TitleCCBU D135 257Tuesday, August 29, 2023<project_name><Designer> GRANDTETON_SWB_20230829135 EXAMAX_10P8C_J12_CPU1(2/5)<Reviewer>
BA IHGFEDC J K L M NO PQ R S T U V W X Y Z432/5J12BCONN270_10146445-101LFA4A4B4B4C4C4D4D4E4E4F4F4G4G4H4H4I4I4J4J4K4K4L4L4M1_4M1_4M2_4M2_4N4N4O4O4P4P4Q4Q4R4R4S4S4T4T4U4U4V4V4W4W4X4X4Y4Y4Z4Z4A3A3B3B3C3C3D3D3E3E3F3F3G3G3H3H3I3I3J3J3K3K3L3L3M3M3N1_3N1_3N2_3N2_3O3O3P3P3Q3Q3R3R3S3S3T3T3U3U3V3V3W3W3X3X3Y3Y3Z3Z3P5E_PEX1_STN6_TX_C_DN<108>P5E_PEX1_STN6_TX_C_DP<108>P5E_PEX1_STN5_TX_C_DN<83>P5E_PEX1_STN5_TX_C_DP<83>P5E_PEX1_STN6_RX_DN<108>P5E_PEX1_STN6_RX_DP<108>P5E_PEX1_STN5_RX_DN<83>P5E_PEX1_STN5_RX_DP<83>P5E_PEX1_STN6_TX_C_DN<100>P5E_PEX1_STN6_TX_C_DP<100>P5E_PEX1_STN5_TX_C_DN<91>P5E_PEX1_STN5_TX_C_DP<91>P5E_PEX1_STN6_RX_DN<100>P5E_PEX1_STN6_RX_DP<100>P5E_PEX1_STN5_RX_DN<91>P5E_PEX1_STN5_RX_DP<91>P5E_PEX1_STN6_TX_C_DN<109>P5E_PEX1_STN6_TX_C_DP<109>P5E_PEX1_STN5_TX_C_DN<82>P5E_PEX1_STN5_TX_C_DP<82>P5E_PEX1_STN6_RX_DN<109>P5E_PEX1_STN6_RX_DP<109>P5E_PEX1_STN5_RX_DN<82>P5E_PEX1_STN5_RX_DP<82>P5E_PEX1_STN6_TX_C_DN<101>P5E_PEX1_STN6_TX_C_DP<101>P5E_PEX1_STN5_TX_C_DN<90>P5E_PEX1_STN5_TX_C_DP<90>P5E_PEX1_STN6_RX_DN<101>P5E_PEX1_STN6_RX_DP<101>P5E_PEX1_STN5_RX_DN<90>P5E_PEX1_STN5_RX_DP<90>GPU_3V3IO_RSVD0_FFU_RPRSNT_GPU_HMC_R_N



5
5
4
4
3
3
2
2
1
1
D D
C C
B B
A A
EXAMAX_10P8C_J12_CPU1(3/5)
P5E_PEX1_STN6_TX_C_DN<106>[26]P5E_PEX1_STN6_TX_C_DP<106>[26]P5E_PEX1_STN5_TX_C_DN<85>[25]P5E_PEX1_STN5_TX_C_DP<85>[25]P5E_PEX1_STN6_RX_DN<106>[26]P5E_PEX1_STN6_RX_DP<106>[26]P5E_PEX1_STN5_RX_DN<85>[25]P5E_PEX1_STN5_RX_DP<85>[25]P5E_PEX1_STN6_TX_C_DN<98>[26]P5E_PEX1_STN6_TX_C_DP<98>[26]P5E_PEX1_STN5_TX_C_DN<93>[25]P5E_PEX1_STN5_TX_C_DP<93>[25]P5E_PEX1_STN6_RX_DN<98>[26]P5E_PEX1_STN6_RX_DP<98>[26]P5E_PEX1_STN5_RX_DN<93>[25]P5E_PEX1_STN5_RX_DP<93>[25]P5E_PEX1_STN6_TX_C_DN<107>[26]P5E_PEX1_STN6_TX_C_DP<107>[26]P5E_PEX1_STN5_TX_C_DN<84>[25]P5E_PEX1_STN5_TX_C_DP<84>[25]P5E_PEX1_STN6_RX_DN<107>[26]P5E_PEX1_STN6_RX_DP<107>[26]P5E_PEX1_STN5_RX_DN<84>[25]P5E_PEX1_STN5_RX_DP<84>[25]P5E_PEX1_STN6_TX_C_DN<99>[26]P5E_PEX1_STN6_TX_C_DP<99>[26]P5E_PEX1_STN5_TX_C_DN<92>[25]P5E_PEX1_STN5_TX_C_DP<92>[25]P5E_PEX1_STN6_RX_DN<99>[26]P5E_PEX1_STN6_RX_DP<99>[26]P5E_PEX1_STN5_RX_DN<92>[25]P5E_PEX1_STN5_RX_DP<92>[25]GPU_3V3IO_RSVD1_FFU_R[165]GPU_BASE_HMC_READY_R[165]
SizeDoc NumberRevDate: SheetofReviewerDesignerDepartmentProject
Page TitleCCBU D136 257Tuesday, August 29, 2023<project_name><Designer> GRANDTETON_SWB_20230829136 EXAMAX_10P8C_J12_CPU1(3/5)<Reviewer>SizeDoc NumberRevDate: SheetofReviewerDesignerDepartmentProject
Page TitleCCBU D136 257Tuesday, August 29, 2023<project_name><Designer> GRANDTETON_SWB_20230829136 EXAMAX_10P8C_J12_CPU1(3/5)<Reviewer>SizeDoc NumberRevDate: SheetofReviewerDesignerDepartmentProject
Page TitleCCBU D136 257Tuesday, August 29, 2023<project_name><Designer> GRANDTETON_SWB_20230829136 EXAMAX_10P8C_J12_CPU1(3/5)<Reviewer>
BA IHGFEDC J K L M NO PQ RST U V W X Y Z563/5J12CCONN270_10146445-101LFA6A6B6B6C6C6D6D6E6E6F6F6G6G6H6H6I6I6J6J6K6K6L6L6M1_6M1_6M2_6M2_6N6N6O6O6P6P6Q6Q6R6R6S6S6T6T6U6U6V6V6W6W6X6X6Y6Y6Z6Z6A5A5B5B5C5C5D5D5E5E5F5F5G5G5H5H5I5I5J5J5K5K5L5L5M5M5N1_5N1_5N2_5N2_5O5O5P5P5Q5Q5R5R5S5S5T5T5U5U5V5V5W5W5X5X5Y5Y5Z5Z5P5E_PEX1_STN6_TX_C_DN<106>P5E_PEX1_STN6_TX_C_DP<106>P5E_PEX1_STN5_TX_C_DN<85>P5E_PEX1_STN5_TX_C_DP<85>P5E_PEX1_STN6_RX_DN<106>P5E_PEX1_STN6_RX_DP<106>P5E_PEX1_STN5_RX_DN<85>P5E_PEX1_STN5_RX_DP<85>P5E_PEX1_STN6_TX_C_DN<98>P5E_PEX1_STN6_TX_C_DP<98>P5E_PEX1_STN5_TX_C_DN<93>P5E_PEX1_STN5_TX_C_DP<93>P5E_PEX1_STN6_RX_DN<98>P5E_PEX1_STN6_RX_DP<98>P5E_PEX1_STN5_RX_DN<93>P5E_PEX1_STN5_RX_DP<93>P5E_PEX1_STN6_TX_C_DN<107>P5E_PEX1_STN6_TX_C_DP<107>P5E_PEX1_STN5_TX_C_DN<84>P5E_PEX1_STN5_TX_C_DP<84>P5E_PEX1_STN6_RX_DN<107>P5E_PEX1_STN6_RX_DP<107>P5E_PEX1_STN5_RX_DN<84>P5E_PEX1_STN5_RX_DP<84>P5E_PEX1_STN6_TX_C_DN<99>P5E_PEX1_STN6_TX_C_DP<99>P5E_PEX1_STN5_TX_C_DN<92>P5E_PEX1_STN5_TX_C_DP<92>P5E_PEX1_STN6_RX_DN<99>P5E_PEX1_STN6_RX_DP<99>P5E_PEX1_STN5_RX_DN<92>P5E_PEX1_STN5_RX_DP<92>GPU_3V3IO_RSVD1_FFU_RGPU_BASE_HMC_READY_R



5
5
4
4
3
3
2
2
1
1
D D
C C
B B
A A
EXAMAX_10P8C_J12_CPU1(4/5)
DVT_CHANGEP5E_PEX1_STN6_TX_C_DN<104>[26]P5E_PEX1_STN6_TX_C_DP<104>[26]P5E_PEX1_STN5_TX_C_DN<87>[25]P5E_PEX1_STN5_TX_C_DP<87>[25]P5E_PEX1_STN6_RX_DN<104>[26]P5E_PEX1_STN6_RX_DP<104>[26]P5E_PEX1_STN5_RX_DN<87>[25]P5E_PEX1_STN5_RX_DP<87>[25]P5E_PEX1_STN6_TX_C_DN<96>[26]P5E_PEX1_STN6_TX_C_DP<96>[26]P5E_PEX1_STN5_TX_C_DN<95>[25]P5E_PEX1_STN5_TX_C_DP<95>[25]P5E_PEX1_STN6_RX_DN<96>[26]P5E_PEX1_STN6_RX_DP<96>[26]P5E_PEX1_STN5_RX_DN<95>[25]P5E_PEX1_STN5_RX_DP<95>[25]P5E_PEX1_STN6_TX_C_DN<105>[26]P5E_PEX1_STN6_TX_C_DP<105>[26]P5E_PEX1_STN5_TX_C_DN<86>[25]P5E_PEX1_STN5_TX_C_DP<86>[25]P5E_PEX1_STN6_RX_DN<105>[26]P5E_PEX1_STN6_RX_DP<105>[26]P5E_PEX1_STN5_RX_DN<86>[25]P5E_PEX1_STN5_RX_DP<86>[25]P5E_PEX1_STN6_TX_C_DN<97>[26]P5E_PEX1_STN6_TX_C_DP<97>[26]P5E_PEX1_STN5_TX_C_DN<94>[25]P5E_PEX1_STN5_TX_C_DP<94>[25]P5E_PEX1_STN6_RX_DN<97>[26]P5E_PEX1_STN6_RX_DP<97>[26]P5E_PEX1_STN5_RX_DN<94>[25]P5E_PEX1_STN5_RX_DP<94>[25]GPU_BASE_STBY_EN[165]
SizeDoc NumberRevDate: SheetofReviewerDesignerDepartmentProject
Page TitleCCBU D137 257Tuesday, August 29, 2023<project_name><Designer> GRANDTETON_SWB_20230829137 EXAMAX_10P8C_J12_CPU1(4/5)<Reviewer>SizeDoc NumberRevDate: SheetofReviewerDesignerDepartmentProject
Page TitleCCBU D137 257Tuesday, August 29, 2023<project_name><Designer> GRANDTETON_SWB_20230829137 EXAMAX_10P8C_J12_CPU1(4/5)<Reviewer>SizeDoc NumberRevDate: SheetofReviewerDesignerDepartmentProject
Page TitleCCBU D137 257Tuesday, August 29, 2023<project_name><Designer> GRANDTETON_SWB_20230829137 EXAMAX_10P8C_J12_CPU1(4/5)<Reviewer>
BA IHGFEDC J K L M NO PQ RST U V W X Y Z784/5J12DCONN270_10146445-101LFA8A8B8B8C8C8D8D8E8E8F8F8G8G8H8H8I8I8J8J8K8K8L8L8M1_8M1_8M2_8M2_8N8N8O8O8P8P8Q8Q8R8R8S8S8T8T8U8U8V8V8W8W8X8X8Y8Y8Z8Z8A7A7B7B7C7C7D7D7E7E7F7F7G7G7H7H7I7I7J7J7K7K7L7L7M7M7N1_7N1_7N2_7N2_7O7O7P7P7Q7Q7R7R7S7S7T7T7U7U7V7V7W7W7X7X7Y7Y7Z7Z7R67700R0402-02015%P5E_PEX1_STN6_TX_C_DN<104>P5E_PEX1_STN6_TX_C_DP<104>P5E_PEX1_STN5_TX_C_DN<87>P5E_PEX1_STN5_TX_C_DP<87>P5E_PEX1_STN6_RX_DN<104>P5E_PEX1_STN6_RX_DP<104>P5E_PEX1_STN5_RX_DN<87>P5E_PEX1_STN5_RX_DP<87>P5E_PEX1_STN6_TX_C_DN<96>P5E_PEX1_STN6_TX_C_DP<96>P5E_PEX1_STN5_TX_C_DN<95>P5E_PEX1_STN5_TX_C_DP<95>P5E_PEX1_STN6_RX_DN<96>P5E_PEX1_STN6_RX_DP<96>P5E_PEX1_STN5_RX_DN<95>P5E_PEX1_STN5_RX_DP<95>P5E_PEX1_STN6_TX_C_DN<105>P5E_PEX1_STN6_TX_C_DP<105>P5E_PEX1_STN5_TX_C_DN<86>P5E_PEX1_STN5_TX_C_DP<86>P5E_PEX1_STN6_RX_DN<105>P5E_PEX1_STN6_RX_DP<105>P5E_PEX1_STN5_RX_DN<86>P5E_PEX1_STN5_RX_DP<86>P5E_PEX1_STN6_TX_C_DN<97>P5E_PEX1_STN6_TX_C_DP<97>P5E_PEX1_STN5_TX_C_DN<94>P5E_PEX1_STN5_TX_C_DP<94>P5E_PEX1_STN6_RX_DN<97>P5E_PEX1_STN6_RX_DP<97>P5E_PEX1_STN5_RX_DN<94>P5E_PEX1_STN5_RX_DP<94>PRSNT_SWB_B3_NGPU_BASE_STBY_EN



5
5
4
4
3
3
2
2
1
1
D D
C C
B B
A A
FPGA, BIC PORTMB PORT
EXAMAX_10P8C_J12_CPU1(5/5)
DVT_CHANGE
SMB_MB_BMC_SDA[138]SMB_GPU2_ALERT_R_N[165]SMB_MB_BMC_SCL[138]SMB_GPU1_ALERT_R_N[165]MB_BIC_MON_BUF_R[132]GPU_FPGA_BOOT_EN[165]MB_BMC_MON[132,165]RST_GPU_FPGA_EROT_N[165]
SMB_MB_BMC_SCL[138]SMB_MB_BMC_SDA[138]SMB_MB_R_SCL [115,211]SMB_MB_R_SDA [115,211]P3V3_AUXP3V3_AUXSizeDoc NumberRevDate: SheetofReviewerDesignerDepartmentProject
Page TitleCCBU D138 257Tuesday, August 29, 2023<project_name><Designer> GRANDTETON_SWB_20230829138 EXAMAX_10P8C_J12_CPU1(5/5)<Reviewer>SizeDoc NumberRevDate: SheetofReviewerDesignerDepartmentProject
Page TitleCCBU D138 257Tuesday, August 29, 2023<project_name><Designer> GRANDTETON_SWB_20230829138 EXAMAX_10P8C_J12_CPU1(5/5)<Reviewer>SizeDoc NumberRevDate: SheetofReviewerDesignerDepartmentProject
Page TitleCCBU D138 257Tuesday, August 29, 2023<project_name><Designer> GRANDTETON_SWB_20230829138 EXAMAX_10P8C_J12_CPU1(5/5)<Reviewer>R410210KR0402-02015%C27790.1UF10%16VC0402-0201C27800.1UF10%16VN ZA I OH PG QF RE SDB TC U VJ K WL XM Y1095/5J12ECONN270_10146445-101LFA10A10B10B10C10C10D10D10E10E10F10F10G10G10H10H10I10I10J10J10K10K10L10L10M1_10M1_10M2_10M2_10N10N10O10O10P10P10Q10Q10R10R10S10S10T10T10U10U10V10V10W10W10X10X10Y10Y10Z10Z10A9A9B9B9C9C9D9D9E9E9F9F9G9G9H9H9I9I9J9J9K9K9L9L9M9M9N1_9N1_9N2_9N2_9O9O9P9P9Q9Q9R9R9S9S9T9T9U9U9V9V9W9W9X9X9Y9Y9Z9Z9
R4103 0 R0402-02015%NIU318PCA9617ADP<Part Number>EN5VCCA1VCCB8SCLA2SDAA3SDAB6SCLB7GND4R4105 0 R0402-02015%R4104 0 R0402-02015%NIR4107 33 R0402-02011%R409810KR0402-02015%NIR4106 0 R0402-02015%R409910K5%NIR4108 33 R0402-02011%R41004.7KR0402-02015%NIR410110K5%
SMB_MB_BMC_SDASMB_GPU2_ALERT_R_NSMB_MB_BMC_SCLSMB_GPU1_ALERT_R_NMB_BIC_MON_BUF_RGPU_FPGA_BOOT_ENMB_BMC_MONRST_GPU_FPGA_EROT_N
SMB_MB_BMC_R_SCLSMB_MB_BMC_ISO_SCLSMB_MB_BMC_R_SDASMB_MB_BMC_ISO_SDAMB_I2C_ISO_EN



5
5
4
4
3
3
2
2
1
1
D D
C C
B B
A A
EXAMAX_10P8C_J5_GPU13(1/5)
P5E_PEX1_STN7_RX_DN<112>[26]P5E_PEX1_STN7_RX_DP<112>[26]P5E_PEX1_STN4_RX_DN<79>[25]P5E_PEX1_STN4_RX_DP<79>[25]P5E_PEX1_STN7_TX_C_DN<112>[26]P5E_PEX1_STN7_TX_C_DP<112>[26]P5E_PEX1_STN4_TX_C_DN<79>[25]P5E_PEX1_STN4_TX_C_DP<79>[25]P5E_PEX1_STN7_RX_DN<120>[26]P5E_PEX1_STN7_RX_DP<120>[26]P5E_PEX1_STN4_RX_DN<71>[25]P5E_PEX1_STN4_RX_DP<71>[25]P5E_PEX1_STN7_TX_C_DN<120>[26]P5E_PEX1_STN7_TX_C_DP<120>[26]P5E_PEX1_STN4_TX_C_DN<71>[25]P5E_PEX1_STN4_TX_C_DP<71>[25]P5E_PEX1_STN7_RX_DN<113>[26]P5E_PEX1_STN7_RX_DP<113>[26]P5E_PEX1_STN4_RX_DN<78>[25]P5E_PEX1_STN4_RX_DP<78>[25]P5E_PEX1_STN7_TX_C_DN<113>[26]P5E_PEX1_STN7_TX_C_DP<113>[26]P5E_PEX1_STN4_TX_C_DN<78>[25]P5E_PEX1_STN4_TX_C_DP<78>[25]P5E_PEX1_STN4_RX_DN<70>[25]P5E_PEX1_STN4_RX_DP<70>[25]P5E_PEX1_STN4_TX_C_DN<70>[25]P5E_PEX1_STN4_TX_C_DP<70>[25]GPU_FPGA_EROT_RECOV_R_N[165]GPU_FPGA_EROT_FATALERR_N[165]P5E_PEX1_STN7_RX_DP<121>[26]P5E_PEX1_STN7_RX_DN<121>[26]P5E_PEX1_STN7_TX_C_DP<121>[26]P5E_PEX1_STN7_TX_C_DN<121>[26]
SizeDoc NumberRevDate: SheetofReviewerDesignerDepartmentProject
Page TitleCCBU D139 257Tuesday, August 29, 2023<project_name><Designer> GRANDTETON_SWB_20230829139 EXAMAX_10P8C_J5_GPU13(1/5)<Reviewer>SizeDoc NumberRevDate: SheetofReviewerDesignerDepartmentProject
Page TitleCCBU D139 257Tuesday, August 29, 2023<project_name><Designer> GRANDTETON_SWB_20230829139 EXAMAX_10P8C_J5_GPU13(1/5)<Reviewer>SizeDoc NumberRevDate: SheetofReviewerDesignerDepartmentProject
Page TitleCCBU D139 257Tuesday, August 29, 2023<project_name><Designer> GRANDTETON_SWB_20230829139 EXAMAX_10P8C_J5_GPU13(1/5)<Reviewer>
BA IHGFEDC J K L M NO PQ RST U V W X Y Z1
2
1/5J5ACONN270_10146445-101LFA2A2B1B1B2B2C1C1C2C2D1D1D2D2E1E1E2E2F1F1F2F2G1G1G2G2H1H1H2H2I1I1I2I2J1J1J2J2K1K1K2K2L1L1L2L2M1M1M1_2M1_2M2_2M2_2N1_1N1_1N2N2N2_1N2_1O1O1O2O2P1P1P2P2Q1Q1Q2Q2R1R1R2R2S1S1S2S2T1T1T2T2U1U1U2U2V1V1V2V2W1W1W2W2X1X1X2X2Y1Y1Y2Y2Z1Z1Z2Z2A1A1P5E_PEX1_STN7_RX_DN<112>P5E_PEX1_STN7_RX_DP<112>P5E_PEX1_STN4_RX_DN<79>P5E_PEX1_STN4_RX_DP<79>P5E_PEX1_STN7_TX_C_DN<112>P5E_PEX1_STN7_TX_C_DP<112>P5E_PEX1_STN4_TX_C_DN<79>P5E_PEX1_STN4_TX_C_DP<79>P5E_PEX1_STN7_RX_DN<120>P5E_PEX1_STN7_RX_DP<120>P5E_PEX1_STN4_RX_DN<71>P5E_PEX1_STN4_RX_DP<71>P5E_PEX1_STN7_TX_C_DN<120>P5E_PEX1_STN7_TX_C_DP<120>P5E_PEX1_STN4_TX_C_DN<71>P5E_PEX1_STN4_TX_C_DP<71>P5E_PEX1_STN7_RX_DN<113>P5E_PEX1_STN7_RX_DP<113>P5E_PEX1_STN4_RX_DN<78>P5E_PEX1_STN4_RX_DP<78>P5E_PEX1_STN7_TX_C_DN<113>P5E_PEX1_STN7_TX_C_DP<113>P5E_PEX1_STN4_TX_C_DN<78>P5E_PEX1_STN4_TX_C_DP<78>P5E_PEX1_STN4_RX_DN<70>P5E_PEX1_STN4_RX_DP<70>P5E_PEX1_STN4_TX_C_DN<70>P5E_PEX1_STN4_TX_C_DP<70>GPU_FPGA_EROT_RECOV_R_NGPU_FPGA_EROT_FATALERR_NP5E_PEX1_STN7_RX_DP<121>P5E_PEX1_STN7_RX_DN<121>P5E_PEX1_STN7_TX_C_DP<121>P5E_PEX1_STN7_TX_C_DN<121>



5
5
4
4
3
3
2
2
1
1
D D
C C
B B
A A
EXAMAX_10P8C_J5_GPU13(2/5)
P5E_PEX1_STN7_RX_DN<115>[26]P5E_PEX1_STN7_RX_DP<115>[26]P5E_PEX1_STN4_RX_DN<76>[25]P5E_PEX1_STN4_RX_DP<76>[25]P5E_PEX1_STN7_TX_C_DN<115>[26]P5E_PEX1_STN7_TX_C_DP<115>[26]P5E_PEX1_STN4_TX_C_DN<76>[25]P5E_PEX1_STN4_TX_C_DP<76>[25]P5E_PEX1_STN7_RX_DN<123>[26]P5E_PEX1_STN7_RX_DP<123>[26]P5E_PEX1_STN4_RX_DN<68>[25]P5E_PEX1_STN4_RX_DP<68>[25]P5E_PEX1_STN7_TX_C_DN<123>[26]P5E_PEX1_STN7_TX_C_DP<123>[26]P5E_PEX1_STN4_TX_C_DN<68>[25]P5E_PEX1_STN4_TX_C_DP<68>[25]P5E_PEX1_STN7_RX_DN<114>[26]P5E_PEX1_STN7_RX_DP<114>[26]P5E_PEX1_STN4_RX_DN<77>[25]P5E_PEX1_STN4_RX_DP<77>[25]P5E_PEX1_STN4_TX_C_DN<77>[25]P5E_PEX1_STN4_TX_C_DP<77>[25]P5E_PEX1_STN4_RX_DN<69>[25]P5E_PEX1_STN4_RX_DP<69>[25]P5E_PEX1_STN4_TX_C_DN<69>[25]P5E_PEX1_STN4_TX_C_DP<69>[25]GPU_3V3IO_RSVD0_FFU[165]PRSNT_GPU_HMC_N[165]P5E_PEX1_STN7_RX_DP<122>[26]P5E_PEX1_STN7_RX_DN<122>[26]P5E_PEX1_STN7_TX_C_DP<122>[26]P5E_PEX1_STN7_TX_C_DN<122>[26]P5E_PEX1_STN7_TX_C_DN<114>[26]P5E_PEX1_STN7_TX_C_DP<114>[26]
SizeDoc NumberRevDate: SheetofReviewerDesignerDepartmentProject
Page TitleCCBU D140 257Tuesday, August 29, 2023<project_name><Designer> GRANDTETON_SWB_20230829140 EXAMAX_10P8C_J5_GPU13(2/5)<Reviewer>SizeDoc NumberRevDate: SheetofReviewerDesignerDepartmentProject
Page TitleCCBU D140 257Tuesday, August 29, 2023<project_name><Designer> GRANDTETON_SWB_20230829140 EXAMAX_10P8C_J5_GPU13(2/5)<Reviewer>SizeDoc NumberRevDate: SheetofReviewerDesignerDepartmentProject
Page TitleCCBU D140 257Tuesday, August 29, 2023<project_name><Designer> GRANDTETON_SWB_20230829140 EXAMAX_10P8C_J5_GPU13(2/5)<Reviewer>
BA IHGFEDC J K L M NO PQ R S T U V W X Y Z432/5J5BCONN270_10146445-101LFA4A4B4B4C4C4D4D4E4E4F4F4G4G4H4H4I4I4J4J4K4K4L4L4M1_4M1_4M2_4M2_4N4N4O4O4P4P4Q4Q4R4R4S4S4T4T4U4U4V4V4W4W4X4X4Y4Y4Z4Z4A3A3B3B3C3C3D3D3E3E3F3F3G3G3H3H3I3I3J3J3K3K3L3L3M3M3N1_3N1_3N2_3N2_3O3O3P3P3Q3Q3R3R3S3S3T3T3U3U3V3V3W3W3X3X3Y3Y3Z3Z3P5E_PEX1_STN7_RX_DN<115>P5E_PEX1_STN7_RX_DP<115>P5E_PEX1_STN4_RX_DN<76>P5E_PEX1_STN4_RX_DP<76>P5E_PEX1_STN7_TX_C_DN<115>P5E_PEX1_STN7_TX_C_DP<115>P5E_PEX1_STN4_TX_C_DN<76>P5E_PEX1_STN4_TX_C_DP<76>P5E_PEX1_STN7_RX_DN<123>P5E_PEX1_STN7_RX_DP<123>P5E_PEX1_STN4_RX_DN<68>P5E_PEX1_STN4_RX_DP<68>P5E_PEX1_STN7_TX_C_DN<123>P5E_PEX1_STN7_TX_C_DP<123>P5E_PEX1_STN4_TX_C_DN<68>P5E_PEX1_STN4_TX_C_DP<68>P5E_PEX1_STN7_RX_DN<114>P5E_PEX1_STN7_RX_DP<114>P5E_PEX1_STN4_RX_DN<77>P5E_PEX1_STN4_RX_DP<77>P5E_PEX1_STN4_TX_C_DN<77>P5E_PEX1_STN4_TX_C_DP<77>P5E_PEX1_STN4_RX_DN<69>P5E_PEX1_STN4_RX_DP<69>P5E_PEX1_STN4_TX_C_DN<69>P5E_PEX1_STN4_TX_C_DP<69>GPU_3V3IO_RSVD0_FFUPRSNT_GPU_HMC_NP5E_PEX1_STN7_RX_DP<122>P5E_PEX1_STN7_RX_DN<122>P5E_PEX1_STN7_TX_C_DP<122>P5E_PEX1_STN7_TX_C_DN<122>P5E_PEX1_STN7_TX_C_DN<114>P5E_PEX1_STN7_TX_C_DP<114>



5
5
4
4
3
3
2
2
1
1
D D
C C
B B
A A
EXAMAX_10P8C_J5_GPU13(3/5)
P5E_PEX1_STN7_RX_DN<117>[26]P5E_PEX1_STN7_RX_DP<117>[26]P5E_PEX1_STN4_RX_DN<74>[25]P5E_PEX1_STN4_RX_DP<74>[25]P5E_PEX1_STN7_TX_C_DN<117>[26]P5E_PEX1_STN7_TX_C_DP<117>[26]P5E_PEX1_STN4_TX_C_DN<74>[25]P5E_PEX1_STN4_TX_C_DP<74>[25]P5E_PEX1_STN7_RX_DN<125>[26]P5E_PEX1_STN7_RX_DP<125>[26]P5E_PEX1_STN4_RX_DN<66>[25]P5E_PEX1_STN4_RX_DP<66>[25]P5E_PEX1_STN7_TX_C_DN<125>[26]P5E_PEX1_STN7_TX_C_DP<125>[26]P5E_PEX1_STN4_TX_C_DN<66>[25]P5E_PEX1_STN4_TX_C_DP<66>[25]P5E_PEX1_STN7_RX_DN<116>[26]P5E_PEX1_STN7_RX_DP<116>[26]P5E_PEX1_STN4_RX_DN<75>[25]P5E_PEX1_STN4_RX_DP<75>[25]P5E_PEX1_STN7_TX_C_DN<116>[26]P5E_PEX1_STN7_TX_C_DP<116>[26]P5E_PEX1_STN4_TX_C_DN<75>[25]P5E_PEX1_STN4_TX_C_DP<75>[25]P5E_PEX1_STN7_RX_DN<124>[26]P5E_PEX1_STN7_RX_DP<124>[26]P5E_PEX1_STN4_RX_DN<67>[25]P5E_PEX1_STN4_RX_DP<67>[25]P5E_PEX1_STN7_TX_C_DN<124>[26]P5E_PEX1_STN7_TX_C_DP<124>[26]P5E_PEX1_STN4_TX_C_DN<67>[25]P5E_PEX1_STN4_TX_C_DP<67>[25]GPU_BASE_HMC_READY[165]GPU_3V3IO_RSVD1_FFU[165]
SizeDoc NumberRevDate: SheetofReviewerDesignerDepartmentProject
Page TitleCCBU D141 257Tuesday, August 29, 2023<project_name><Designer> GRANDTETON_SWB_20230829141 EXAMAX_10P8C_J5_GPU13(3/5)<Reviewer>SizeDoc NumberRevDate: SheetofReviewerDesignerDepartmentProject
Page TitleCCBU D141 257Tuesday, August 29, 2023<project_name><Designer> GRANDTETON_SWB_20230829141 EXAMAX_10P8C_J5_GPU13(3/5)<Reviewer>SizeDoc NumberRevDate: SheetofReviewerDesignerDepartmentProject
Page TitleCCBU D141 257Tuesday, August 29, 2023<project_name><Designer> GRANDTETON_SWB_20230829141 EXAMAX_10P8C_J5_GPU13(3/5)<Reviewer>
BA IHGFEDC J K L M NO PQ RST U V W X Y Z563/5J5CCONN270_10146445-101LFA6A6B6B6C6C6D6D6E6E6F6F6G6G6H6H6I6I6J6J6K6K6L6L6M1_6M1_6M2_6M2_6N6N6O6O6P6P6Q6Q6R6R6S6S6T6T6U6U6V6V6W6W6X6X6Y6Y6Z6Z6A5A5B5B5C5C5D5D5E5E5F5F5G5G5H5H5I5I5J5J5K5K5L5L5M5M5N1_5N1_5N2_5N2_5O5O5P5P5Q5Q5R5R5S5S5T5T5U5U5V5V5W5W5X5X5Y5Y5Z5Z5P5E_PEX1_STN7_RX_DN<117>P5E_PEX1_STN7_RX_DP<117>P5E_PEX1_STN4_RX_DN<74>P5E_PEX1_STN4_RX_DP<74>P5E_PEX1_STN7_TX_C_DN<117>P5E_PEX1_STN7_TX_C_DP<117>P5E_PEX1_STN4_TX_C_DN<74>P5E_PEX1_STN4_TX_C_DP<74>P5E_PEX1_STN7_RX_DN<125>P5E_PEX1_STN7_RX_DP<125>P5E_PEX1_STN4_RX_DN<66>P5E_PEX1_STN4_RX_DP<66>P5E_PEX1_STN7_TX_C_DN<125>P5E_PEX1_STN7_TX_C_DP<125>P5E_PEX1_STN4_TX_C_DN<66>P5E_PEX1_STN4_TX_C_DP<66>P5E_PEX1_STN7_RX_DN<116>P5E_PEX1_STN7_RX_DP<116>P5E_PEX1_STN4_RX_DN<75>P5E_PEX1_STN4_RX_DP<75>P5E_PEX1_STN7_TX_C_DN<116>P5E_PEX1_STN7_TX_C_DP<116>P5E_PEX1_STN4_TX_C_DN<75>P5E_PEX1_STN4_TX_C_DP<75>P5E_PEX1_STN7_RX_DN<124>P5E_PEX1_STN7_RX_DP<124>P5E_PEX1_STN4_RX_DN<67>P5E_PEX1_STN4_RX_DP<67>P5E_PEX1_STN7_TX_C_DN<124>P5E_PEX1_STN7_TX_C_DP<124>P5E_PEX1_STN4_TX_C_DN<67>P5E_PEX1_STN4_TX_C_DP<67>GPU_BASE_HMC_READYGPU_3V3IO_RSVD1_FFU



5
5
4
4
3
3
2
2
1
1
D D
C C
B B
A A
EXAMAX_10P8C_J5_GPU13(4/5)
DVT_CHANGEDVT_CHANGE
P5E_PEX1_STN7_RX_DN<119>[26]P5E_PEX1_STN7_RX_DP<119>[26]P5E_PEX1_STN4_RX_DN<72>[25]P5E_PEX1_STN4_RX_DP<72>[25]P5E_PEX1_STN7_TX_C_DN<119>[26]P5E_PEX1_STN7_TX_C_DP<119>[26]P5E_PEX1_STN4_TX_C_DN<72>[25]P5E_PEX1_STN4_TX_C_DP<72>[25]P5E_PEX1_STN7_RX_DN<127>[26]P5E_PEX1_STN7_RX_DP<127>[26]P5E_PEX1_STN4_RX_DN<64>[25]P5E_PEX1_STN4_RX_DP<64>[25]P5E_PEX1_STN7_TX_C_DN<127>[26]P5E_PEX1_STN7_TX_C_DP<127>[26]P5E_PEX1_STN4_TX_C_DN<64>[25]P5E_PEX1_STN4_TX_C_DP<64>[25]P5E_PEX1_STN7_RX_DN<118>[26]P5E_PEX1_STN7_RX_DP<118>[26]P5E_PEX1_STN4_RX_DN<73>[25]P5E_PEX1_STN4_RX_DP<73>[25]P5E_PEX1_STN7_TX_C_DN<118>[26]P5E_PEX1_STN7_TX_C_DP<118>[26]P5E_PEX1_STN4_TX_C_DN<73>[25]P5E_PEX1_STN4_TX_C_DP<73>[25]P5E_PEX1_STN7_RX_DN<126>[26]P5E_PEX1_STN7_RX_DP<126>[26]P5E_PEX1_STN4_RX_DN<65>[25]P5E_PEX1_STN4_RX_DP<65>[25]P5E_PEX1_STN7_TX_C_DN<126>[26]P5E_PEX1_STN7_TX_C_DP<126>[26]P5E_PEX1_STN4_TX_C_DN<65>[25]P5E_PEX1_STN4_TX_C_DP<65>[25]GPU_BASE_STBY_EN_R[165]PRSNT_GPU_A3_N[142]PRSNT_GPU_A3_R_N[153]PRSNT_GPU_A3_N [142]SizeDoc NumberRevDate: SheetofReviewerDesignerDepartmentProject
Page TitleCCBU D142 257Tuesday, August 29, 2023<project_name><Designer> GRANDTETON_SWB_20230829142 EXAMAX_10P8C_J5_GPU13(4/5)<Reviewer>SizeDoc NumberRevDate: SheetofReviewerDesignerDepartmentProject
Page TitleCCBU D142 257Tuesday, August 29, 2023<project_name><Designer> GRANDTETON_SWB_20230829142 EXAMAX_10P8C_J5_GPU13(4/5)<Reviewer>SizeDoc NumberRevDate: SheetofReviewerDesignerDepartmentProject
Page TitleCCBU D142 257Tuesday, August 29, 2023<project_name><Designer> GRANDTETON_SWB_20230829142 EXAMAX_10P8C_J5_GPU13(4/5)<Reviewer>
BA IHGFEDC J K L M NO PQ RST U V W X Y Z784/5J5DCONN270_10146445-101LFA8A8B8B8C8C8D8D8E8E8F8F8G8G8H8H8I8I8J8J8K8K8L8L8M1_8M1_8M2_8M2_8N8N8O8O8P8P8Q8Q8R8R8S8S8T8T8U8U8V8V8W8W8X8X8Y8Y8Z8Z8A7A7B7B7C7C7D7D7E7E7F7F7G7G7H7H7I7I7J7J7K7K7L7L7M7M7N1_7N1_7N2_7N2_7O7O7P7P7Q7Q7R7R7S7S7T7T7U7U7V7V7W7W7X7X7Y7Y7Z7Z7R6773 0 R0402-02015%
P5E_PEX1_STN7_RX_DN<119>P5E_PEX1_STN7_RX_DP<119>P5E_PEX1_STN4_RX_DN<72>P5E_PEX1_STN4_RX_DP<72>P5E_PEX1_STN7_TX_C_DN<119>P5E_PEX1_STN7_TX_C_DP<119>P5E_PEX1_STN4_TX_C_DN<72>P5E_PEX1_STN4_TX_C_DP<72>P5E_PEX1_STN7_RX_DN<127>P5E_PEX1_STN7_RX_DP<127>P5E_PEX1_STN4_RX_DN<64>P5E_PEX1_STN4_RX_DP<64>P5E_PEX1_STN7_TX_C_DN<127>P5E_PEX1_STN7_TX_C_DP<127>P5E_PEX1_STN4_TX_C_DN<64>P5E_PEX1_STN4_TX_C_DP<64>P5E_PEX1_STN7_RX_DN<118>P5E_PEX1_STN7_RX_DP<118>P5E_PEX1_STN4_RX_DN<73>P5E_PEX1_STN4_RX_DP<73>P5E_PEX1_STN7_TX_C_DN<118>P5E_PEX1_STN7_TX_C_DP<118>P5E_PEX1_STN4_TX_C_DN<73>P5E_PEX1_STN4_TX_C_DP<73>P5E_PEX1_STN7_RX_DN<126>P5E_PEX1_STN7_RX_DP<126>P5E_PEX1_STN4_RX_DN<65>P5E_PEX1_STN4_RX_DP<65>P5E_PEX1_STN7_TX_C_DN<126>P5E_PEX1_STN7_TX_C_DP<126>P5E_PEX1_STN4_TX_C_DN<65>P5E_PEX1_STN4_TX_C_DP<65>GPU_BASE_STBY_EN_RPRSNT_GPU_A3_R_NPRSNT_GPU_A3_N



5
5
4
4
3
3
2
2
1
1
D D
C C
B B
A A
EXAMAX_10P8C_J5_GPU13(5/5)
SMB_GPU2_ALERT_N[165]GPU_RSVD_PARTNER2SMB_GPU1_ALERT_N[165]GPU_RSVD_PARTNER1GPU_FPGA_BOOT_EN_R[165]GPU_RSVD_PARTNER0RST_GPU_FPGA_EROT_R_N[165]
SizeDoc NumberRevDate: SheetofReviewerDesignerDepartmentProject
Page TitleCCBU D143 257Tuesday, August 29, 2023<project_name><Designer> GRANDTETON_SWB_20230829143 EXAMAX_10P8C_J5_GPU13(5/5)<Reviewer>SizeDoc NumberRevDate: SheetofReviewerDesignerDepartmentProject
Page TitleCCBU D143 257Tuesday, August 29, 2023<project_name><Designer> GRANDTETON_SWB_20230829143 EXAMAX_10P8C_J5_GPU13(5/5)<Reviewer>SizeDoc NumberRevDate: SheetofReviewerDesignerDepartmentProject
Page TitleCCBU D143 257Tuesday, August 29, 2023<project_name><Designer> GRANDTETON_SWB_20230829143 EXAMAX_10P8C_J5_GPU13(5/5)<Reviewer>
N ZA I OH PG QF RE SDB TC U VJ K WL XM Y1095/5J5ECONN270_10146445-101LFA10A10B10B10C10C10D10D10E10E10F10F10G10G10H10H10I10I10J10J10K10K10L10L10M1_10M1_10M2_10M2_10N10N10O10O10P10P10Q10Q10R10R10S10S10T10T10U10U10V10V10W10W10X10X10Y10Y10Z10Z10A9A9B9B9C9C9D9D9E9E9F9F9G9G9H9H9I9I9J9J9K9K9L9L9M9M9N1_9N1_9N2_9N2_9O9O9P9P9Q9Q9R9R9S9S9T9T9U9U9V9V9W9W9X9X9Y9Y9Z9Z9SMB_GPU2_ALERT_NGPU_RSVD_PARTNER2SMB_GPU1_ALERT_NGPU_RSVD_PARTNER1GPU_FPGA_BOOT_EN_RGPU_RSVD_PARTNER0RST_GPU_FPGA_EROT_R_N



5
5
4
4
3
3
2
2
1
1
D D
C C
B B
A A
EXAMAX_10P8C_J7_GPU68(1/5)
P5E_PEX2_STN7_RX_DN<112>[39]P5E_PEX2_STN7_RX_DP<112>[39]P5E_PEX2_STN4_RX_DN<79>[38]P5E_PEX2_STN4_RX_DP<79>[38]P5E_PEX2_STN7_TX_C_DN<112>[39]P5E_PEX2_STN7_TX_C_DP<112>[39]P5E_PEX2_STN4_TX_C_DN<79>[38]P5E_PEX2_STN4_TX_C_DP<79>[38]P5E_PEX2_STN7_RX_DN<120>[39]P5E_PEX2_STN7_RX_DP<120>[39]P5E_PEX2_STN4_RX_DN<71>[38]P5E_PEX2_STN4_RX_DP<71>[38]P5E_PEX2_STN7_TX_C_DN<120>[39]P5E_PEX2_STN7_TX_C_DP<120>[39]P5E_PEX2_STN4_TX_C_DN<71>[38]P5E_PEX2_STN4_TX_C_DP<71>[38]P5E_PEX2_STN7_RX_DN<113>[39]P5E_PEX2_STN7_RX_DP<113>[39]P5E_PEX2_STN4_RX_DN<78>[38]P5E_PEX2_STN4_RX_DP<78>[38]P5E_PEX2_STN7_TX_C_DN<113>[39]P5E_PEX2_STN7_TX_C_DP<113>[39]P5E_PEX2_STN4_TX_C_DN<78>[38]P5E_PEX2_STN4_TX_C_DP<78>[38]P5E_PEX2_STN4_RX_DN<70>[38]P5E_PEX2_STN4_RX_DP<70>[38]P5E_PEX2_STN4_TX_C_DN<70>[38]P5E_PEX2_STN4_TX_C_DP<70>[38]GPU_3V3IO_RSVD3_FFU[166]P5E_PEX2_STN7_RX_DP<121>[39]P5E_PEX2_STN7_RX_DN<121>[39]P5E_PEX2_STN7_TX_C_DP<121>[39]P5E_PEX2_STN7_TX_C_DN<121>[39]
SizeDoc NumberRevDate: SheetofReviewerDesignerDepartmentProject
Page TitleCCBU D144 257Tuesday, August 29, 2023<project_name><Designer> GRANDTETON_SWB_20230829144 EXAMAX_10P8C_J7_GPU68(1/5)<Reviewer>SizeDoc NumberRevDate: SheetofReviewerDesignerDepartmentProject
Page TitleCCBU D144 257Tuesday, August 29, 2023<project_name><Designer> GRANDTETON_SWB_20230829144 EXAMAX_10P8C_J7_GPU68(1/5)<Reviewer>SizeDoc NumberRevDate: SheetofReviewerDesignerDepartmentProject
Page TitleCCBU D144 257Tuesday, August 29, 2023<project_name><Designer> GRANDTETON_SWB_20230829144 EXAMAX_10P8C_J7_GPU68(1/5)<Reviewer>
BA IHGFEDC J K L M NO PQ RST U V W X Y Z1
2
1/5J7ACONN270_10146445-101LFA2A2B1B1B2B2C1C1C2C2D1D1D2D2E1E1E2E2F1F1F2F2G1G1G2G2H1H1H2H2I1I1I2I2J1J1J2J2K1K1K2K2L1L1L2L2M1M1M1_2M1_2M2_2M2_2N1_1N1_1N2N2N2_1N2_1O1O1O2O2P1P1P2P2Q1Q1Q2Q2R1R1R2R2S1S1S2S2T1T1T2T2U1U1U2U2V1V1V2V2W1W1W2W2X1X1X2X2Y1Y1Y2Y2Z1Z1Z2Z2A1A1P5E_PEX2_STN7_RX_DN<112>P5E_PEX2_STN7_RX_DP<112>P5E_PEX2_STN4_RX_DN<79>P5E_PEX2_STN4_RX_DP<79>P5E_PEX2_STN7_TX_C_DN<112>P5E_PEX2_STN7_TX_C_DP<112>P5E_PEX2_STN4_TX_C_DN<79>P5E_PEX2_STN4_TX_C_DP<79>P5E_PEX2_STN7_RX_DN<120>P5E_PEX2_STN7_RX_DP<120>P5E_PEX2_STN4_RX_DN<71>P5E_PEX2_STN4_RX_DP<71>P5E_PEX2_STN7_TX_C_DN<120>P5E_PEX2_STN7_TX_C_DP<120>P5E_PEX2_STN4_TX_C_DN<71>P5E_PEX2_STN4_TX_C_DP<71>P5E_PEX2_STN7_RX_DN<113>P5E_PEX2_STN7_RX_DP<113>P5E_PEX2_STN4_RX_DN<78>P5E_PEX2_STN4_RX_DP<78>P5E_PEX2_STN7_TX_C_DN<113>P5E_PEX2_STN7_TX_C_DP<113>P5E_PEX2_STN4_TX_C_DN<78>P5E_PEX2_STN4_TX_C_DP<78>P5E_PEX2_STN4_RX_DN<70>P5E_PEX2_STN4_RX_DP<70>P5E_PEX2_STN4_TX_C_DN<70>P5E_PEX2_STN4_TX_C_DP<70>GPU_3V3IO_RSVD3_FFUP5E_PEX2_STN7_RX_DP<121>P5E_PEX2_STN7_RX_DN<121>P5E_PEX2_STN7_TX_C_DP<121>P5E_PEX2_STN7_TX_C_DN<121>



5
5
4
4
3
3
2
2
1
1
D D
C C
B B
A A
EXAMAX_10P8C_J7_GPU68(2/5)
DVT_CHANGEDVT_CHANGE
P5E_PEX2_STN7_RX_DN<115>[39]P5E_PEX2_STN7_RX_DP<115>[39]P5E_PEX2_STN4_RX_DN<76>[38]P5E_PEX2_STN4_RX_DP<76>[38]P5E_PEX2_STN7_TX_C_DN<115>[39]P5E_PEX2_STN7_TX_C_DP<115>[39]P5E_PEX2_STN4_TX_C_DN<76>[38]P5E_PEX2_STN4_TX_C_DP<76>[38]P5E_PEX2_STN7_RX_DN<123>[39]P5E_PEX2_STN7_RX_DP<123>[39]P5E_PEX2_STN4_RX_DN<68>[38]P5E_PEX2_STN4_RX_DP<68>[38]P5E_PEX2_STN7_TX_C_DN<123>[39]P5E_PEX2_STN7_TX_C_DP<123>[39]P5E_PEX2_STN4_TX_C_DN<68>[38]P5E_PEX2_STN4_TX_C_DP<68>[38]P5E_PEX2_STN7_RX_DN<114>[39]P5E_PEX2_STN7_RX_DP<114>[39]P5E_PEX2_STN4_RX_DN<77>[38]P5E_PEX2_STN4_RX_DP<77>[38]P5E_PEX2_STN4_TX_C_DN<77>[38]P5E_PEX2_STN4_TX_C_DP<77>[38]P5E_PEX2_STN4_RX_DN<69>[38]P5E_PEX2_STN4_RX_DP<69>[38]P5E_PEX2_STN4_TX_C_DN<69>[38]P5E_PEX2_STN4_TX_C_DP<69>[38]P5E_PEX2_STN7_RX_DP<122>[39]P5E_PEX2_STN7_RX_DN<122>[39]P5E_PEX2_STN7_TX_C_DP<122>[39]P5E_PEX2_STN7_TX_C_DN<122>[39]P5E_PEX2_STN7_TX_C_DN<114>[39]P5E_PEX2_STN7_TX_C_DP<114>[39]PRSNT_GPU_A2_N[145]PRSNT_GPU_A2_R_N[150]PRSNT_GPU_A2_N [145]SizeDoc NumberRevDate: SheetofReviewerDesignerDepartmentProject
Page TitleCCBU D145 257Tuesday, August 29, 2023<project_name><Designer> GRANDTETON_SWB_20230829145 EXAMAX_10P8C_J7_GPU68(2/5)<Reviewer>SizeDoc NumberRevDate: SheetofReviewerDesignerDepartmentProject
Page TitleCCBU D145 257Tuesday, August 29, 2023<project_name><Designer> GRANDTETON_SWB_20230829145 EXAMAX_10P8C_J7_GPU68(2/5)<Reviewer>SizeDoc NumberRevDate: SheetofReviewerDesignerDepartmentProject
Page TitleCCBU D145 257Tuesday, August 29, 2023<project_name><Designer> GRANDTETON_SWB_20230829145 EXAMAX_10P8C_J7_GPU68(2/5)<Reviewer>R6774 0 R0402-02015%BA IHGFEDC J K L M NO PQ R S T U V W X Y Z432/5J7BCONN270_10146445-101LFA4A4B4B4C4C4D4D4E4E4F4F4G4G4H4H4I4I4J4J4K4K4L4L4M1_4M1_4M2_4M2_4N4N4O4O4P4P4Q4Q4R4R4S4S4T4T4U4U4V4V4W4W4X4X4Y4Y4Z4Z4A3A3B3B3C3C3D3D3E3E3F3F3G3G3H3H3I3I3J3J3K3K3L3L3M3M3N1_3N1_3N2_3N2_3O3O3P3P3Q3Q3R3R3S3S3T3T3U3U3V3V3W3W3X3X3Y3Y3Z3Z3P5E_PEX2_STN7_RX_DN<115>P5E_PEX2_STN7_RX_DP<115>P5E_PEX2_STN4_RX_DN<76>P5E_PEX2_STN4_RX_DP<76>P5E_PEX2_STN7_TX_C_DN<115>P5E_PEX2_STN7_TX_C_DP<115>P5E_PEX2_STN4_TX_C_DN<76>P5E_PEX2_STN4_TX_C_DP<76>P5E_PEX2_STN7_RX_DN<123>P5E_PEX2_STN7_RX_DP<123>P5E_PEX2_STN4_RX_DN<68>P5E_PEX2_STN4_RX_DP<68>P5E_PEX2_STN7_TX_C_DN<123>P5E_PEX2_STN7_TX_C_DP<123>P5E_PEX2_STN4_TX_C_DN<68>P5E_PEX2_STN4_TX_C_DP<68>P5E_PEX2_STN7_RX_DN<114>P5E_PEX2_STN7_RX_DP<114>P5E_PEX2_STN4_RX_DN<77>P5E_PEX2_STN4_RX_DP<77>P5E_PEX2_STN4_TX_C_DN<77>P5E_PEX2_STN4_TX_C_DP<77>P5E_PEX2_STN4_RX_DN<69>P5E_PEX2_STN4_RX_DP<69>P5E_PEX2_STN4_TX_C_DN<69>P5E_PEX2_STN4_TX_C_DP<69>PRSNT_GPU_A2_NP5E_PEX2_STN7_RX_DP<122>P5E_PEX2_STN7_RX_DN<122>P5E_PEX2_STN7_TX_C_DP<122>P5E_PEX2_STN7_TX_C_DN<122>P5E_PEX2_STN7_TX_C_DN<114>P5E_PEX2_STN7_TX_C_DP<114>PRSNT_GPU_A2_R_NPRSNT_GPU_A2_N



5
5
4
4
3
3
2
2
1
1
D D
C C
B B
A A
EXAMAX_10P8C_J7_GPU68(3/5)
P5E_PEX2_STN7_RX_DN<117>[39]P5E_PEX2_STN7_RX_DP<117>[39]P5E_PEX2_STN4_RX_DN<74>[38]P5E_PEX2_STN4_RX_DP<74>[38]P5E_PEX2_STN7_TX_C_DN<117>[39]P5E_PEX2_STN7_TX_C_DP<117>[39]P5E_PEX2_STN4_TX_C_DN<74>[38]P5E_PEX2_STN4_TX_C_DP<74>[38]P5E_PEX2_STN7_RX_DN<125>[39]P5E_PEX2_STN7_RX_DP<125>[39]P5E_PEX2_STN4_RX_DN<66>[38]P5E_PEX2_STN4_RX_DP<66>[38]P5E_PEX2_STN7_TX_C_DN<125>[39]P5E_PEX2_STN7_TX_C_DP<125>[39]P5E_PEX2_STN4_TX_C_DN<66>[38]P5E_PEX2_STN4_TX_C_DP<66>[38]P5E_PEX2_STN7_RX_DN<116>[39]P5E_PEX2_STN7_RX_DP<116>[39]P5E_PEX2_STN4_RX_DN<75>[38]P5E_PEX2_STN4_RX_DP<75>[38]P5E_PEX2_STN7_TX_C_DN<116>[39]P5E_PEX2_STN7_TX_C_DP<116>[39]P5E_PEX2_STN4_TX_C_DN<75>[38]P5E_PEX2_STN4_TX_C_DP<75>[38]P5E_PEX2_STN7_RX_DN<124>[39]P5E_PEX2_STN7_RX_DP<124>[39]P5E_PEX2_STN4_RX_DN<67>[38]P5E_PEX2_STN4_RX_DP<67>[38]P5E_PEX2_STN7_TX_C_DN<124>[39]P5E_PEX2_STN7_TX_C_DP<124>[39]P5E_PEX2_STN4_TX_C_DN<67>[38]P5E_PEX2_STN4_TX_C_DP<67>[38]GPU_3V3IO_RSVD5_FFU[166]
SizeDoc NumberRevDate: SheetofReviewerDesignerDepartmentProject
Page TitleCCBU D146 257Tuesday, August 29, 2023<project_name><Designer> GRANDTETON_SWB_20230829146 EXAMAX_10P8C_J7_GPU68(3/5)<Reviewer>SizeDoc NumberRevDate: SheetofReviewerDesignerDepartmentProject
Page TitleCCBU D146 257Tuesday, August 29, 2023<project_name><Designer> GRANDTETON_SWB_20230829146 EXAMAX_10P8C_J7_GPU68(3/5)<Reviewer>SizeDoc NumberRevDate: SheetofReviewerDesignerDepartmentProject
Page TitleCCBU D146 257Tuesday, August 29, 2023<project_name><Designer> GRANDTETON_SWB_20230829146 EXAMAX_10P8C_J7_GPU68(3/5)<Reviewer>
BA IHGFEDC J K L M NO PQ RST U V W X Y Z563/5J7CCONN270_10146445-101LFA6A6B6B6C6C6D6D6E6E6F6F6G6G6H6H6I6I6J6J6K6K6L6L6M1_6M1_6M2_6M2_6N6N6O6O6P6P6Q6Q6R6R6S6S6T6T6U6U6V6V6W6W6X6X6Y6Y6Z6Z6A5A5B5B5C5C5D5D5E5E5F5F5G5G5H5H5I5I5J5J5K5K5L5L5M5M5N1_5N1_5N2_5N2_5O5O5P5P5Q5Q5R5R5S5S5T5T5U5U5V5V5W5W5X5X5Y5Y5Z5Z5P5E_PEX2_STN7_RX_DN<117>P5E_PEX2_STN7_RX_DP<117>P5E_PEX2_STN4_RX_DN<74>P5E_PEX2_STN4_RX_DP<74>P5E_PEX2_STN7_TX_C_DN<117>P5E_PEX2_STN7_TX_C_DP<117>P5E_PEX2_STN4_TX_C_DN<74>P5E_PEX2_STN4_TX_C_DP<74>P5E_PEX2_STN7_RX_DN<125>P5E_PEX2_STN7_RX_DP<125>P5E_PEX2_STN4_RX_DN<66>P5E_PEX2_STN4_RX_DP<66>P5E_PEX2_STN7_TX_C_DN<125>P5E_PEX2_STN7_TX_C_DP<125>P5E_PEX2_STN4_TX_C_DN<66>P5E_PEX2_STN4_TX_C_DP<66>P5E_PEX2_STN7_RX_DN<116>P5E_PEX2_STN7_RX_DP<116>P5E_PEX2_STN4_RX_DN<75>P5E_PEX2_STN4_RX_DP<75>P5E_PEX2_STN7_TX_C_DN<116>P5E_PEX2_STN7_TX_C_DP<116>P5E_PEX2_STN4_TX_C_DN<75>P5E_PEX2_STN4_TX_C_DP<75>P5E_PEX2_STN7_RX_DN<124>P5E_PEX2_STN7_RX_DP<124>P5E_PEX2_STN4_RX_DN<67>P5E_PEX2_STN4_RX_DP<67>P5E_PEX2_STN7_TX_C_DN<124>P5E_PEX2_STN7_TX_C_DP<124>P5E_PEX2_STN4_TX_C_DN<67>P5E_PEX2_STN4_TX_C_DP<67>GPU_3V3IO_RSVD5_FFU



5
5
4
4
3
3
2
2
1
1
D D
C C
B B
A A
EXAMAX_10P8C_J7_GPU68(4/5)
P5E_PEX2_STN7_RX_DN<119>[39]P5E_PEX2_STN7_RX_DP<119>[39]P5E_PEX2_STN4_RX_DN<72>[38]P5E_PEX2_STN4_RX_DP<72>[38]P5E_PEX2_STN7_TX_C_DN<119>[39]P5E_PEX2_STN7_TX_C_DP<119>[39]P5E_PEX2_STN4_TX_C_DN<72>[38]P5E_PEX2_STN4_TX_C_DP<72>[38]P5E_PEX2_STN7_RX_DN<127>[39]P5E_PEX2_STN7_RX_DP<127>[39]P5E_PEX2_STN4_RX_DN<64>[38]P5E_PEX2_STN4_RX_DP<64>[38]P5E_PEX2_STN7_TX_C_DN<127>[39]P5E_PEX2_STN7_TX_C_DP<127>[39]P5E_PEX2_STN4_TX_C_DN<64>[38]P5E_PEX2_STN4_TX_C_DP<64>[38]P5E_PEX2_STN7_RX_DN<118>[39]P5E_PEX2_STN7_RX_DP<118>[39]P5E_PEX2_STN4_RX_DN<73>[38]P5E_PEX2_STN4_RX_DP<73>[38]P5E_PEX2_STN7_TX_C_DN<118>[39]P5E_PEX2_STN7_TX_C_DP<118>[39]P5E_PEX2_STN4_TX_C_DN<73>[38]P5E_PEX2_STN4_TX_C_DP<73>[38]P5E_PEX2_STN7_RX_DN<126>[39]P5E_PEX2_STN7_RX_DP<126>[39]P5E_PEX2_STN4_RX_DN<65>[38]P5E_PEX2_STN4_RX_DP<65>[38]P5E_PEX2_STN7_TX_C_DN<126>[39]P5E_PEX2_STN7_TX_C_DP<126>[39]P5E_PEX2_STN4_TX_C_DN<65>[38]P5E_PEX2_STN4_TX_C_DP<65>[38]GPU_FPGA_OVERT_N[166]
SizeDoc NumberRevDate: SheetofReviewerDesignerDepartmentProject
Page TitleCCBU D147 257Tuesday, August 29, 2023<project_name><Designer> GRANDTETON_SWB_20230829147 EXAMAX_10P8C_J7_GPU68(4/5)<Reviewer>SizeDoc NumberRevDate: SheetofReviewerDesignerDepartmentProject
Page TitleCCBU D147 257Tuesday, August 29, 2023<project_name><Designer> GRANDTETON_SWB_20230829147 EXAMAX_10P8C_J7_GPU68(4/5)<Reviewer>SizeDoc NumberRevDate: SheetofReviewerDesignerDepartmentProject
Page TitleCCBU D147 257Tuesday, August 29, 2023<project_name><Designer> GRANDTETON_SWB_20230829147 EXAMAX_10P8C_J7_GPU68(4/5)<Reviewer>
BA IHGFEDC J K L M NO PQ RST U V W X Y Z784/5J7DCONN270_10146445-101LFA8A8B8B8C8C8D8D8E8E8F8F8G8G8H8H8I8I8J8J8K8K8L8L8M1_8M1_8M2_8M2_8N8N8O8O8P8P8Q8Q8R8R8S8S8T8T8U8U8V8V8W8W8X8X8Y8Y8Z8Z8A7A7B7B7C7C7D7D7E7E7F7F7G7G7H7H7I7I7J7J7K7K7L7L7M7M7N1_7N1_7N2_7N2_7O7O7P7P7Q7Q7R7R7S7S7T7T7U7U7V7V7W7W7X7X7Y7Y7Z7Z7P5E_PEX2_STN7_RX_DN<119>P5E_PEX2_STN7_RX_DP<119>P5E_PEX2_STN4_RX_DN<72>P5E_PEX2_STN4_RX_DP<72>P5E_PEX2_STN7_TX_C_DN<119>P5E_PEX2_STN7_TX_C_DP<119>P5E_PEX2_STN4_TX_C_DN<72>P5E_PEX2_STN4_TX_C_DP<72>P5E_PEX2_STN7_RX_DN<127>P5E_PEX2_STN7_RX_DP<127>P5E_PEX2_STN4_RX_DN<64>P5E_PEX2_STN4_RX_DP<64>P5E_PEX2_STN7_TX_C_DN<127>P5E_PEX2_STN7_TX_C_DP<127>P5E_PEX2_STN4_TX_C_DN<64>P5E_PEX2_STN4_TX_C_DP<64>P5E_PEX2_STN7_RX_DN<118>P5E_PEX2_STN7_RX_DP<118>P5E_PEX2_STN4_RX_DN<73>P5E_PEX2_STN4_RX_DP<73>P5E_PEX2_STN7_TX_C_DN<118>P5E_PEX2_STN7_TX_C_DP<118>P5E_PEX2_STN4_TX_C_DN<73>P5E_PEX2_STN4_TX_C_DP<73>P5E_PEX2_STN7_RX_DN<126>P5E_PEX2_STN7_RX_DP<126>P5E_PEX2_STN4_RX_DN<65>P5E_PEX2_STN4_RX_DP<65>P5E_PEX2_STN7_TX_C_DN<126>P5E_PEX2_STN7_TX_C_DP<126>P5E_PEX2_STN4_TX_C_DN<65>P5E_PEX2_STN4_TX_C_DP<65>GPU_FPGA_OVERT_N



5
5
4
4
3
3
2
2
1
1
D D
C C
B B
A A
EXAMAX_10P8C_J7_GPU68(5/5) SizeDoc NumberRevDate: SheetofReviewerDesignerDepartmentProject
Page TitleCCBU D148 257Tuesday, August 29, 2023<project_name><Designer> GRANDTETON_SWB_20230829148 EXAMAX_10P8C_J7_GPU68(5/5)<Reviewer>SizeDoc NumberRevDate: SheetofReviewerDesignerDepartmentProject
Page TitleCCBU D148 257Tuesday, August 29, 2023<project_name><Designer> GRANDTETON_SWB_20230829148 EXAMAX_10P8C_J7_GPU68(5/5)<Reviewer>SizeDoc NumberRevDate: SheetofReviewerDesignerDepartmentProject
Page TitleCCBU D148 257Tuesday, August 29, 2023<project_name><Designer> GRANDTETON_SWB_20230829148 EXAMAX_10P8C_J7_GPU68(5/5)<Reviewer>
N ZA I OH PG QF RE SDB TC U VJ K WL XM Y1095/5J7ECONN270_10146445-101LFA10A10B10B10C10C10D10D10E10E10F10F10G10G10H10H10I10I10J10J10K10K10L10L10M1_10M1_10M2_10M2_10N10N10O10O10P10P10Q10Q10R10R10S10S10T10T10U10U10V10V10W10W10X10X10Y10Y10Z10Z10A9A9B9B9C9C9D9D9E9E9F9F9G9G9H9H9I9I9J9J9K9K9L9L9M9M9N1_9N1_9N2_9N2_9O9O9P9P9Q9Q9R9R9S9S9T9T9U9U9V9V9W9W9X9X9Y9Y9Z9Z9



5
5
4
4
3
3
2
2
1
1
D D
C C
B B
A A
EXAMAX_10P8C_J13_CPU0(1/5)
DVT_CHANGEP5E_PEX2_STN6_TX_C_DN<111>[39]P5E_PEX2_STN6_TX_C_DP<111>[39]P5E_PEX2_STN5_TX_C_DN<80>[38]P5E_PEX2_STN5_TX_C_DP<80>[38]P5E_PEX2_STN6_RX_DN<111>[39]P5E_PEX2_STN6_RX_DP<111>[39]P5E_PEX2_STN5_RX_DN<80>[38]P5E_PEX2_STN5_RX_DP<80>[38]P5E_PEX2_STN6_TX_C_DN<103>[39]P5E_PEX2_STN6_TX_C_DP<103>[39]P5E_PEX2_STN5_TX_C_DN<88>[38]P5E_PEX2_STN5_TX_C_DP<88>[38]P5E_PEX2_STN6_RX_DN<103>[39]P5E_PEX2_STN6_RX_DP<103>[39]P5E_PEX2_STN5_RX_DN<88>[38]P5E_PEX2_STN5_RX_DP<88>[38]P5E_PEX2_STN6_TX_C_DN<110>[39]P5E_PEX2_STN6_TX_C_DP<110>[39]P5E_PEX2_STN5_TX_C_DN<81>[38]P5E_PEX2_STN5_TX_C_DP<81>[38]P5E_PEX2_STN6_RX_DN<110>[39]P5E_PEX2_STN6_RX_DP<110>[39]P5E_PEX2_STN5_RX_DN<81>[38]P5E_PEX2_STN5_RX_DP<81>[38]P5E_PEX2_STN6_TX_C_DN<102>[39]P5E_PEX2_STN6_TX_C_DP<102>[39]P5E_PEX2_STN5_TX_C_DN<89>[38]P5E_PEX2_STN5_TX_C_DP<89>[38]P5E_PEX2_STN6_RX_DN<102>[39]P5E_PEX2_STN6_RX_DP<102>[39]P5E_PEX2_STN5_RX_DN<89>[38]P5E_PEX2_STN5_RX_DP<89>[38]GPU_3V3IO_RSVD3_FFU_R[166]
SizeDoc NumberRevDate: SheetofReviewerDesignerDepartmentProject
Page TitleCCBU D149 257Tuesday, August 29, 2023<project_name><Designer> GRANDTETON_SWB_20230829149 EXAMAX_10P8C_J13_CPU0(1/5)<Reviewer>SizeDoc NumberRevDate: SheetofReviewerDesignerDepartmentProject
Page TitleCCBU D149 257Tuesday, August 29, 2023<project_name><Designer> GRANDTETON_SWB_20230829149 EXAMAX_10P8C_J13_CPU0(1/5)<Reviewer>SizeDoc NumberRevDate: SheetofReviewerDesignerDepartmentProject
Page TitleCCBU D149 257Tuesday, August 29, 2023<project_name><Designer> GRANDTETON_SWB_20230829149 EXAMAX_10P8C_J13_CPU0(1/5)<Reviewer>
R67710R0402-02015%BA IHGFEDC J K L M NO PQ RST U V W X Y Z1
2
1/5J13ACONN270_10146445-101LFA2A2B1B1B2B2C1C1C2C2D1D1D2D2E1E1E2E2F1F1F2F2G1G1G2G2H1H1H2H2I1I1I2I2J1J1J2J2K1K1K2K2L1L1L2L2M1M1M1_2M1_2M2_2M2_2N1_1N1_1N2N2N2_1N2_1O1O1O2O2P1P1P2P2Q1Q1Q2Q2R1R1R2R2S1S1S2S2T1T1T2T2U1U1U2U2V1V1V2V2W1W1W2W2X1X1X2X2Y1Y1Y2Y2Z1Z1Z2Z2A1A1P5E_PEX2_STN6_TX_C_DN<111>P5E_PEX2_STN6_TX_C_DP<111>P5E_PEX2_STN5_TX_C_DN<80>P5E_PEX2_STN5_TX_C_DP<80>P5E_PEX2_STN6_RX_DN<111>P5E_PEX2_STN6_RX_DP<111>P5E_PEX2_STN5_RX_DN<80>P5E_PEX2_STN5_RX_DP<80>P5E_PEX2_STN6_TX_C_DN<103>P5E_PEX2_STN6_TX_C_DP<103>P5E_PEX2_STN5_TX_C_DN<88>P5E_PEX2_STN5_TX_C_DP<88>P5E_PEX2_STN6_RX_DN<103>P5E_PEX2_STN6_RX_DP<103>P5E_PEX2_STN5_RX_DN<88>P5E_PEX2_STN5_RX_DP<88>P5E_PEX2_STN6_TX_C_DN<110>P5E_PEX2_STN6_TX_C_DP<110>P5E_PEX2_STN5_TX_C_DN<81>P5E_PEX2_STN5_TX_C_DP<81>P5E_PEX2_STN6_RX_DN<110>P5E_PEX2_STN6_RX_DP<110>P5E_PEX2_STN5_RX_DN<81>P5E_PEX2_STN5_RX_DP<81>P5E_PEX2_STN6_TX_C_DN<102>P5E_PEX2_STN6_TX_C_DP<102>P5E_PEX2_STN5_TX_C_DN<89>P5E_PEX2_STN5_TX_C_DP<89>P5E_PEX2_STN6_RX_DN<102>P5E_PEX2_STN6_RX_DP<102>P5E_PEX2_STN5_RX_DN<89>P5E_PEX2_STN5_RX_DP<89>GPU_3V3IO_RSVD3_FFU_RPRSNT_SWB_B2_N



5
5
4
4
3
3
2
2
1
1
D D
C C
B B
A A
EXAMAX_10P8C_J13_CPU0(2/5)
DVT_CHANGEP5E_PEX2_STN6_TX_C_DN<108>[39]P5E_PEX2_STN6_TX_C_DP<108>[39]P5E_PEX2_STN5_TX_C_DN<83>[38]P5E_PEX2_STN5_TX_C_DP<83>[38]P5E_PEX2_STN6_RX_DN<108>[39]P5E_PEX2_STN6_RX_DP<108>[39]P5E_PEX2_STN5_RX_DN<83>[38]P5E_PEX2_STN5_RX_DP<83>[38]P5E_PEX2_STN6_TX_C_DN<100>[39]P5E_PEX2_STN6_TX_C_DP<100>[39]P5E_PEX2_STN5_TX_C_DN<91>[38]P5E_PEX2_STN5_TX_C_DP<91>[38]P5E_PEX2_STN6_RX_DN<100>[39]P5E_PEX2_STN6_RX_DP<100>[39]P5E_PEX2_STN5_RX_DN<91>[38]P5E_PEX2_STN5_RX_DP<91>[38]P5E_PEX2_STN6_TX_C_DN<109>[39]P5E_PEX2_STN6_TX_C_DP<109>[39]P5E_PEX2_STN5_TX_C_DN<82>[38]P5E_PEX2_STN5_TX_C_DP<82>[38]P5E_PEX2_STN6_RX_DN<109>[39]P5E_PEX2_STN6_RX_DP<109>[39]P5E_PEX2_STN5_RX_DN<82>[38]P5E_PEX2_STN5_RX_DP<82>[38]P5E_PEX2_STN6_TX_C_DN<101>[39]P5E_PEX2_STN6_TX_C_DP<101>[39]P5E_PEX2_STN5_TX_C_DN<90>[38]P5E_PEX2_STN5_TX_C_DP<90>[38]P5E_PEX2_STN6_RX_DN<101>[39]P5E_PEX2_STN6_RX_DP<101>[39]P5E_PEX2_STN5_RX_DN<90>[38]P5E_PEX2_STN5_RX_DP<90>[38]PRSNT_GPU_A2_R_N[145]
SizeDoc NumberRevDate: SheetofReviewerDesignerDepartmentProject
Page TitleCCBU D150 257Tuesday, August 29, 2023<project_name><Designer> GRANDTETON_SWB_20230829150 EXAMAX_10P8C_J13_CPU0(2/5)<Reviewer>SizeDoc NumberRevDate: SheetofReviewerDesignerDepartmentProject
Page TitleCCBU D150 257Tuesday, August 29, 2023<project_name><Designer> GRANDTETON_SWB_20230829150 EXAMAX_10P8C_J13_CPU0(2/5)<Reviewer>SizeDoc NumberRevDate: SheetofReviewerDesignerDepartmentProject
Page TitleCCBU D150 257Tuesday, August 29, 2023<project_name><Designer> GRANDTETON_SWB_20230829150 EXAMAX_10P8C_J13_CPU0(2/5)<Reviewer>
BA IHGFEDC J K L M NO PQ R S T U V W X Y Z432/5J13BCONN270_10146445-101LFA4A4B4B4C4C4D4D4E4E4F4F4G4G4H4H4I4I4J4J4K4K4L4L4M1_4M1_4M2_4M2_4N4N4O4O4P4P4Q4Q4R4R4S4S4T4T4U4U4V4V4W4W4X4X4Y4Y4Z4Z4A3A3B3B3C3C3D3D3E3E3F3F3G3G3H3H3I3I3J3J3K3K3L3L3M3M3N1_3N1_3N2_3N2_3O3O3P3P3Q3Q3R3R3S3S3T3T3U3U3V3V3W3W3X3X3Y3Y3Z3Z3P5E_PEX2_STN6_TX_C_DN<108>P5E_PEX2_STN6_TX_C_DP<108>P5E_PEX2_STN5_TX_C_DN<83>P5E_PEX2_STN5_TX_C_DP<83>P5E_PEX2_STN6_RX_DN<108>P5E_PEX2_STN6_RX_DP<108>P5E_PEX2_STN5_RX_DN<83>P5E_PEX2_STN5_RX_DP<83>P5E_PEX2_STN6_TX_C_DN<100>P5E_PEX2_STN6_TX_C_DP<100>P5E_PEX2_STN5_TX_C_DN<91>P5E_PEX2_STN5_TX_C_DP<91>P5E_PEX2_STN6_RX_DN<100>P5E_PEX2_STN6_RX_DP<100>P5E_PEX2_STN5_RX_DN<91>P5E_PEX2_STN5_RX_DP<91>P5E_PEX2_STN6_TX_C_DN<109>P5E_PEX2_STN6_TX_C_DP<109>P5E_PEX2_STN5_TX_C_DN<82>P5E_PEX2_STN5_TX_C_DP<82>P5E_PEX2_STN6_RX_DN<109>P5E_PEX2_STN6_RX_DP<109>P5E_PEX2_STN5_RX_DN<82>P5E_PEX2_STN5_RX_DP<82>P5E_PEX2_STN6_TX_C_DN<101>P5E_PEX2_STN6_TX_C_DP<101>P5E_PEX2_STN5_TX_C_DN<90>P5E_PEX2_STN5_TX_C_DP<90>P5E_PEX2_STN6_RX_DN<101>P5E_PEX2_STN6_RX_DP<101>P5E_PEX2_STN5_RX_DN<90>P5E_PEX2_STN5_RX_DP<90>PRSNT_GPU_A2_R_N



5
5
4
4
3
3
2
2
1
1
D D
C C
B B
A A
EXAMAX_10P8C_J13_CPU0(3/5)
P5E_PEX2_STN6_TX_C_DN<106>[39]P5E_PEX2_STN6_TX_C_DP<106>[39]P5E_PEX2_STN5_TX_C_DN<85>[38]P5E_PEX2_STN5_TX_C_DP<85>[38]P5E_PEX2_STN6_RX_DN<106>[39]P5E_PEX2_STN6_RX_DP<106>[39]P5E_PEX2_STN5_RX_DN<85>[38]P5E_PEX2_STN5_RX_DP<85>[38]P5E_PEX2_STN6_TX_C_DN<98>[39]P5E_PEX2_STN6_TX_C_DP<98>[39]P5E_PEX2_STN5_TX_C_DN<93>[38]P5E_PEX2_STN5_TX_C_DP<93>[38]P5E_PEX2_STN6_RX_DN<98>[39]P5E_PEX2_STN6_RX_DP<98>[39]P5E_PEX2_STN5_RX_DN<93>[38]P5E_PEX2_STN5_RX_DP<93>[38]P5E_PEX2_STN6_TX_C_DN<107>[39]P5E_PEX2_STN6_TX_C_DP<107>[39]P5E_PEX2_STN5_TX_C_DN<84>[38]P5E_PEX2_STN5_TX_C_DP<84>[38]P5E_PEX2_STN6_RX_DN<107>[39]P5E_PEX2_STN6_RX_DP<107>[39]P5E_PEX2_STN5_RX_DN<84>[38]P5E_PEX2_STN5_RX_DP<84>[38]P5E_PEX2_STN6_TX_C_DN<99>[39]P5E_PEX2_STN6_TX_C_DP<99>[39]P5E_PEX2_STN5_TX_C_DN<92>[38]P5E_PEX2_STN5_TX_C_DP<92>[38]P5E_PEX2_STN6_RX_DN<99>[39]P5E_PEX2_STN6_RX_DP<99>[39]P5E_PEX2_STN5_RX_DN<92>[38]P5E_PEX2_STN5_RX_DP<92>[38]GPU_3V3IO_RSVD5_FFU_R[166]
SizeDoc NumberRevDate: SheetofReviewerDesignerDepartmentProject
Page TitleCCBU D151 257Tuesday, August 29, 2023<project_name><Designer> GRANDTETON_SWB_20230829151 EXAMAX_10P8C_J13_CPU0(3/5)<Reviewer>SizeDoc NumberRevDate: SheetofReviewerDesignerDepartmentProject
Page TitleCCBU D151 257Tuesday, August 29, 2023<project_name><Designer> GRANDTETON_SWB_20230829151 EXAMAX_10P8C_J13_CPU0(3/5)<Reviewer>SizeDoc NumberRevDate: SheetofReviewerDesignerDepartmentProject
Page TitleCCBU D151 257Tuesday, August 29, 2023<project_name><Designer> GRANDTETON_SWB_20230829151 EXAMAX_10P8C_J13_CPU0(3/5)<Reviewer>
BA IHGFEDC J K L M NO PQ RST U V W X Y Z563/5J13CCONN270_10146445-101LFA6A6B6B6C6C6D6D6E6E6F6F6G6G6H6H6I6I6J6J6K6K6L6L6M1_6M1_6M2_6M2_6N6N6O6O6P6P6Q6Q6R6R6S6S6T6T6U6U6V6V6W6W6X6X6Y6Y6Z6Z6A5A5B5B5C5C5D5D5E5E5F5F5G5G5H5H5I5I5J5J5K5K5L5L5M5M5N1_5N1_5N2_5N2_5O5O5P5P5Q5Q5R5R5S5S5T5T5U5U5V5V5W5W5X5X5Y5Y5Z5Z5P5E_PEX2_STN6_TX_C_DN<106>P5E_PEX2_STN6_TX_C_DP<106>P5E_PEX2_STN5_TX_C_DN<85>P5E_PEX2_STN5_TX_C_DP<85>P5E_PEX2_STN6_RX_DN<106>P5E_PEX2_STN6_RX_DP<106>P5E_PEX2_STN5_RX_DN<85>P5E_PEX2_STN5_RX_DP<85>P5E_PEX2_STN6_TX_C_DN<98>P5E_PEX2_STN6_TX_C_DP<98>P5E_PEX2_STN5_TX_C_DN<93>P5E_PEX2_STN5_TX_C_DP<93>P5E_PEX2_STN6_RX_DN<98>P5E_PEX2_STN6_RX_DP<98>P5E_PEX2_STN5_RX_DN<93>P5E_PEX2_STN5_RX_DP<93>P5E_PEX2_STN6_TX_C_DN<107>P5E_PEX2_STN6_TX_C_DP<107>P5E_PEX2_STN5_TX_C_DN<84>P5E_PEX2_STN5_TX_C_DP<84>P5E_PEX2_STN6_RX_DN<107>P5E_PEX2_STN6_RX_DP<107>P5E_PEX2_STN5_RX_DN<84>P5E_PEX2_STN5_RX_DP<84>P5E_PEX2_STN6_TX_C_DN<99>P5E_PEX2_STN6_TX_C_DP<99>P5E_PEX2_STN5_TX_C_DN<92>P5E_PEX2_STN5_TX_C_DP<92>P5E_PEX2_STN6_RX_DN<99>P5E_PEX2_STN6_RX_DP<99>P5E_PEX2_STN5_RX_DN<92>P5E_PEX2_STN5_RX_DP<92>GPU_3V3IO_RSVD5_FFU_R



5
5
4
4
3
3
2
2
1
1
D D
C C
B B
A A
For HSC Power on indepently function.Default: Power on by MB
EXAMAX_10P8C_J13_CPU0(4/5)
P5E_PEX2_STN6_TX_C_DN<104>[39]P5E_PEX2_STN6_TX_C_DP<104>[39]P5E_PEX2_STN5_TX_C_DN<87>[38]P5E_PEX2_STN5_TX_C_DP<87>[38]P5E_PEX2_STN6_RX_DN<104>[39]P5E_PEX2_STN6_RX_DP<104>[39]P5E_PEX2_STN5_RX_DN<87>[38]P5E_PEX2_STN5_RX_DP<87>[38]P5E_PEX2_STN6_TX_C_DN<96>[39]P5E_PEX2_STN6_TX_C_DP<96>[39]P5E_PEX2_STN5_TX_C_DN<95>[38]P5E_PEX2_STN5_TX_C_DP<95>[38]P5E_PEX2_STN6_RX_DN<96>[39]P5E_PEX2_STN6_RX_DP<96>[39]P5E_PEX2_STN5_RX_DN<95>[38]P5E_PEX2_STN5_RX_DP<95>[38]P5E_PEX2_STN6_TX_C_DN<105>[39]P5E_PEX2_STN6_TX_C_DP<105>[39]P5E_PEX2_STN5_TX_C_DN<86>[38]P5E_PEX2_STN5_TX_C_DP<86>[38]P5E_PEX2_STN6_RX_DN<105>[39]P5E_PEX2_STN6_RX_DP<105>[39]P5E_PEX2_STN5_RX_DN<86>[38]P5E_PEX2_STN5_RX_DP<86>[38]P5E_PEX2_STN6_TX_C_DN<97>[39]P5E_PEX2_STN6_TX_C_DP<97>[39]P5E_PEX2_STN5_TX_C_DN<94>[38]P5E_PEX2_STN5_TX_C_DP<94>[38]P5E_PEX2_STN6_RX_DN<97>[39]P5E_PEX2_STN6_RX_DP<97>[39]P5E_PEX2_STN5_RX_DN<94>[38]P5E_PEX2_STN5_RX_DP<94>[38]GPU_FPGA_OVERT_R_N[166]MB_HSC_EN[152,166]
HSC_P12V_EN [213,214]MB_HSC_ISO_D1_EN [152]MB_HSC_EN[152,166]MB_HSC_ISO_D1_EN [152]P12V_STBYSizeDoc NumberRevDate: SheetofReviewerDesignerDepartmentProject
Page TitleCCBU D152 257Tuesday, August 29, 2023<project_name><Designer> GRANDTETON_SWB_20230829152 EXAMAX_10P8C_J13_CPU0(4/5)<Reviewer>SizeDoc NumberRevDate: SheetofReviewerDesignerDepartmentProject
Page TitleCCBU D152 257Tuesday, August 29, 2023<project_name><Designer> GRANDTETON_SWB_20230829152 EXAMAX_10P8C_J13_CPU0(4/5)<Reviewer>SizeDoc NumberRevDate: SheetofReviewerDesignerDepartmentProject
Page TitleCCBU D152 257Tuesday, August 29, 2023<project_name><Designer> GRANDTETON_SWB_20230829152 EXAMAX_10P8C_J13_CPU0(4/5)<Reviewer>R5714 10R0402-02011% <Part Number>C40060.1UFC0402-0201J58SCONN3_TSM-103-01-S-SV-TR123R6252267K1%R0402-0201<Part Number>Q123ADMN53D0LDW-7<Part Number>S11G12D16Q123BDMN53D0LDW-7<Part Number>D23G25S24 J58_12<Part Number>1BA IHGFEDC J K L M NO PQ RST U V W X Y Z784/5J13DCONN270_10146445-101LFA8A8B8B8C8C8D8D8E8E8F8F8G8G8H8H8I8I8J8J8K8K8L8L8M1_8M1_8M2_8M2_8N8N8O8O8P8P8Q8Q8R8R8S8S8T8T8U8U8V8V8W8W8X8X8Y8Y8Z8Z8A7A7B7B7C7C7D7D7E7E7F7F7G7G7H7H7I7I7J7J7K7K7L7L7M7M7N1_7N1_7N2_7N2_7O7O7P7P7Q7Q7R7R7S7S7T7T7U7U7V7V7W7W7X7X7Y7Y7Z7Z7R6253100K<Part Number>R0402-02011%R625510K1%R0402-0201<Part Number>
P5E_PEX2_STN6_TX_C_DN<104>P5E_PEX2_STN6_TX_C_DP<104>P5E_PEX2_STN5_TX_C_DN<87>P5E_PEX2_STN5_TX_C_DP<87>P5E_PEX2_STN6_RX_DN<104>P5E_PEX2_STN6_RX_DP<104>P5E_PEX2_STN5_RX_DN<87>P5E_PEX2_STN5_RX_DP<87>P5E_PEX2_STN6_TX_C_DN<96>P5E_PEX2_STN6_TX_C_DP<96>P5E_PEX2_STN5_TX_C_DN<95>P5E_PEX2_STN5_TX_C_DP<95>P5E_PEX2_STN6_RX_DN<96>P5E_PEX2_STN6_RX_DP<96>P5E_PEX2_STN5_RX_DN<95>P5E_PEX2_STN5_RX_DP<95>P5E_PEX2_STN6_TX_C_DN<105>P5E_PEX2_STN6_TX_C_DP<105>P5E_PEX2_STN5_TX_C_DN<86>P5E_PEX2_STN5_TX_C_DP<86>P5E_PEX2_STN6_RX_DN<105>P5E_PEX2_STN6_RX_DP<105>P5E_PEX2_STN5_RX_DN<86>P5E_PEX2_STN5_RX_DP<86>P5E_PEX2_STN6_TX_C_DN<97>P5E_PEX2_STN6_TX_C_DP<97>P5E_PEX2_STN5_TX_C_DN<94>P5E_PEX2_STN5_TX_C_DP<94>P5E_PEX2_STN6_RX_DN<97>P5E_PEX2_STN6_RX_DP<97>P5E_PEX2_STN5_RX_DN<94>P5E_PEX2_STN5_RX_DP<94>GPU_FPGA_OVERT_R_NMB_HSC_EN
MB_HSC_ISO_D2_ENMB_HSC_ISO_D1_ENPD_MB_HSC_ISO_D1_EN



5
5
4
4
3
3
2
2
1
1
D D
C C
B B
A A
EXAMAX_10P8C_J13_CPU0(5/5)
DVT_CHANGEPWRGD_P12V_AUX_R[121,213,214,220]PRSNT_GPU_A3_R_N[142]
SizeDoc NumberRevDate: SheetofReviewerDesignerDepartmentProject
Page TitleCCBU D153 257Tuesday, August 29, 2023<project_name><Designer> GRANDTETON_SWB_20230829153 EXAMAX_10P8C_J13_CPU0(5/5)<Reviewer>SizeDoc NumberRevDate: SheetofReviewerDesignerDepartmentProject
Page TitleCCBU D153 257Tuesday, August 29, 2023<project_name><Designer> GRANDTETON_SWB_20230829153 EXAMAX_10P8C_J13_CPU0(5/5)<Reviewer>SizeDoc NumberRevDate: SheetofReviewerDesignerDepartmentProject
Page TitleCCBU D153 257Tuesday, August 29, 2023<project_name><Designer> GRANDTETON_SWB_20230829153 EXAMAX_10P8C_J13_CPU0(5/5)<Reviewer>
R63150 R0402-02015% <Part Number>N ZA I OH PG QF RE SDB TC U VJ K WL XM Y1095/5J13ECONN270_10146445-101LFA10A10B10B10C10C10D10D10E10E10F10F10G10G10H10H10I10I10J10J10K10K10L10L10M1_10M1_10M2_10M2_10N10N10O10O10P10P10Q10Q10R10R10S10S10T10T10U10U10V10V10W10W10X10X10Y10Y10Z10Z10A9A9B9B9C9C9D9D9E9E9F9F9G9G9H9H9I9I9J9J9K9K9L9L9M9M9N1_9N1_9N2_9N2_9O9O9P9P9Q9Q9R9R9S9S9T9T9U9U9V9V9W9W9X9X9Y9Y9Z9Z9SWB_HSC_PWRGDPRSNT_GPU_A3_R_N



5
5
4
4
3
3
2
2
1
1
D D
C C
B B
A A
EXAMAX_10P8C_J14_CPU0(1/5)
DVT_CHANGEP5E_PEX3_STN6_TX_C_DN<111>[52]P5E_PEX3_STN6_TX_C_DP<111>[52]P5E_PEX3_STN5_TX_C_DN<80>[51]P5E_PEX3_STN5_TX_C_DP<80>[51]P5E_PEX3_STN6_RX_DN<111>[52]P5E_PEX3_STN6_RX_DP<111>[52]P5E_PEX3_STN5_RX_DN<80>[51]P5E_PEX3_STN5_RX_DP<80>[51]P5E_PEX3_STN6_TX_C_DN<103>[52]P5E_PEX3_STN6_TX_C_DP<103>[52]P5E_PEX3_STN5_TX_C_DN<88>[51]P5E_PEX3_STN5_TX_C_DP<88>[51]P5E_PEX3_STN6_RX_DN<103>[52]P5E_PEX3_STN6_RX_DP<103>[52]P5E_PEX3_STN5_RX_DN<88>[51]P5E_PEX3_STN5_RX_DP<88>[51]P5E_PEX3_STN6_TX_C_DN<110>[52]P5E_PEX3_STN6_TX_C_DP<110>[52]P5E_PEX3_STN5_TX_C_DN<81>[51]P5E_PEX3_STN5_TX_C_DP<81>[51]P5E_PEX3_STN6_RX_DN<110>[52]P5E_PEX3_STN6_RX_DP<110>[52]P5E_PEX3_STN5_RX_DN<81>[51]P5E_PEX3_STN5_RX_DP<81>[51]P5E_PEX3_STN6_TX_C_DN<102>[52]P5E_PEX3_STN6_TX_C_DP<102>[52]P5E_PEX3_STN5_TX_C_DN<89>[51]P5E_PEX3_STN5_TX_C_DP<89>[51]P5E_PEX3_STN6_RX_DN<102>[52]P5E_PEX3_STN6_RX_DP<102>[52]P5E_PEX3_STN5_RX_DN<89>[51]P5E_PEX3_STN5_RX_DP<89>[51]MB_SWB_PWR_EN[129,167]
SizeDoc NumberRevDate: SheetofReviewerDesignerDepartmentProject
Page TitleCCBU D154 257Tuesday, August 29, 2023<project_name><Designer> GRANDTETON_SWB_20230829154 EXAMAX_10P8C_J14_CPU0(1/5)<Reviewer>SizeDoc NumberRevDate: SheetofReviewerDesignerDepartmentProject
Page TitleCCBU D154 257Tuesday, August 29, 2023<project_name><Designer> GRANDTETON_SWB_20230829154 EXAMAX_10P8C_J14_CPU0(1/5)<Reviewer>SizeDoc NumberRevDate: SheetofReviewerDesignerDepartmentProject
Page TitleCCBU D154 257Tuesday, August 29, 2023<project_name><Designer> GRANDTETON_SWB_20230829154 EXAMAX_10P8C_J14_CPU0(1/5)<Reviewer>
BA IHGFEDC J K L M NO PQ RST U V W X Y Z1
2
1/5J14ACONN270_10146445-101LFA2A2B1B1B2B2C1C1C2C2D1D1D2D2E1E1E2E2F1F1F2F2G1G1G2G2H1H1H2H2I1I1I2I2J1J1J2J2K1K1K2K2L1L1L2L2M1M1M1_2M1_2M2_2M2_2N1_1N1_1N2N2N2_1N2_1O1O1O2O2P1P1P2P2Q1Q1Q2Q2R1R1R2R2S1S1S2S2T1T1T2T2U1U1U2U2V1V1V2V2W1W1W2W2X1X1X2X2Y1Y1Y2Y2Z1Z1Z2Z2A1A1R67720R0402-02015%P5E_PEX3_STN6_TX_C_DN<111>P5E_PEX3_STN6_TX_C_DP<111>P5E_PEX3_STN5_TX_C_DN<80>P5E_PEX3_STN5_TX_C_DP<80>P5E_PEX3_STN6_RX_DN<111>P5E_PEX3_STN6_RX_DP<111>P5E_PEX3_STN5_RX_DN<80>P5E_PEX3_STN5_RX_DP<80>P5E_PEX3_STN6_TX_C_DN<103>P5E_PEX3_STN6_TX_C_DP<103>P5E_PEX3_STN5_TX_C_DN<88>P5E_PEX3_STN5_TX_C_DP<88>P5E_PEX3_STN6_RX_DN<103>P5E_PEX3_STN6_RX_DP<103>P5E_PEX3_STN5_RX_DN<88>P5E_PEX3_STN5_RX_DP<88>P5E_PEX3_STN6_TX_C_DN<110>P5E_PEX3_STN6_TX_C_DP<110>P5E_PEX3_STN5_TX_C_DN<81>P5E_PEX3_STN5_TX_C_DP<81>P5E_PEX3_STN6_RX_DN<110>P5E_PEX3_STN6_RX_DP<110>P5E_PEX3_STN5_RX_DN<81>P5E_PEX3_STN5_RX_DP<81>P5E_PEX3_STN6_TX_C_DN<102>P5E_PEX3_STN6_TX_C_DP<102>P5E_PEX3_STN5_TX_C_DN<89>P5E_PEX3_STN5_TX_C_DP<89>P5E_PEX3_STN6_RX_DN<102>P5E_PEX3_STN6_RX_DP<102>P5E_PEX3_STN5_RX_DN<89>P5E_PEX3_STN5_RX_DP<89>PRSNT_SWB_B1_N



5
5
4
4
3
3
2
2
1
1
D D
C C
B B
A A
EXAMAX_10P8C_J14_CPU0(2/5)
P5E_PEX3_STN6_TX_C_DN<108>[52]P5E_PEX3_STN6_TX_C_DP<108>[52]P5E_PEX3_STN5_TX_C_DN<83>[51]P5E_PEX3_STN5_TX_C_DP<83>[51]P5E_PEX3_STN6_RX_DN<108>[52]P5E_PEX3_STN6_RX_DP<108>[52]P5E_PEX3_STN5_RX_DN<83>[51]P5E_PEX3_STN5_RX_DP<83>[51]P5E_PEX3_STN6_TX_C_DN<100>[52]P5E_PEX3_STN6_TX_C_DP<100>[52]P5E_PEX3_STN5_TX_C_DN<91>[51]P5E_PEX3_STN5_TX_C_DP<91>[51]P5E_PEX3_STN6_RX_DN<100>[52]P5E_PEX3_STN6_RX_DP<100>[52]P5E_PEX3_STN5_RX_DN<91>[51]P5E_PEX3_STN5_RX_DP<91>[51]P5E_PEX3_STN6_TX_C_DN<109>[52]P5E_PEX3_STN6_TX_C_DP<109>[52]P5E_PEX3_STN5_TX_C_DN<82>[51]P5E_PEX3_STN5_TX_C_DP<82>[51]P5E_PEX3_STN6_RX_DN<109>[52]P5E_PEX3_STN6_RX_DP<109>[52]P5E_PEX3_STN5_RX_DN<82>[51]P5E_PEX3_STN5_RX_DP<82>[51]P5E_PEX3_STN6_TX_C_DN<101>[52]P5E_PEX3_STN6_TX_C_DP<101>[52]P5E_PEX3_STN5_TX_C_DN<90>[51]P5E_PEX3_STN5_TX_C_DP<90>[51]P5E_PEX3_STN6_RX_DN<101>[52]P5E_PEX3_STN6_RX_DP<101>[52]P5E_PEX3_STN5_RX_DN<90>[51]P5E_PEX3_STN5_RX_DP<90>[51]MB_BIC_READY_BUF_R_N[132]MB_SWB_PWRGD_BUF_R[129]
SizeDoc NumberRevDate: SheetofReviewerDesignerDepartmentProject
Page TitleCCBU D155 257Tuesday, August 29, 2023<project_name><Designer> GRANDTETON_SWB_20230829155 EXAMAX_10P8C_J14_CPU0(2/5)<Reviewer>SizeDoc NumberRevDate: SheetofReviewerDesignerDepartmentProject
Page TitleCCBU D155 257Tuesday, August 29, 2023<project_name><Designer> GRANDTETON_SWB_20230829155 EXAMAX_10P8C_J14_CPU0(2/5)<Reviewer>SizeDoc NumberRevDate: SheetofReviewerDesignerDepartmentProject
Page TitleCCBU D155 257Tuesday, August 29, 2023<project_name><Designer> GRANDTETON_SWB_20230829155 EXAMAX_10P8C_J14_CPU0(2/5)<Reviewer>
BA IHGFEDC J K L M NO PQ R S T U V W X Y Z432/5J14BCONN270_10146445-101LFA4A4B4B4C4C4D4D4E4E4F4F4G4G4H4H4I4I4J4J4K4K4L4L4M1_4M1_4M2_4M2_4N4N4O4O4P4P4Q4Q4R4R4S4S4T4T4U4U4V4V4W4W4X4X4Y4Y4Z4Z4A3A3B3B3C3C3D3D3E3E3F3F3G3G3H3H3I3I3J3J3K3K3L3L3M3M3N1_3N1_3N2_3N2_3O3O3P3P3Q3Q3R3R3S3S3T3T3U3U3V3V3W3W3X3X3Y3Y3Z3Z3P5E_PEX3_STN6_TX_C_DN<108>P5E_PEX3_STN6_TX_C_DP<108>P5E_PEX3_STN5_TX_C_DN<83>P5E_PEX3_STN5_TX_C_DP<83>P5E_PEX3_STN6_RX_DN<108>P5E_PEX3_STN6_RX_DP<108>P5E_PEX3_STN5_RX_DN<83>P5E_PEX3_STN5_RX_DP<83>P5E_PEX3_STN6_TX_C_DN<100>P5E_PEX3_STN6_TX_C_DP<100>P5E_PEX3_STN5_TX_C_DN<91>P5E_PEX3_STN5_TX_C_DP<91>P5E_PEX3_STN6_RX_DN<100>P5E_PEX3_STN6_RX_DP<100>P5E_PEX3_STN5_RX_DN<91>P5E_PEX3_STN5_RX_DP<91>P5E_PEX3_STN6_TX_C_DN<109>P5E_PEX3_STN6_TX_C_DP<109>P5E_PEX3_STN5_TX_C_DN<82>P5E_PEX3_STN5_TX_C_DP<82>P5E_PEX3_STN6_RX_DN<109>P5E_PEX3_STN6_RX_DP<109>P5E_PEX3_STN5_RX_DN<82>P5E_PEX3_STN5_RX_DP<82>P5E_PEX3_STN6_TX_C_DN<101>P5E_PEX3_STN6_TX_C_DP<101>P5E_PEX3_STN5_TX_C_DN<90>P5E_PEX3_STN5_TX_C_DP<90>P5E_PEX3_STN6_RX_DN<101>P5E_PEX3_STN6_RX_DP<101>P5E_PEX3_STN5_RX_DN<90>P5E_PEX3_STN5_RX_DP<90>MB_SWB_PWRGD_BUF_RMB_BIC_READY_BUF_R_N



5
5
4
4
3
3
2
2
1
1
D D
C C
B B
A A
EXAMAX_10P8C_J14_CPU0(3/5)
P5E_PEX3_STN6_TX_C_DN<106>[52]P5E_PEX3_STN6_TX_C_DP<106>[52]P5E_PEX3_STN5_TX_C_DN<85>[51]P5E_PEX3_STN5_TX_C_DP<85>[51]P5E_PEX3_STN6_RX_DN<106>[52]P5E_PEX3_STN6_RX_DP<106>[52]P5E_PEX3_STN5_RX_DN<85>[51]P5E_PEX3_STN5_RX_DP<85>[51]P5E_PEX3_STN6_TX_C_DN<98>[52]P5E_PEX3_STN6_TX_C_DP<98>[52]P5E_PEX3_STN5_TX_C_DN<93>[51]P5E_PEX3_STN5_TX_C_DP<93>[51]P5E_PEX3_STN6_RX_DN<98>[52]P5E_PEX3_STN6_RX_DP<98>[52]P5E_PEX3_STN5_RX_DN<93>[51]P5E_PEX3_STN5_RX_DP<93>[51]P5E_PEX3_STN6_TX_C_DN<107>[52]P5E_PEX3_STN6_TX_C_DP<107>[52]P5E_PEX3_STN5_TX_C_DN<84>[51]P5E_PEX3_STN5_TX_C_DP<84>[51]P5E_PEX3_STN6_RX_DN<107>[52]P5E_PEX3_STN6_RX_DP<107>[52]P5E_PEX3_STN5_RX_DN<84>[51]P5E_PEX3_STN5_RX_DP<84>[51]P5E_PEX3_STN6_TX_C_DN<99>[52]P5E_PEX3_STN6_TX_C_DP<99>[52]P5E_PEX3_STN5_TX_C_DN<92>[51]P5E_PEX3_STN5_TX_C_DP<92>[51]P5E_PEX3_STN6_RX_DN<99>[52]P5E_PEX3_STN6_RX_DP<99>[52]P5E_PEX3_STN5_RX_DN<92>[51]P5E_PEX3_STN5_RX_DP<92>[51]RST_MB_BIC_N[132,167]
SizeDoc NumberRevDate: SheetofReviewerDesignerDepartmentProject
Page TitleCCBU D156 257Tuesday, August 29, 2023<project_name><Designer> GRANDTETON_SWB_20230829156 EXAMAX_10P8C_J14_CPU0(3/5)<Reviewer>SizeDoc NumberRevDate: SheetofReviewerDesignerDepartmentProject
Page TitleCCBU D156 257Tuesday, August 29, 2023<project_name><Designer> GRANDTETON_SWB_20230829156 EXAMAX_10P8C_J14_CPU0(3/5)<Reviewer>SizeDoc NumberRevDate: SheetofReviewerDesignerDepartmentProject
Page TitleCCBU D156 257Tuesday, August 29, 2023<project_name><Designer> GRANDTETON_SWB_20230829156 EXAMAX_10P8C_J14_CPU0(3/5)<Reviewer>
BA IHGFEDC J K L M NO PQ RST U V W X Y Z563/5J14CCONN270_10146445-101LFA6A6B6B6C6C6D6D6E6E6F6F6G6G6H6H6I6I6J6J6K6K6L6L6M1_6M1_6M2_6M2_6N6N6O6O6P6P6Q6Q6R6R6S6S6T6T6U6U6V6V6W6W6X6X6Y6Y6Z6Z6A5A5B5B5C5C5D5D5E5E5F5F5G5G5H5H5I5I5J5J5K5K5L5L5M5M5N1_5N1_5N2_5N2_5O5O5P5P5Q5Q5R5R5S5S5T5T5U5U5V5V5W5W5X5X5Y5Y5Z5Z5P5E_PEX3_STN6_TX_C_DN<106>P5E_PEX3_STN6_TX_C_DP<106>P5E_PEX3_STN5_TX_C_DN<85>P5E_PEX3_STN5_TX_C_DP<85>P5E_PEX3_STN6_RX_DN<106>P5E_PEX3_STN6_RX_DP<106>P5E_PEX3_STN5_RX_DN<85>P5E_PEX3_STN5_RX_DP<85>P5E_PEX3_STN6_TX_C_DN<98>P5E_PEX3_STN6_TX_C_DP<98>P5E_PEX3_STN5_TX_C_DN<93>P5E_PEX3_STN5_TX_C_DP<93>P5E_PEX3_STN6_RX_DN<98>P5E_PEX3_STN6_RX_DP<98>P5E_PEX3_STN5_RX_DN<93>P5E_PEX3_STN5_RX_DP<93>P5E_PEX3_STN6_TX_C_DN<107>P5E_PEX3_STN6_TX_C_DP<107>P5E_PEX3_STN5_TX_C_DN<84>P5E_PEX3_STN5_TX_C_DP<84>P5E_PEX3_STN6_RX_DN<107>P5E_PEX3_STN6_RX_DP<107>P5E_PEX3_STN5_RX_DN<84>P5E_PEX3_STN5_RX_DP<84>P5E_PEX3_STN6_TX_C_DN<99>P5E_PEX3_STN6_TX_C_DP<99>P5E_PEX3_STN5_TX_C_DN<92>P5E_PEX3_STN5_TX_C_DP<92>P5E_PEX3_STN6_RX_DN<99>P5E_PEX3_STN6_RX_DP<99>P5E_PEX3_STN5_RX_DN<92>P5E_PEX3_STN5_RX_DP<92>



5
5
4
4
3
3
2
2
1
1
D D
C C
B B
A A
EXAMAX_10P8C_J14_CPU0(4/5)
DVT_CHANGEP5E_PEX3_STN6_TX_C_DN<104>[52]P5E_PEX3_STN6_TX_C_DP<104>[52]P5E_PEX3_STN5_TX_C_DN<87>[51]P5E_PEX3_STN5_TX_C_DP<87>[51]P5E_PEX3_STN6_RX_DN<104>[52]P5E_PEX3_STN6_RX_DP<104>[52]P5E_PEX3_STN5_RX_DN<87>[51]P5E_PEX3_STN5_RX_DP<87>[51]P5E_PEX3_STN6_TX_C_DN<96>[52]P5E_PEX3_STN6_TX_C_DP<96>[52]P5E_PEX3_STN5_TX_C_DN<95>[51]P5E_PEX3_STN5_TX_C_DP<95>[51]P5E_PEX3_STN6_RX_DN<96>[52]P5E_PEX3_STN6_RX_DP<96>[52]P5E_PEX3_STN5_RX_DN<95>[51]P5E_PEX3_STN5_RX_DP<95>[51]P5E_PEX3_STN6_TX_C_DN<105>[52]P5E_PEX3_STN6_TX_C_DP<105>[52]P5E_PEX3_STN5_TX_C_DN<86>[51]P5E_PEX3_STN5_TX_C_DP<86>[51]P5E_PEX3_STN6_RX_DN<105>[52]P5E_PEX3_STN6_RX_DP<105>[52]P5E_PEX3_STN5_RX_DN<86>[51]P5E_PEX3_STN5_RX_DP<86>[51]P5E_PEX3_STN6_TX_C_DN<97>[52]P5E_PEX3_STN6_TX_C_DP<97>[52]P5E_PEX3_STN5_TX_C_DN<94>[51]P5E_PEX3_STN5_TX_C_DP<94>[51]P5E_PEX3_STN6_RX_DN<97>[52]P5E_PEX3_STN6_RX_DP<97>[52]P5E_PEX3_STN5_RX_DN<94>[51]P5E_PEX3_STN5_RX_DP<94>[51]RST_MB_BMC_BUF_R_N[132]PRSNT_GPU_A1_R_N[162]
SizeDoc NumberRevDate: SheetofReviewerDesignerDepartmentProject
Page TitleCCBU D157 257Tuesday, August 29, 2023<project_name><Designer> GRANDTETON_SWB_20230829157 EXAMAX_10P8C_J14_CPU0(4/5)<Reviewer>SizeDoc NumberRevDate: SheetofReviewerDesignerDepartmentProject
Page TitleCCBU D157 257Tuesday, August 29, 2023<project_name><Designer> GRANDTETON_SWB_20230829157 EXAMAX_10P8C_J14_CPU0(4/5)<Reviewer>SizeDoc NumberRevDate: SheetofReviewerDesignerDepartmentProject
Page TitleCCBU D157 257Tuesday, August 29, 2023<project_name><Designer> GRANDTETON_SWB_20230829157 EXAMAX_10P8C_J14_CPU0(4/5)<Reviewer>
BA IHGFEDC J K L M NO PQ RST U V W X Y Z784/5J14DCONN270_10146445-101LFA8A8B8B8C8C8D8D8E8E8F8F8G8G8H8H8I8I8J8J8K8K8L8L8M1_8M1_8M2_8M2_8N8N8O8O8P8P8Q8Q8R8R8S8S8T8T8U8U8V8V8W8W8X8X8Y8Y8Z8Z8A7A7B7B7C7C7D7D7E7E7F7F7G7G7H7H7I7I7J7J7K7K7L7L7M7M7N1_7N1_7N2_7N2_7O7O7P7P7Q7Q7R7R7S7S7T7T7U7U7V7V7W7W7X7X7Y7Y7Z7Z7P5E_PEX3_STN6_TX_C_DN<104>P5E_PEX3_STN6_TX_C_DP<104>P5E_PEX3_STN5_TX_C_DN<87>P5E_PEX3_STN5_TX_C_DP<87>P5E_PEX3_STN6_RX_DN<104>P5E_PEX3_STN6_RX_DP<104>P5E_PEX3_STN5_RX_DN<87>P5E_PEX3_STN5_RX_DP<87>P5E_PEX3_STN6_TX_C_DN<96>P5E_PEX3_STN6_TX_C_DP<96>P5E_PEX3_STN5_TX_C_DN<95>P5E_PEX3_STN5_TX_C_DP<95>P5E_PEX3_STN6_RX_DN<96>P5E_PEX3_STN6_RX_DP<96>P5E_PEX3_STN5_RX_DN<95>P5E_PEX3_STN5_RX_DP<95>P5E_PEX3_STN6_TX_C_DN<105>P5E_PEX3_STN6_TX_C_DP<105>P5E_PEX3_STN5_TX_C_DN<86>P5E_PEX3_STN5_TX_C_DP<86>P5E_PEX3_STN6_RX_DN<105>P5E_PEX3_STN6_RX_DP<105>P5E_PEX3_STN5_RX_DN<86>P5E_PEX3_STN5_RX_DP<86>P5E_PEX3_STN6_TX_C_DN<97>P5E_PEX3_STN6_TX_C_DP<97>P5E_PEX3_STN5_TX_C_DN<94>P5E_PEX3_STN5_TX_C_DP<94>P5E_PEX3_STN6_RX_DN<97>P5E_PEX3_STN6_RX_DP<97>P5E_PEX3_STN5_RX_DN<94>P5E_PEX3_STN5_RX_DP<94>PRSNT_GPU_A1_R_NRST_MB_BMC_BUF_R_N



5
5
4
4
3
3
2
2
1
1
D D
C C
B B
A A
FROM SWB
FROM MB
Tri-stat BufferP1 is enable pin
Tri-stat BufferP1 is enable pin
INTERNAL PUBY VCCB
EXAMAX_10P8C_J14_CPU0(5/5)
MB_3V3IO_RSVD1[158]MB_3V3IO_RSVD3[158]GPU_WP_HW_CTRL_N[167]MB_3V3IO_RSVD4[158]UART_MB_BIC_TX_BUF_R[158]UART_MB_BIC_RX[158]
UART_MB_BIC_TX[211]UART_MB_BIC_TX_BUF_R [158]UART_MB_BIC_RX[158]UART_MB_BIC_RX_BUF_R [211]I3C_MB_BMC_R_SCL[158]SMB_MB_I3C_ISO_SCL [87]I3C_MB_BMC_R_SDA[158]SMB_MB_I3C_ISO_SDA [87]
I3C_MB_BMC_R_SDA[158]I3C_MB_BMC_R_SCL[158]MB_3V3IO_RSVD1_ISO_R[118]MB_3V3IO_RSVD1 [158]MB_3V3IO_RSVD3_ISO_R[118]MB_3V3IO_RSVD3 [158]MB_3V3IO_RSVD4_ISO_R[118]MB_3V3IO_RSVD4 [158]P3V3_AUXP3V3_AUXP3V3_AUXP3V3_AUXP3V3_AUXP3V3_AUX
P3V3_AUXP3V3_AUXP3V3_AUXP3V3_AUXP3V3_AUXP3V3_AUXP3V3_AUXP3V3_AUXP3V3_AUX
SizeDoc NumberRevDate: SheetofReviewerDesignerDepartmentProject
Page TitleCCBU D158 257Tuesday, August 29, 2023<project_name><Designer> GRANDTETON_SWB_20230829158 EXAMAX_10P8C_J14_CPU0(5/5)<Reviewer>SizeDoc NumberRevDate: SheetofReviewerDesignerDepartmentProject
Page TitleCCBU D158 257Tuesday, August 29, 2023<project_name><Designer> GRANDTETON_SWB_20230829158 EXAMAX_10P8C_J14_CPU0(5/5)<Reviewer>SizeDoc NumberRevDate: SheetofReviewerDesignerDepartmentProject
Page TitleCCBU D158 257Tuesday, August 29, 2023<project_name><Designer> GRANDTETON_SWB_20230829158 EXAMAX_10P8C_J14_CPU0(5/5)<Reviewer>
R6704 33R0402-02011%R6699100K<Part Number>R0402-02011%1/16WNIR62824.7K5%NIR6706 33 R0402-02011%NI R6278 0 R0402-02015%Q247BBSS138BKSD23G25S24
R6697100K<Part Number>R0402-02011%1/16WNI
R2742 33.2 R0402-02011%Q247ABSS138BKSS11G12D16C36440.1UFX7RC0402-020110%16V
R6279 0 R0402-02015%
R62724.7KR0402-02015% NI
R6698 33R0402-02011%R6700 33 R0402-02011%NIR67074.7KR0402-02011%Q246BBSS138BKSD23G25S24C44571000PFC02015%16VNIR5472 0 R0402-02015%
R6280 0 R0402-02015%Q246ABSS138BKSS11G12D16R67084.7KR0402-02011%
R2740 10K 1% R0402-0201R6711100K<Part Number>R0402-02011%1/16WNIU356SN74LVC1G126DCKR<Part Number>24531R6709100K<Part Number>R0402-02011%1/16WNIC39960.1UF10%16VC0402-0201NIC25690.1UFX7RC0402-020110%16V
R67014.7KR0402-02011%Q245BBSS138BKSD23G25S24C44561000PFC02015%16VNIR5473 33.2 R0402-02011%
Q245ABSS138BKSS11G12D16 C39970.1UF10%16VC0402-0201NIR67024.7KR0402-02011%R6710 33R0402-02011%R6705100K<Part Number>R0402-02011%1/16WNIR6712 33 R0402-02011%NIR2739 0 R0402-02015%
R6703100K<Part Number>R0402-02011%1/16WNI
R6297100K1% R0402-0201<Part Number>
R66954.7KR0402-02011%
U422PCA9617ADPNIEN5VCCA1VCCB8SCLA2SDAA3SDAB6SCLB7GND4R6277 0 R0402-02015%
C44551000PFC02015%16VNIR62814.7K5%NIU302SN74LVC1G126DCKR<Part Number>24531R5474 10K 1% R0402-0201
R66964.7KR0402-02011%N ZA I OH PG QF RE SDB TC U VJ K WL XM Y1095/5J14ECONN270_10146445-101LFA10A10B10B10C10C10D10D10E10E10F10F10G10G10H10H10I10I10J10J10K10K10L10L10M1_10M1_10M2_10M2_10N10N10O10O10P10P10Q10Q10R10R10S10S10T10T10U10U10V10V10W10W10X10X10Y10Y10Z10Z10A9A9B9B9C9C9D9D9E9E9F9F9G9G9H9H9I9I9J9J9K9K9L9L9M9M9N1_9N1_9N2_9N2_9O9O9P9P9Q9Q9R9R9S9S9T9T9U9U9V9V9W9W9X9X9Y9Y9Z9Z9MB_3V3IO_RSVD1MB_3V3IO_RSVD3GPU_WP_HW_CTRL_NMB_3V3IO_RSVD4UART_MB_BIC_TX_BUF_RUART_MB_BIC_RX
UART_MB_BIC_TXUART_MB_BIC_R_TXUART_MB_BIC_TX_BUFUART_MB_BIC_TX_BUF_RBUF_UART_MB_BIC_TX_ENUART_MB_BIC_RXUART_MB_BIC_R_RXUART_MB_BIC_RX_BUFUART_MB_BIC_RX_BUF_RBUF_UART_MB_BIC_RX_ENSMB_MB_I3C_ISO_SCLSMB_MB_I3C_ISO_SDAMB_I3C_ISO_EN
I3C_MB_BMC_SDAI3C_MB_BMC_SCLMB_3V3IO_RSVD1_ISOMB_3V3IO_RSVD1_NMB_3V3IO_RSVD3_ISOMB_3V3IO_RSVD3_NMB_3V3IO_RSVD4_ISOMB_3V3IO_RSVD4_N



5
5
4
4
3
3
2
2
1
1
D D
C C
B B
A A
EXAMAX_10P8C_J9_GPU78(1/5)
P5E_PEX3_STN7_RX_DN<112>[52]P5E_PEX3_STN7_RX_DP<112>[52]P5E_PEX3_STN4_RX_DN<79>[51]P5E_PEX3_STN4_RX_DP<79>[51]P5E_PEX3_STN7_TX_C_DN<112>[52]P5E_PEX3_STN7_TX_C_DP<112>[52]P5E_PEX3_STN4_TX_C_DN<79>[51]P5E_PEX3_STN4_TX_C_DP<79>[51]P5E_PEX3_STN7_RX_DN<120>[52]P5E_PEX3_STN7_RX_DP<120>[52]P5E_PEX3_STN4_RX_DN<71>[51]P5E_PEX3_STN4_RX_DP<71>[51]P5E_PEX3_STN7_TX_C_DN<120>[52]P5E_PEX3_STN7_TX_C_DP<120>[52]P5E_PEX3_STN4_TX_C_DN<71>[51]P5E_PEX3_STN4_TX_C_DP<71>[51]P5E_PEX3_STN7_RX_DN<113>[52]P5E_PEX3_STN7_RX_DP<113>[52]P5E_PEX3_STN4_RX_DN<78>[51]P5E_PEX3_STN4_RX_DP<78>[51]P5E_PEX3_STN7_TX_C_DN<113>[52]P5E_PEX3_STN7_TX_C_DP<113>[52]P5E_PEX3_STN4_TX_C_DN<78>[51]P5E_PEX3_STN4_TX_C_DP<78>[51]P5E_PEX3_STN4_RX_DN<70>[51]P5E_PEX3_STN4_RX_DP<70>[51]P5E_PEX3_STN4_TX_C_DN<70>[51]P5E_PEX3_STN4_TX_C_DP<70>[51]P5E_PEX3_STN7_RX_DP<121>[52]P5E_PEX3_STN7_RX_DN<121>[52]P5E_PEX3_STN7_TX_C_DP<121>[52]P5E_PEX3_STN7_TX_C_DN<121>[52]
SizeDoc NumberRevDate: SheetofReviewerDesignerDepartmentProject
Page TitleCCBU D159 257Tuesday, August 29, 2023<project_name><Designer> GRANDTETON_SWB_20230829159 EXAMAX_10P8C_J9_GPU78(1/5)<Reviewer>SizeDoc NumberRevDate: SheetofReviewerDesignerDepartmentProject
Page TitleCCBU D159 257Tuesday, August 29, 2023<project_name><Designer> GRANDTETON_SWB_20230829159 EXAMAX_10P8C_J9_GPU78(1/5)<Reviewer>SizeDoc NumberRevDate: SheetofReviewerDesignerDepartmentProject
Page TitleCCBU D159 257Tuesday, August 29, 2023<project_name><Designer> GRANDTETON_SWB_20230829159 EXAMAX_10P8C_J9_GPU78(1/5)<Reviewer>
BA IHGFEDC J K L M NO PQ RST U V W X Y Z1
2
1/5J9ACONN270_10146445-101LFA2A2B1B1B2B2C1C1C2C2D1D1D2D2E1E1E2E2F1F1F2F2G1G1G2G2H1H1H2H2I1I1I2I2J1J1J2J2K1K1K2K2L1L1L2L2M1M1M1_2M1_2M2_2M2_2N1_1N1_1N2N2N2_1N2_1O1O1O2O2P1P1P2P2Q1Q1Q2Q2R1R1R2R2S1S1S2S2T1T1T2T2U1U1U2U2V1V1V2V2W1W1W2W2X1X1X2X2Y1Y1Y2Y2Z1Z1Z2Z2A1A1P5E_PEX3_STN7_RX_DN<112>P5E_PEX3_STN7_RX_DP<112>P5E_PEX3_STN4_RX_DN<79>P5E_PEX3_STN4_RX_DP<79>P5E_PEX3_STN7_TX_C_DN<112>P5E_PEX3_STN7_TX_C_DP<112>P5E_PEX3_STN4_TX_C_DN<79>P5E_PEX3_STN4_TX_C_DP<79>P5E_PEX3_STN7_RX_DN<120>P5E_PEX3_STN7_RX_DP<120>P5E_PEX3_STN4_RX_DN<71>P5E_PEX3_STN4_RX_DP<71>P5E_PEX3_STN7_TX_C_DN<120>P5E_PEX3_STN7_TX_C_DP<120>P5E_PEX3_STN4_TX_C_DN<71>P5E_PEX3_STN4_TX_C_DP<71>P5E_PEX3_STN7_RX_DN<113>P5E_PEX3_STN7_RX_DP<113>P5E_PEX3_STN4_RX_DN<78>P5E_PEX3_STN4_RX_DP<78>P5E_PEX3_STN7_TX_C_DN<113>P5E_PEX3_STN7_TX_C_DP<113>P5E_PEX3_STN4_TX_C_DN<78>P5E_PEX3_STN4_TX_C_DP<78>P5E_PEX3_STN4_RX_DN<70>P5E_PEX3_STN4_RX_DP<70>P5E_PEX3_STN4_TX_C_DN<70>P5E_PEX3_STN4_TX_C_DP<70>P5E_PEX3_STN7_RX_DP<121>P5E_PEX3_STN7_RX_DN<121>P5E_PEX3_STN7_TX_C_DP<121>P5E_PEX3_STN7_TX_C_DN<121>



5
5
4
4
3
3
2
2
1
1
D D
C C
B B
A A
EXAMAX_10P8C_J9_GPU78(2/5)
P5E_PEX3_STN7_RX_DN<115>[52]P5E_PEX3_STN7_RX_DP<115>[52]P5E_PEX3_STN4_RX_DN<76>[51]P5E_PEX3_STN4_RX_DP<76>[51]P5E_PEX3_STN7_TX_C_DN<115>[52]P5E_PEX3_STN7_TX_C_DP<115>[52]P5E_PEX3_STN4_TX_C_DN<76>[51]P5E_PEX3_STN4_TX_C_DP<76>[51]P5E_PEX3_STN7_RX_DN<123>[52]P5E_PEX3_STN7_RX_DP<123>[52]P5E_PEX3_STN4_RX_DN<68>[51]P5E_PEX3_STN4_RX_DP<68>[51]P5E_PEX3_STN7_TX_C_DN<123>[52]P5E_PEX3_STN7_TX_C_DP<123>[52]P5E_PEX3_STN4_TX_C_DN<68>[51]P5E_PEX3_STN4_TX_C_DP<68>[51]P5E_PEX3_STN7_RX_DN<114>[52]P5E_PEX3_STN7_RX_DP<114>[52]P5E_PEX3_STN4_RX_DN<77>[51]P5E_PEX3_STN4_RX_DP<77>[51]P5E_PEX3_STN4_TX_C_DN<77>[51]P5E_PEX3_STN4_TX_C_DP<77>[51]P5E_PEX3_STN4_RX_DN<69>[51]P5E_PEX3_STN4_RX_DP<69>[51]P5E_PEX3_STN4_TX_C_DN<69>[51]P5E_PEX3_STN4_TX_C_DP<69>[51]P5E_PEX3_STN7_RX_DP<122>[52]P5E_PEX3_STN7_RX_DN<122>[52]P5E_PEX3_STN7_TX_C_DP<122>[52]P5E_PEX3_STN7_TX_C_DN<122>[52]P5E_PEX3_STN7_TX_C_DN<114>[52]P5E_PEX3_STN7_TX_C_DP<114>[52]
SizeDoc NumberRevDate: SheetofReviewerDesignerDepartmentProject
Page TitleCCBU D160 257Tuesday, August 29, 2023<project_name><Designer> GRANDTETON_SWB_20230829160 EXAMAX_10P8C_J9_GPU78(2/5)<Reviewer>SizeDoc NumberRevDate: SheetofReviewerDesignerDepartmentProject
Page TitleCCBU D160 257Tuesday, August 29, 2023<project_name><Designer> GRANDTETON_SWB_20230829160 EXAMAX_10P8C_J9_GPU78(2/5)<Reviewer>SizeDoc NumberRevDate: SheetofReviewerDesignerDepartmentProject
Page TitleCCBU D160 257Tuesday, August 29, 2023<project_name><Designer> GRANDTETON_SWB_20230829160 EXAMAX_10P8C_J9_GPU78(2/5)<Reviewer>
BA IHGFEDC J K L M NO PQ R S T U V W X Y Z432/5J9BCONN270_10146445-101LFA4A4B4B4C4C4D4D4E4E4F4F4G4G4H4H4I4I4J4J4K4K4L4L4M1_4M1_4M2_4M2_4N4N4O4O4P4P4Q4Q4R4R4S4S4T4T4U4U4V4V4W4W4X4X4Y4Y4Z4Z4A3A3B3B3C3C3D3D3E3E3F3F3G3G3H3H3I3I3J3J3K3K3L3L3M3M3N1_3N1_3N2_3N2_3O3O3P3P3Q3Q3R3R3S3S3T3T3U3U3V3V3W3W3X3X3Y3Y3Z3Z3P5E_PEX3_STN7_RX_DN<115>P5E_PEX3_STN7_RX_DP<115>P5E_PEX3_STN4_RX_DN<76>P5E_PEX3_STN4_RX_DP<76>P5E_PEX3_STN7_TX_C_DN<115>P5E_PEX3_STN7_TX_C_DP<115>P5E_PEX3_STN4_TX_C_DN<76>P5E_PEX3_STN4_TX_C_DP<76>P5E_PEX3_STN7_RX_DN<123>P5E_PEX3_STN7_RX_DP<123>P5E_PEX3_STN4_RX_DN<68>P5E_PEX3_STN4_RX_DP<68>P5E_PEX3_STN7_TX_C_DN<123>P5E_PEX3_STN7_TX_C_DP<123>P5E_PEX3_STN4_TX_C_DN<68>P5E_PEX3_STN4_TX_C_DP<68>P5E_PEX3_STN7_RX_DN<114>P5E_PEX3_STN7_RX_DP<114>P5E_PEX3_STN4_RX_DN<77>P5E_PEX3_STN4_RX_DP<77>P5E_PEX3_STN4_TX_C_DN<77>P5E_PEX3_STN4_TX_C_DP<77>P5E_PEX3_STN4_RX_DN<69>P5E_PEX3_STN4_RX_DP<69>P5E_PEX3_STN4_TX_C_DN<69>P5E_PEX3_STN4_TX_C_DP<69>P5E_PEX3_STN7_RX_DP<122>P5E_PEX3_STN7_RX_DN<122>P5E_PEX3_STN7_TX_C_DP<122>P5E_PEX3_STN7_TX_C_DN<122>P5E_PEX3_STN7_TX_C_DN<114>P5E_PEX3_STN7_TX_C_DP<114>



5
5
4
4
3
3
2
2
1
1
D D
C C
B B
A A
EXAMAX_10P8C_J9_GPU78(3/5)
P5E_PEX3_STN7_RX_DN<117>[52]P5E_PEX3_STN7_RX_DP<117>[52]P5E_PEX3_STN4_RX_DN<74>[51]P5E_PEX3_STN4_RX_DP<74>[51]P5E_PEX3_STN7_TX_C_DN<117>[52]P5E_PEX3_STN7_TX_C_DP<117>[52]P5E_PEX3_STN4_TX_C_DN<74>[51]P5E_PEX3_STN4_TX_C_DP<74>[51]P5E_PEX3_STN7_RX_DN<125>[52]P5E_PEX3_STN7_RX_DP<125>[52]P5E_PEX3_STN4_RX_DN<66>[51]P5E_PEX3_STN4_RX_DP<66>[51]P5E_PEX3_STN7_TX_C_DN<125>[52]P5E_PEX3_STN7_TX_C_DP<125>[52]P5E_PEX3_STN4_TX_C_DN<66>[51]P5E_PEX3_STN4_TX_C_DP<66>[51]P5E_PEX3_STN7_RX_DN<116>[52]P5E_PEX3_STN7_RX_DP<116>[52]P5E_PEX3_STN4_RX_DN<75>[51]P5E_PEX3_STN4_RX_DP<75>[51]P5E_PEX3_STN7_TX_C_DN<116>[52]P5E_PEX3_STN7_TX_C_DP<116>[52]P5E_PEX3_STN4_TX_C_DN<75>[51]P5E_PEX3_STN4_TX_C_DP<75>[51]P5E_PEX3_STN7_RX_DN<124>[52]P5E_PEX3_STN7_RX_DP<124>[52]P5E_PEX3_STN4_RX_DN<67>[51]P5E_PEX3_STN4_RX_DP<67>[51]P5E_PEX3_STN7_TX_C_DN<124>[52]P5E_PEX3_STN7_TX_C_DP<124>[52]P5E_PEX3_STN4_TX_C_DN<67>[51]P5E_PEX3_STN4_TX_C_DP<67>[51]
SizeDoc NumberRevDate: SheetofReviewerDesignerDepartmentProject
Page TitleCCBU D161 257Tuesday, August 29, 2023<project_name><Designer> GRANDTETON_SWB_20230829161 EXAMAX_10P8C_J9_GPU78(3/5)<Reviewer>SizeDoc NumberRevDate: SheetofReviewerDesignerDepartmentProject
Page TitleCCBU D161 257Tuesday, August 29, 2023<project_name><Designer> GRANDTETON_SWB_20230829161 EXAMAX_10P8C_J9_GPU78(3/5)<Reviewer>SizeDoc NumberRevDate: SheetofReviewerDesignerDepartmentProject
Page TitleCCBU D161 257Tuesday, August 29, 2023<project_name><Designer> GRANDTETON_SWB_20230829161 EXAMAX_10P8C_J9_GPU78(3/5)<Reviewer>
BA IHGFEDC J K L M NO PQ RST U V W X Y Z563/5J9CCONN270_10146445-101LFA6A6B6B6C6C6D6D6E6E6F6F6G6G6H6H6I6I6J6J6K6K6L6L6M1_6M1_6M2_6M2_6N6N6O6O6P6P6Q6Q6R6R6S6S6T6T6U6U6V6V6W6W6X6X6Y6Y6Z6Z6A5A5B5B5C5C5D5D5E5E5F5F5G5G5H5H5I5I5J5J5K5K5L5L5M5M5N1_5N1_5N2_5N2_5O5O5P5P5Q5Q5R5R5S5S5T5T5U5U5V5V5W5W5X5X5Y5Y5Z5Z5P5E_PEX3_STN7_RX_DN<117>P5E_PEX3_STN7_RX_DP<117>P5E_PEX3_STN4_RX_DN<74>P5E_PEX3_STN4_RX_DP<74>P5E_PEX3_STN7_TX_C_DN<117>P5E_PEX3_STN7_TX_C_DP<117>P5E_PEX3_STN4_TX_C_DN<74>P5E_PEX3_STN4_TX_C_DP<74>P5E_PEX3_STN7_RX_DN<125>P5E_PEX3_STN7_RX_DP<125>P5E_PEX3_STN4_RX_DN<66>P5E_PEX3_STN4_RX_DP<66>P5E_PEX3_STN7_TX_C_DN<125>P5E_PEX3_STN7_TX_C_DP<125>P5E_PEX3_STN4_TX_C_DN<66>P5E_PEX3_STN4_TX_C_DP<66>P5E_PEX3_STN7_RX_DN<116>P5E_PEX3_STN7_RX_DP<116>P5E_PEX3_STN4_RX_DN<75>P5E_PEX3_STN4_RX_DP<75>P5E_PEX3_STN7_TX_C_DN<116>P5E_PEX3_STN7_TX_C_DP<116>P5E_PEX3_STN4_TX_C_DN<75>P5E_PEX3_STN4_TX_C_DP<75>P5E_PEX3_STN7_RX_DN<124>P5E_PEX3_STN7_RX_DP<124>P5E_PEX3_STN4_RX_DN<67>P5E_PEX3_STN4_RX_DP<67>P5E_PEX3_STN7_TX_C_DN<124>P5E_PEX3_STN7_TX_C_DP<124>P5E_PEX3_STN4_TX_C_DN<67>P5E_PEX3_STN4_TX_C_DP<67>



5
5
4
4
3
3
2
2
1
1
D D
C C
B B
A A
EXAMAX_10P8C_J9_GPU78(4/5)
DVT_CHANGEDVT_CHANGE
P5E_PEX3_STN7_RX_DN<119>[52]P5E_PEX3_STN7_RX_DP<119>[52]P5E_PEX3_STN4_RX_DN<72>[51]P5E_PEX3_STN4_RX_DP<72>[51]P5E_PEX3_STN7_TX_C_DN<119>[52]P5E_PEX3_STN7_TX_C_DP<119>[52]P5E_PEX3_STN4_TX_C_DN<72>[51]P5E_PEX3_STN4_TX_C_DP<72>[51]P5E_PEX3_STN7_RX_DN<127>[52]P5E_PEX3_STN7_RX_DP<127>[52]P5E_PEX3_STN4_RX_DN<64>[51]P5E_PEX3_STN4_RX_DP<64>[51]P5E_PEX3_STN7_TX_C_DN<127>[52]P5E_PEX3_STN7_TX_C_DP<127>[52]P5E_PEX3_STN4_TX_C_DN<64>[51]P5E_PEX3_STN4_TX_C_DP<64>[51]P5E_PEX3_STN7_RX_DN<118>[52]P5E_PEX3_STN7_RX_DP<118>[52]P5E_PEX3_STN4_RX_DN<73>[51]P5E_PEX3_STN4_RX_DP<73>[51]P5E_PEX3_STN7_TX_C_DN<118>[52]P5E_PEX3_STN7_TX_C_DP<118>[52]P5E_PEX3_STN4_TX_C_DN<73>[51]P5E_PEX3_STN4_TX_C_DP<73>[51]P5E_PEX3_STN7_RX_DN<126>[52]P5E_PEX3_STN7_RX_DP<126>[52]P5E_PEX3_STN4_RX_DN<65>[51]P5E_PEX3_STN4_RX_DP<65>[51]P5E_PEX3_STN7_TX_C_DN<126>[52]P5E_PEX3_STN7_TX_C_DP<126>[52]P5E_PEX3_STN4_TX_C_DN<65>[51]P5E_PEX3_STN4_TX_C_DP<65>[51]PRSNT_GPU_A1_N[162]PRSNT_GPU_A1_R_N[157]PRSNT_GPU_A1_N [162]SizeDoc NumberRevDate: SheetofReviewerDesignerDepartmentProject
Page TitleCCBU D162 257Tuesday, August 29, 2023<project_name><Designer> GRANDTETON_SWB_20230829162 EXAMAX_10P8C_J9_GPU78(4/5)<Reviewer>SizeDoc NumberRevDate: SheetofReviewerDesignerDepartmentProject
Page TitleCCBU D162 257Tuesday, August 29, 2023<project_name><Designer> GRANDTETON_SWB_20230829162 EXAMAX_10P8C_J9_GPU78(4/5)<Reviewer>SizeDoc NumberRevDate: SheetofReviewerDesignerDepartmentProject
Page TitleCCBU D162 257Tuesday, August 29, 2023<project_name><Designer> GRANDTETON_SWB_20230829162 EXAMAX_10P8C_J9_GPU78(4/5)<Reviewer>
BA IHGFEDC J K L M NO PQ RST U V W X Y Z784/5J9DCONN270_10146445-101LFA8A8B8B8C8C8D8D8E8E8F8F8G8G8H8H8I8I8J8J8K8K8L8L8M1_8M1_8M2_8M2_8N8N8O8O8P8P8Q8Q8R8R8S8S8T8T8U8U8V8V8W8W8X8X8Y8Y8Z8Z8A7A7B7B7C7C7D7D7E7E7F7F7G7G7H7H7I7I7J7J7K7K7L7L7M7M7N1_7N1_7N2_7N2_7O7O7P7P7Q7Q7R7R7S7S7T7T7U7U7V7V7W7W7X7X7Y7Y7Z7Z7R6775 0 R0402-02015%
P5E_PEX3_STN7_RX_DN<119>P5E_PEX3_STN7_RX_DP<119>P5E_PEX3_STN4_RX_DN<72>P5E_PEX3_STN4_RX_DP<72>P5E_PEX3_STN7_TX_C_DN<119>P5E_PEX3_STN7_TX_C_DP<119>P5E_PEX3_STN4_TX_C_DN<72>P5E_PEX3_STN4_TX_C_DP<72>P5E_PEX3_STN7_RX_DN<127>P5E_PEX3_STN7_RX_DP<127>P5E_PEX3_STN4_RX_DN<64>P5E_PEX3_STN4_RX_DP<64>P5E_PEX3_STN7_TX_C_DN<127>P5E_PEX3_STN7_TX_C_DP<127>P5E_PEX3_STN4_TX_C_DN<64>P5E_PEX3_STN4_TX_C_DP<64>P5E_PEX3_STN7_RX_DN<118>P5E_PEX3_STN7_RX_DP<118>P5E_PEX3_STN4_RX_DN<73>P5E_PEX3_STN4_RX_DP<73>P5E_PEX3_STN7_TX_C_DN<118>P5E_PEX3_STN7_TX_C_DP<118>P5E_PEX3_STN4_TX_C_DN<73>P5E_PEX3_STN4_TX_C_DP<73>P5E_PEX3_STN7_RX_DN<126>P5E_PEX3_STN7_RX_DP<126>P5E_PEX3_STN4_RX_DN<65>P5E_PEX3_STN4_RX_DP<65>P5E_PEX3_STN7_TX_C_DN<126>P5E_PEX3_STN7_TX_C_DP<126>P5E_PEX3_STN4_TX_C_DN<65>P5E_PEX3_STN4_TX_C_DP<65>PRSNT_GPU_A1_NPRSNT_GPU_A1_R_NPRSNT_GPU_A1_N



5
5
4
4
3
3
2
2
1
1
D D
C C
B B
A A
EXAMAX_10P8C_J9_GPU78(5/5)
GPU_3V3IO_RSVD4[163,167]GPU_3V3IO_RSVD1[163,167]GPU_3V3IO_RSVD3[163,167]GPU_WP_HW_CTRL_R_N[167]GPU_3V3IO_RSVD1 [163,167]GPU_3V3IO_RSVD1_ISO_R[118]GPU_3V3IO_RSVD3_ISO_R[118]GPU_3V3IO_RSVD3 [163,167]GPU_3V3IO_RSVD4_ISO_R[118]GPU_3V3IO_RSVD4 [163,167]
P3V3_AUXP3V3_AUXP3V3_AUXP3V3_AUXP3V3_AUXP3V3_AUXP3V3_AUXP3V3_AUXP3V3_AUX
SizeDoc NumberRevDate: SheetofReviewerDesignerDepartmentProject
Page TitleCCBU D163 257Tuesday, August 29, 2023<project_name><Designer> GRANDTETON_SWB_20230829163 EXAMAX_10P8C_J9_GPU78(5/5)<Reviewer>SizeDoc NumberRevDate: SheetofReviewerDesignerDepartmentProject
Page TitleCCBU D163 257Tuesday, August 29, 2023<project_name><Designer> GRANDTETON_SWB_20230829163 EXAMAX_10P8C_J9_GPU78(5/5)<Reviewer>SizeDoc NumberRevDate: SheetofReviewerDesignerDepartmentProject
Page TitleCCBU D163 257Tuesday, August 29, 2023<project_name><Designer> GRANDTETON_SWB_20230829163 EXAMAX_10P8C_J9_GPU78(5/5)<Reviewer>
R6692 33R0402-02011%R6694 33 R0402-02011%NIC44521000PFC02015%16VNIR66834.7KR0402-02011%C44531000PFC02015%16VNIR66844.7KR0402-02011%R6687100K<Part Number>R0402-02011%1/16WNIR6681100K<Part Number>R0402-02011%1/16WNIR6685100K<Part Number>R0402-02011%1/16WNIQ244BBSS138BKSD23G25S24R66774.7KR0402-02011%Q244ABSS138BKSS11G12D16R6682100K<Part Number>R0402-02011%1/16WNIR6686 33R0402-02011%R6688 33 R0402-02011%NIR66784.7KR0402-02011%R66894.7KR0402-02011%C44541000PFC02015%16VNIQ242ABSS138BKSS11G12D16R6679 33R0402-02011%N ZA I OH PG QF RE SDB TC U VJ K WL XM Y1095/5J9ECONN270_10146445-101LFA10A10B10B10C10C10D10D10E10E10F10F10G10G10H10H10I10I10J10J10K10K10L10L10M1_10M1_10M2_10M2_10N10N10O10O10P10P10Q10Q10R10R10S10S10T10T10U10U10V10V10W10W10X10X10Y10Y10Z10Z10A9A9B9B9C9C9D9D9E9E9F9F9G9G9H9H9I9I9J9J9K9K9L9L9M9M9N1_9N1_9N2_9N2_9O9O9P9P9Q9Q9R9R9S9S9T9T9U9U9V9V9W9W9X9X9Y9Y9Z9Z9R66904.7KR0402-02011%R6693100K<Part Number>R0402-02011%1/16WNIQ243BBSS138BKSD23G25S24R6691100K<Part Number>R0402-02011%1/16WNIQ242BBSS138BKSD23G25S24R6680 33 R0402-02011%NIQ243ABSS138BKSS11G12D16GPU_3V3IO_RSVD4GPU_3V3IO_RSVD1GPU_3V3IO_RSVD3GPU_WP_HW_CTRL_R_NGPU_3V3IO_RSVD1_ISOGPU_3V3IO_RSVD1_NGPU_3V3IO_RSVD3_ISOGPU_3V3IO_RSVD3_NGPU_3V3IO_RSVD4_ISOGPU_3V3IO_RSVD4_N



5
5
4
4
3
3
2
2
1
1
D D
C C
B B
A A
CAP Place close to J3 CAP Place close to J11
J11_J3_BYPASS
DVT_CHANGEDVT_CHANGEPVT_CHANGEGPU_BASE_PWR_GD[126,164]GPU_BASE_PWR_GD_R [131]GPU_BASE_ID1[132,164]GPU_BASE_ID1_R [127]RST_GPU_FPGA_PEX_RST_N[133,164]RST_GPU_FPGA_PEX_RST_R_N [128]GPU_THERM_OVERT_N[128,164]GPU_THERM_OVERT_R_N [133]GPU_PEX_STRAP0[133,164]GPU_PEX_STRAP0_R [128]GPU_PWR_BRAKE_N[133,164]GPU_PWR_BRAKE_R_N [128]GPU_BASE_ID0[133,164]GPU_BASE_ID0_R [128]SMB_GPU_2_SCL[133]SMB_GPU_2_R_SCL [128]SMB_GPU_2_SDA[133]SMB_GPU_2_R_SDA [128]GPU_BASE_FPGA_READY[128,164]GPU_BASE_FPGA_READY_R [133]GPU_PEX_STRAP1[133,164]GPU_PEX_STRAP1_R [128]SMB_GPU_1_SCL[133]SMB_GPU_1_R_SCL [128]SMB_GPU_1_SDA[133]SMB_GPU_1_R_SDA [128]GPU_BASE_PWR_EN[130,164]GPU_BASE_PWR_EN_R [125]GPU_HGX_DETECT_N[125,164]GPU_HGX_DETECT_R_N [130]GPU_HGX_DETECT_N [125,164]GPU_BASE_PWR_GD [126,164]PRSNT_GPU_N [124,127]GPU_THERM_OVERT_N [128,164]GPU_BASE_FPGA_READY [128,164]RST_MB_PERST_2_N [129]GPU_BASE_PWR_EN [130,164]RST_MB_PERST_1_N [129,131]GPU_BASE_ID1 [132,164]RST_GPU_FPGA_PEX_RST_N [133,164]GPU_PEX_STRAP0 [133,164]GPU_PWR_BRAKE_N [133,164]GPU_BASE_ID0 [133,164]GPU_PEX_STRAP1 [133,164]RST_MB_PERST_0_N [129,133]
PRSNT_GPU_D_N[124,164]PRSNT_GPU_D_R_N [129]PRSNT_GPU_D_N [124,164]
SizeDoc NumberRevDate: SheetofReviewerDesignerDepartmentProject
Page TitleCCBU D164 257Tuesday, August 29, 2023<project_name><Designer> GRANDTETON_SWB_20230829164 J11_J3_BYPASS<Reviewer>SizeDoc NumberRevDate: SheetofReviewerDesignerDepartmentProject
Page TitleCCBU D164 257Tuesday, August 29, 2023<project_name><Designer> GRANDTETON_SWB_20230829164 J11_J3_BYPASS<Reviewer>SizeDoc NumberRevDate: SheetofReviewerDesignerDepartmentProject
Page TitleCCBU D164 257Tuesday, August 29, 2023<project_name><Designer> GRANDTETON_SWB_20230829164 J11_J3_BYPASS<Reviewer>
R1833 0 R0402-02015%R1835 0 R0402-02015%C4009 0.1UF C0402-0201NIR1825 0 R0402-02015%C4013 0.1UF C0402-0201NIR1828 0 R0402-02015%C4040 0.1UF C0402-0201NIC4030 0.1UF C0402-0201NIC4014 0.1UF C0402-0201NIR1829 0 R0402-02015%C4017 0.1UF C0402-0201NIC4051 0.1UF C0402-0201NIC4041 0.1UF C0402-0201NI
R1834 0 R0402-02015%R1822 0 R0402-02015%R1830 0 R0402-02015%R1836 0 R0402-02015%R1826 0 R0402-02015%C4042 0.1UF C0402-0201NIC4037 0.1UF C0402-0201NI
R1870 0 R0402-02015%
C4025 0.1UF C0402-0201NIC4010 0.1UF C0402-0201NIC4048 0.1UF C0402-0201NI
R6256 0 R0402-02015%
C4038 0.1UF C0402-0201NIC4033 0.1UF C0402-0201NIR1824 0 R0402-02015%R1831 100 1% R0402-0201R1827 0 R0402-02015%C4034 0.1UF C0402-0201NIR1832 100 1% R0402-0201



5
5
4
4
3
3
2
2
1
1
D D
C C
B B
A A
CAP Place close to J5 CAP Place close to J12
J12_J5_BYPASS
DVT_CHANGE
DVT_CHANGE
GPU_FPGA_EROT_RECOV_N[134,165]GPU_FPGA_EROT_RECOV_R_N [139]GPU_FPGA_EROT_FATALERR_N[139,165]GPU_FPGA_EROT_FATALERR_R_N [134]PRSNT_GPU_HMC_N[140,165]PRSNT_GPU_HMC_R_N [135]GPU_3V3IO_RSVD0_FFU[140,165]GPU_3V3IO_RSVD0_FFU_R [135]GPU_BASE_HMC_READY[141,165]GPU_BASE_HMC_READY_R [136]GPU_3V3IO_RSVD1_FFU[141,165]GPU_3V3IO_RSVD1_FFU_R [136]GPU_BASE_STBY_EN[137,165]GPU_BASE_STBY_EN_R [142]SMB_GPU2_ALERT_N[143,165]SMB_GPU2_ALERT_R_N [138]SMB_GPU1_ALERT_N[143,165]SMB_GPU1_ALERT_R_N [138]GPU_FPGA_BOOT_EN[138,165]GPU_FPGA_BOOT_EN_R [143]RST_GPU_FPGA_EROT_N[138,165]RST_GPU_FPGA_EROT_R_N [143]GPU_FPGA_EROT_RECOV_N [134,165]GPU_BASE_STBY_EN [137,165]GPU_FPGA_BOOT_EN [138,165]MB_BMC_MON [132,138]RST_GPU_FPGA_EROT_N [138,165]GPU_FPGA_EROT_FATALERR_N [139,165]PRSNT_GPU_HMC_N [140,165]GPU_3V3IO_RSVD0_FFU [140,165]GPU_BASE_HMC_READY [141,165]GPU_3V3IO_RSVD1_FFU [141,165]SMB_GPU2_ALERT_N [143,165]SMB_GPU1_ALERT_N [143,165]SizeDoc NumberRevDate: SheetofReviewerDesignerDepartmentProject
Page TitleCCBU D165 257Tuesday, August 29, 2023<project_name><Designer> GRANDTETON_SWB_20230829165 J12_J5_BYPASS<Reviewer>SizeDoc NumberRevDate: SheetofReviewerDesignerDepartmentProject
Page TitleCCBU D165 257Tuesday, August 29, 2023<project_name><Designer> GRANDTETON_SWB_20230829165 J12_J5_BYPASS<Reviewer>SizeDoc NumberRevDate: SheetofReviewerDesignerDepartmentProject
Page TitleCCBU D165 257Tuesday, August 29, 2023<project_name><Designer> GRANDTETON_SWB_20230829165 J12_J5_BYPASS<Reviewer>
R1847 0 R0402-02015%C4104 0.1UF C0402-0201NIC4099 0.1UF C0402-0201NIR1848 0 R0402-02015%C4080 0.1UF C0402-0201NI
R1840 0 R0402-02015%R1838 0 R0402-02015%
C4100 0.1UF C0402-0201NIR1846 0 R0402-02015%C4106 0.1UF C0402-0201NIC4096 0.1UF C0402-0201NIC4082 0.1UF C0402-0201NI
R1839 0 R0402-02015%R1841 0 R0402-02015%C4052 0.1UF C0402-0201NIR1845 0 R0402-02015%C4097 0.1UF C0402-0201NIR1843 0 R0402-02015%
C4078 0.1UF C0402-0201NI
R1837 0 R0402-02015%
C4098 0.1UF C0402-0201NIR1842 0 R0402-02015%
C4064 0.1UF C0402-0201NI



5
5
4
4
3
3
2
2
1
1
D D
C C
B B
A A
CAP Place close to J7 CAP Place close to J13
J13_J7_BYPASS
DVT_CHANGEDVT_CHANGEGPU_3V3IO_RSVD3_FFU[144,166]GPU_3V3IO_RSVD3_FFU_R [149]GPU_3V3IO_RSVD5_FFU[146,166]GPU_3V3IO_RSVD5_FFU_R [151]GPU_FPGA_OVERT_N[147,166]GPU_FPGA_OVERT_R_N [152]GPU_3V3IO_RSVD3_FFU [144,166]GPU_3V3IO_RSVD5_FFU [146,166]GPU_FPGA_OVERT_N [147,166]MB_HSC_EN [152]
SizeDoc NumberRevDate: SheetofReviewerDesignerDepartmentProject
Page TitleCCBU D166 257Tuesday, August 29, 2023<project_name><Designer> GRANDTETON_SWB_20230829166 J13_J7_BYPASS<Reviewer>SizeDoc NumberRevDate: SheetofReviewerDesignerDepartmentProject
Page TitleCCBU D166 257Tuesday, August 29, 2023<project_name><Designer> GRANDTETON_SWB_20230829166 J13_J7_BYPASS<Reviewer>SizeDoc NumberRevDate: SheetofReviewerDesignerDepartmentProject
Page TitleCCBU D166 257Tuesday, August 29, 2023<project_name><Designer> GRANDTETON_SWB_20230829166 J13_J7_BYPASS<Reviewer>
C4116 0.1UF C0402-0201NIR18520 R0402-02015%C4112 0.1UF C0402-0201NIR18490 R0402-02015%C4108 0.1UF C0402-0201NIR18510 R0402-02015%C4128 0.1UF C0402-0201NI



5
5
4
4
3
3
2
2
1
1
D D
C C
B B
A A
CAP Place close to J9 CAP Place close to J14
J14_J9_BYPASS
GPU_BB_RSVD_1[167]GPU_BB_RSVD_1_RGPU_WP_HW_CTRL_N[158,167]GPU_WP_HW_CTRL_R_N [163]GPU_BB_RSVD_1 [167]GPU_3V3IO_RSVD1 [163]GPU_3V3IO_RSVD3 [163]GPU_3V3IO_RSVD4 [163]MB_SWB_PWR_EN [129,154]RST_MB_BIC_N [132,156]GPU_WP_HW_CTRL_N [158,167]
SizeDoc NumberRevDate: SheetofReviewerDesignerDepartmentProject
Page TitleCCBU D167 257Tuesday, August 29, 2023<project_name><Designer> GRANDTETON_SWB_20230829167 J14_J9_BYPASS<Reviewer>SizeDoc NumberRevDate: SheetofReviewerDesignerDepartmentProject
Page TitleCCBU D167 257Tuesday, August 29, 2023<project_name><Designer> GRANDTETON_SWB_20230829167 J14_J9_BYPASS<Reviewer>SizeDoc NumberRevDate: SheetofReviewerDesignerDepartmentProject
Page TitleCCBU D167 257Tuesday, August 29, 2023<project_name><Designer> GRANDTETON_SWB_20230829167 J14_J9_BYPASS<Reviewer>
C4168 0.1UF C0402-0201NIR1853 0 R0402-02015%C4162 0.1UF C0402-0201NIC4158 0.1UF C0402-0201NIC4164 0.1UF C0402-0201NIC4159 0.1UF C0402-0201NIR1856 0 R0402-02015%C4160 0.1UF C0402-0201NIC4175 0.1UF C0402-0201NI



5
5
4
4
3
3
2
2
1
1
D D
C C
B B
A A
PRIMARY CONNECTOR
NIC_0_J20(1/3)
LANE REVERSAL
PVT2_BOM_CHANGECLK_100M_DB2000QL_NIC0_R_DN[79]CLK_100M_DB2000QL_NIC0_R_DP[79]NIC0_DATA_IN[168]NIC0_DATA_OUT[168]NIC0_CLK[168]PWRGD_NIC0_PWR_GOOD[168]NIC0_MAIN_PWR_EN_R[168]NIC0_LD_N[168]NIC0_SLOT_ID0[169]NCSI_NIC0_RXD1[168]NCSI_NIC0_RXD0[168]NCSI_NIC0_CRS_DV[168]CLK_50M_NIC0_RBT_REF [168]NIC0_RBT_ARB_OUT [168]NIC0_SLOT_ID1 [169]NCSI_NIC0_TX_EN [168]NCSI_NIC0_TXD1 [168]NCSI_NIC0_TXD0 [168]NIC0_MAIN_PWR_EN[116,168]NIC0_MAIN_PWR_EN_R [168]NIC0_AUX_PWR_EN[116,168]NIC0_AUX_PWR_EN_R [168,169]NIC0_BIF0_N[169]NIC0_BIF1_N[169]NIC0_BIF2_N[169]RST_NIC0_PERST0_R_N[170]PRSNTB0_NIC0_N [168,170]PRSNTB0_NIC0_N[168,170]PRSNTB3_NIC0_N[168,170]PRSNTB1_NIC0_N [168,170]PRSNTB2_NIC0_N [168,170]PRSNTB1_NIC0_N [168,170]PRSNTB2_NIC0_N [168,170]PRSNTB3_NIC0_N [168,170]NIC0_AUX_PWR_EN_R[168,169]NIC0_RBT_ARB_IN [168]RST_SMB_NIC0_MUX_ISO_R_N [169]RST_NIC0_PERST1_R_N [170]RST_NIC0_PERST2_R_N [170]RST_NIC0_PERST3_R_N [170]NIC0_RBT_ARB_IN[168]NIC0_RBT_ARB_OUT [168]
NCSI_NIC0_CRS_DV [168]NCSI_NIC0_RXD0 [168]NCSI_NIC0_RXD1 [168]NCSI_NIC0_TXD0 [168]NCSI_NIC0_TXD1 [168]CLK_50M_NIC0_RBT_REF [168]NCSI_NIC0_TX_EN [168]PWRGD_NIC0_PWR_GOOD [168]NIC0_MAIN_PWR_EN [116,168]NIC0_AUX_PWR_EN [116,168]NIC0_LD_N [168]NIC0_DATA_IN [168]NIC0_DATA_OUT [168]PWRGD_NIC0_PWR_GOOD_R[116]PWRGD_NIC0_PWR_GOOD [168]
NIC0_PWRBRK_R_N [192]P5E_PEX0_STN1_TX_C_DP<31>[10]P5E_PEX0_STN1_RX_DN<31> [10]P5E_PEX0_STN1_TX_C_DN<31>[10]P5E_PEX0_STN1_RX_DP<31> [10]P5E_PEX0_STN1_TX_C_DN<30>[10]P5E_PEX0_STN1_RX_DN<30> [10]P5E_PEX0_STN1_TX_C_DP<30>[10]P5E_PEX0_STN1_RX_DP<30> [10]P5E_PEX0_STN1_TX_C_DP<29>[10]P5E_PEX0_STN1_RX_DN<29> [10]P5E_PEX0_STN1_TX_C_DN<29>[10]P5E_PEX0_STN1_RX_DP<29> [10]P5E_PEX0_STN1_TX_C_DN<28>[10]P5E_PEX0_STN1_RX_DN<28> [10]P5E_PEX0_STN1_TX_C_DP<28>[10]P5E_PEX0_STN1_RX_DP<28> [10]P5E_PEX0_STN1_TX_C_DP<27>[10]P5E_PEX0_STN1_RX_DN<27> [10]P5E_PEX0_STN1_TX_C_DN<27>[10]P5E_PEX0_STN1_RX_DP<27> [10]P5E_PEX0_STN1_TX_C_DN<26>[10]P5E_PEX0_STN1_RX_DN<26> [10]P5E_PEX0_STN1_TX_C_DP<26>[10]P5E_PEX0_STN1_RX_DP<26> [10]P5E_PEX0_STN1_TX_C_DP<25>[10]P5E_PEX0_STN1_RX_DN<25> [10]P5E_PEX0_STN1_TX_C_DN<25>[10]P5E_PEX0_STN1_RX_DP<25> [10]P5E_PEX0_STN1_TX_C_DN<24>[10]P5E_PEX0_STN1_RX_DN<24> [10]P5E_PEX0_STN1_TX_C_DP<24>[10]P5E_PEX0_STN1_RX_DP<24> [10]P5E_PEX0_STN1_TX_C_DP<23>[10]P5E_PEX0_STN1_RX_DN<23> [10]P5E_PEX0_STN1_TX_C_DN<23>[10]P5E_PEX0_STN1_RX_DP<23> [10]P5E_PEX0_STN1_TX_C_DN<22>[10]P5E_PEX0_STN1_RX_DN<22> [10]P5E_PEX0_STN1_TX_C_DP<22>[10]P5E_PEX0_STN1_RX_DP<22> [10]P5E_PEX0_STN1_TX_C_DP<21>[10]P5E_PEX0_STN1_RX_DN<21> [10]P5E_PEX0_STN1_TX_C_DN<21>[10]P5E_PEX0_STN1_RX_DP<21> [10]P5E_PEX0_STN1_TX_C_DN<20>[10]P5E_PEX0_STN1_RX_DN<20> [10]P5E_PEX0_STN1_TX_C_DP<20>[10]P5E_PEX0_STN1_RX_DP<20> [10]P5E_PEX0_STN1_TX_C_DP<19>[10]P5E_PEX0_STN1_RX_DN<19> [10]P5E_PEX0_STN1_TX_C_DN<19>[10]P5E_PEX0_STN1_RX_DP<19> [10]P5E_PEX0_STN1_TX_C_DN<18>[10]P5E_PEX0_STN1_RX_DN<18> [10]P5E_PEX0_STN1_TX_C_DP<18>[10]P5E_PEX0_STN1_RX_DP<18> [10]P5E_PEX0_STN1_TX_C_DP<17>[10]P5E_PEX0_STN1_RX_DN<17> [10]P5E_PEX0_STN1_TX_C_DN<17>[10]P5E_PEX0_STN1_RX_DP<17> [10]P5E_PEX0_STN1_TX_C_DN<16>[10]P5E_PEX0_STN1_RX_DN<16> [10]P5E_PEX0_STN1_TX_C_DP<16>[10]P5E_PEX0_STN1_RX_DP<16> [10]NIC0_CLK [168]SMB_NIC0_R_SCL [87,168]SMB_NIC0_R_SDA [87,168]SMB_NIC0_R_SCL [87,168]SMB_NIC0_R_SDA [87,168]P12V_NIC0P3V3_NIC0P12V_NIC0P3V3_NIC0P3V3_AUXP3V3_NIC0
SizeDoc NumberRevDate: SheetofReviewerDesignerDepartmentProject
Page TitleCCBU D168 257Tuesday, August 29, 2023<project_name><Designer> GRANDTETON_SWB_20230829168 NIC_0_J20(1/3)<Reviewer>SizeDoc NumberRevDate: SheetofReviewerDesignerDepartmentProject
Page TitleCCBU D168 257Tuesday, August 29, 2023<project_name><Designer> GRANDTETON_SWB_20230829168 NIC_0_J20(1/3)<Reviewer>SizeDoc NumberRevDate: SheetofReviewerDesignerDepartmentProject
Page TitleCCBU D168 257Tuesday, August 29, 2023<project_name><Designer> GRANDTETON_SWB_20230829168 NIC_0_J20(1/3)<Reviewer>
C8510.1UFX6SC020110%16V<Part Number>
R21100K1% R0402-0201<Part Number>R92.2K5% R0402-0201
R105% R0402-0201<Part Number>
R19100K1% R0402-0201<Part Number>
R405% R0402-0201<Part Number>KEYKEYKEYSCONN168_G64V35313HR
J20
<Part Number>
NIC_PWR_GOODOB1MAIN_PWR_ENOB2LD#OB3DATA_INOB4DATA_OUTOB5CLKOB6SLOT_ID0OB7RBT_RXD1OB8RBT_RXD0OB9GND_OB10OB10REFCLKn2OB11REFCLKp2OB12GND_OB13OB13RBT_CRS_DVOB14+12V_EDGE_B1B1+12V_EDGE_B2B2+12V_EDGE_B3B3+12V_EDGE_B4B4+12V_EDGE_B5B5+12V_EDGE_B6B6BIF0#B7BIF1#B8BIF2#B9PERST0#B10+3.3V_EDGEB11AUX_PWR_ENB12GND_B13B13REFCLKn0B14REFCLKp0B15GND_B16B16PETn0B17PETp0B18GND_B19B19PETn1B20PETp1B21GND_B22B22PETn2B23PETp2B24GND_B25B25PETn3B26PETp3B27GND_B28B28GND_B29B29PETn4B30PETp4B31GND_B32B32PETn5B33PETp5B34GND_B35B35PETn6B36PETp6B37GND_B38B38PETn7B39PETp7B40GND_B41B41PRSNTB0#B42GND_B43B43PETn8B44PETp8B45GND_B46B46PETn9B47PETp9B48GND_B49B49PETn10B50PETp10B51GND_B52B52PETn11B53PETp11B54GND_B55B55PETn12B56
PERST2#OA1PERST3#OA2WAKE#OA3RBT_ARB_INOA4RBT_ARB_OUTOA5SLOT_ID1OA6RBT_TX_ENOA7RBT_TXD1OA8RBT_TXD0OA9GND_OA10OA10REFCLKn3OA11REFCLKp3OA12GND_OA13OA13RBT_CLK_INOA14GND_A1A1GND_A2A2GND_A3A3GND_A4A4GND_A5A5GND_A6A6SMCLKA7SMDATA8SMRST#A9PRSNTA#A10PERST1#A11PRSNTB2#A12GND_A13A13REFCLKn1A14REFCLKp1A15GND_A16A16PERn0A17PERp0A18GND_A19A19PERn1A20PERp1A21GND_A22A22PERn2A23PERp2A24GND_A25A25PERn3A26PERp3A27GND_A28A28GND_A29A29PERn4A30PERp4A31GND_A32A32PERn5A33PERp5A34GND_A35A35PERn6A36PERp6A37GND_A38A38PERn7A39PERp7A40GND_A41A41PRSNTB1#A42GND_A43A43PERn8A44PERp8A45GND_A46A46PERn9A47PERp9A48GND_A49A49PERn10A50PERp10A51GND_A52A52PERn11A53PERp11A54GND_A55A55PERn12A56PERp12A57GND_A58A58PERn13A59PERp13A60GND_A61A61PERn14A62PERp14A63GND_A64A64PERn15A65PERp15A66GND_A67A67USB_DATnA68USB_DATpA69PWRBRK0#A70PETp12B57GND_B58B58PETn13B59PETp13B60GND_B61B61PETn14B62PETp14B63GND_B64B64PETn15B65PETp15B66GND_B67B67RFU1_NCB68RFU2_NCB69PRSNTB3#B70G1G1G2G2G3G3G4G4G5G5G6G6G7G7G8G8G9G9R102.2K5% R0402-0201R18100K1% R0402-0201<Part Number>
C8490.1UFX6SC020110%16V<Part Number>C8550.1UFX6SC0402-020110%25V<Part Number>C8520.1UFX6SC0402-020110%25V<Part Number>
R17100K1% R0402-0201<Part Number>
C8480.1UFX6SC020110%16V<Part Number>R81K1% R0402-0201<Part Number>C8470.1UFX6SC020110%16V<Part Number>R305% R0402-0201<Part Number>C84622UFX6SC0805_H5720%16V<Part Number>
R2410K1% R0402-0201<Part Number>R20100K1% R0402-0201<Part Number>R1210K1% R0402-0201<Part Number>R16100K1% R0402-0201<Part Number>R111K1% R0402-0201<Part Number>R2310K1% R0402-0201<Part Number>R15100K1% R0402-0201<Part Number>R131K1% R0402-0201<Part Number>R51K1% R0402-0201<Part Number>R71K1% R0402-0201<Part Number>R22100K1% R0402-0201<Part Number>
R205% R0402-0201<Part Number>C8530.1UFX6SC0402-020110%25V<Part Number>C8540.1UFX6SC0402-020110%25V<Part Number>R61K1% R0402-0201<Part Number>C8500.1UFX6SC020110%16V<Part Number>C84522UFX6SC0805_H5720%16V<Part Number>
R14100K1% R0402-0201<Part Number>PWRGD_NIC0_PWR_GOODNIC0_MAIN_PWR_EN_RNIC0_LD_NNIC0_DATA_INNIC0_DATA_OUTNIC0_CLKNIC0_SLOT_ID0NCSI_NIC0_RXD1NCSI_NIC0_RXD0NCSI_NIC0_CRS_DVCLK_50M_NIC0_RBT_REFNIC0_RBT_ARB_OUTNIC0_SLOT_ID1NCSI_NIC0_TX_ENNCSI_NIC0_TXD1NCSI_NIC0_TXD0NIC0_RBT_ARB_INNIC0_MAIN_PWR_ENNIC0_MAIN_PWR_EN_RNIC0_AUX_PWR_ENNIC0_AUX_PWR_EN_RNIC0_BIF0_NNIC0_BIF1_NNIC0_BIF2_NPRSNTB3_NIC0_NPRSNTB0_NIC0_NPRSNTB1_NIC0_NPRSNTB2_NIC0_NRST_NIC0_PERST0_R_NPRSNTB0_NIC0_NPRSNTB1_NIC0_NPRSNTB2_NIC0_NPRSNTB3_NIC0_NNIC0_AUX_PWR_EN_RRST_NIC0_PERST1_R_NRST_NIC0_PERST2_R_NRST_NIC0_PERST3_R_NNIC0_RBT_ARB_INNIC0_RBT_ARB_OUT
NCSI_NIC0_CRS_DVNCSI_NIC0_RXD0NCSI_NIC0_RXD1NCSI_NIC0_TXD0NCSI_NIC0_TXD1CLK_50M_NIC0_RBT_REFNCSI_NIC0_TX_ENPWRGD_NIC0_PWR_GOODNIC0_MAIN_PWR_ENNIC0_AUX_PWR_ENNIC0_LD_NNIC0_DATA_INNIC0_DATA_OUTNIC0_PWRBRK_R_N
PWRGD_NIC0_PWR_GOOD_RPWRGD_NIC0_PWR_GOODP5E_PEX0_STN1_TX_C_DP<31>P5E_PEX0_STN1_RX_DN<31>P5E_PEX0_STN1_TX_C_DN<31>P5E_PEX0_STN1_RX_DP<31>P5E_PEX0_STN1_TX_C_DN<30>P5E_PEX0_STN1_RX_DN<30>P5E_PEX0_STN1_TX_C_DP<30>P5E_PEX0_STN1_RX_DP<30>P5E_PEX0_STN1_TX_C_DP<29>P5E_PEX0_STN1_RX_DN<29>P5E_PEX0_STN1_TX_C_DN<29>P5E_PEX0_STN1_RX_DP<29>P5E_PEX0_STN1_TX_C_DN<28>P5E_PEX0_STN1_RX_DN<28>P5E_PEX0_STN1_TX_C_DP<28>P5E_PEX0_STN1_RX_DP<28>P5E_PEX0_STN1_TX_C_DP<27>P5E_PEX0_STN1_RX_DN<27>P5E_PEX0_STN1_TX_C_DN<27>P5E_PEX0_STN1_RX_DP<27>P5E_PEX0_STN1_TX_C_DN<26>P5E_PEX0_STN1_RX_DN<26>P5E_PEX0_STN1_TX_C_DP<26>P5E_PEX0_STN1_RX_DP<26>P5E_PEX0_STN1_TX_C_DP<25>P5E_PEX0_STN1_RX_DN<25>P5E_PEX0_STN1_TX_C_DN<25>P5E_PEX0_STN1_RX_DP<25>P5E_PEX0_STN1_TX_C_DN<24>P5E_PEX0_STN1_RX_DN<24>P5E_PEX0_STN1_TX_C_DP<24>P5E_PEX0_STN1_RX_DP<24>P5E_PEX0_STN1_TX_C_DP<23>P5E_PEX0_STN1_RX_DN<23>P5E_PEX0_STN1_TX_C_DN<23>P5E_PEX0_STN1_RX_DP<23>P5E_PEX0_STN1_TX_C_DN<22>P5E_PEX0_STN1_RX_DN<22>P5E_PEX0_STN1_TX_C_DP<22>P5E_PEX0_STN1_RX_DP<22>P5E_PEX0_STN1_TX_C_DP<21>P5E_PEX0_STN1_RX_DN<21>P5E_PEX0_STN1_TX_C_DN<21>P5E_PEX0_STN1_RX_DP<21>P5E_PEX0_STN1_TX_C_DN<20>P5E_PEX0_STN1_RX_DN<20>P5E_PEX0_STN1_TX_C_DP<20>P5E_PEX0_STN1_RX_DP<20>P5E_PEX0_STN1_TX_C_DP<19>P5E_PEX0_STN1_RX_DN<19>P5E_PEX0_STN1_TX_C_DN<19>P5E_PEX0_STN1_RX_DP<19>P5E_PEX0_STN1_TX_C_DN<18>P5E_PEX0_STN1_RX_DN<18>P5E_PEX0_STN1_TX_C_DP<18>P5E_PEX0_STN1_RX_DP<18>P5E_PEX0_STN1_TX_C_DP<17>P5E_PEX0_STN1_RX_DN<17>P5E_PEX0_STN1_TX_C_DN<17>P5E_PEX0_STN1_RX_DP<17>P5E_PEX0_STN1_TX_C_DN<16>P5E_PEX0_STN1_RX_DN<16>P5E_PEX0_STN1_TX_C_DP<16>P5E_PEX0_STN1_RX_DP<16>NIC0_CLKSMB_NIC0_R_SCLSMB_NIC0_R_SDASMB_NIC0_R_SCLSMB_NIC0_R_SDARST_SMB_NIC0_MUX_ISO_R_NCLK_100M_DB2000QL_NIC0_R_DNCLK_100M_DB2000QL_NIC0_R_DP



5
5
4
4
3
3
2
2
1
1
D D
C C
B B
A A
NIC_0_J20(2/3)
RST_SMB_NIC_MUX_R_N[87,172,175,178,181,184,187,190]NIC0_AUX_PWR_EN_R[168]RST_SMB_NIC0_MUX_ISO_R_N [168]
NIC0_BIF0_N [168]NIC0_BIF1_N [168]NIC0_BIF2_N [168]NIC0_SLOT_ID0 [168]NIC0_SLOT_ID1 [168]
P3V3_AUXP3V3_AUXP3V3_AUXP3V3_AUXP3V3_NIC0P3V3_NIC0
P3V3_NIC0SizeDoc NumberRevDate: SheetofReviewerDesignerDepartmentProject
Page TitleCCBU D169 257Tuesday, August 29, 2023<project_name><Designer> GRANDTETON_SWB_20230829169 NIC_0_J20(2/3)<Reviewer>SizeDoc NumberRevDate: SheetofReviewerDesignerDepartmentProject
Page TitleCCBU D169 257Tuesday, August 29, 2023<project_name><Designer> GRANDTETON_SWB_20230829169 NIC_0_J20(2/3)<Reviewer>SizeDoc NumberRevDate: SheetofReviewerDesignerDepartmentProject
Page TitleCCBU D169 257Tuesday, August 29, 2023<project_name><Designer> GRANDTETON_SWB_20230829169 NIC_0_J20(2/3)<Reviewer>
R33100K1% R0402-0201<Part Number>NIC8560.1UFX6SC0402-020110%25V<Part Number>
R281001% R0402-0201<Part Number>
R36 33 R0402-02011%
R29100K1% R0402-0201<Part Number>NIR354.75KR0402-02011%NI3 state outputU874HC1G126GW<Part Number>24513R38100K1%R0402-0201<Part Number>R31100K1% R0402-0201<Part Number>NIR254.7K1% R0402-0201<Part Number>NIR3205% R0402-0201<Part Number>R3005% R0402-0201<Part Number>R261001% R0402-0201<Part Number>
R3705% R0402-0201<Part Number>
R274.7K1% R0402-0201<Part Number>NIR3405% R0402-0201<Part Number>RST_SMB_NIC0_MUX_ISO_R_NRST_SMB_NIC0_MUX_ISO_NRST_SMB_NIC0_MUX_NNIC0_AUX_PWR_EN_RNIC0_BIF0_NNIC0_BIF1_NNIC0_BIF2_NNIC0_SLOT_ID0NIC0_SLOT_ID1



5
5
4
4
3
3
2
2
1
1
D D
C C
B B
A A
NIC_0_J20(3/3)
PRSNT_NIC0_R_N [86,116,170]HP_NIC0_EN [235,238,242,248]PRSNT_NIC0_R_N[86,116,170]RST_NIC0_PERST0_R_N [168]RST_NIC0_PERST1_R_N [168]RST_HP_NIC0_N[170]HP_NIC0_PWRGD_R [170]HP_NIC0_PWRGD_R[170]RST_HP_NIC0_N [170]RST_NIC0_PERST_R_N[116]
PRSNTB0_NIC0_N[168]PRSNTB1_NIC0_N[168]PRSNTB2_NIC0_N[168]PRSNTB3_NIC0_N[168]RST_NIC0_PERST2_R_N [168]RST_NIC0_PERST3_R_N [168]PWRGD_P12V_NIC0_R[116,235,242]
P3V3_AUXP3V3_AUXP3V3_NIC0P3V3_AUXP3V3_NIC0P3V3_AUXSizeDoc NumberRevDate: SheetofReviewerDesignerDepartmentProject
Page TitleCCBU D170 257Tuesday, August 29, 2023<project_name><Designer> GRANDTETON_SWB_20230829170 NIC_0_J20(3/3)<Reviewer>SizeDoc NumberRevDate: SheetofReviewerDesignerDepartmentProject
Page TitleCCBU D170 257Tuesday, August 29, 2023<project_name><Designer> GRANDTETON_SWB_20230829170 NIC_0_J20(3/3)<Reviewer>SizeDoc NumberRevDate: SheetofReviewerDesignerDepartmentProject
Page TitleCCBU D170 257Tuesday, August 29, 2023<project_name><Designer> GRANDTETON_SWB_20230829170 NIC_0_J20(3/3)<Reviewer>
U9BSS138K<Part Number>GDSR491K1%R0402-0201<Part Number>R4833.21% R0402-0201<Part Number>R4733.21% R0402-0201<Part Number>Q1BDMN53D0LDW-7<Part Number>D23G25S24U10SN74LVC1G17DCKR<Part Number>24531U12DS1818-5<Part Number>RST#1VCC2GND3
R4333.21% R0402-0201<Part Number>C8570.1UFX6SC0402-020110%25V<Part Number>R4205% R0402-0201<Part Number>
C8590.1UFX6SC0402-020110%25V<Part Number>R5133.21% R0402-0201<Part Number>Q1ADMN53D0LDW-7<Part Number>S11G12D16R5010K1%R0402-0201<Part Number>
C39980.1UF25V10%C0402-0201X7RR4105% R0402-0201<Part Number>
U1174LVC1G08GV12453
R4005% R0402-0201<Part Number>R441K1%R0402-0201<Part Number>R4633.21% R0402-0201<Part Number>R3905% R0402-0201<Part Number>C8580.1UFX6SC0402-020110%25V<Part Number>R4533.21% R0402-0201<Part Number>PRSNT_NIC0_R_NHP_NIC0_ENPRSNT_NIC0_R_NRST_NIC0_PERST0_R_NRST_HP_NIC0_BUF_NRST_NIC0_PERST1_R_NRST_HP_NIC0_NHP_NIC0_PWRGDHP_NIC0_PWRGD_RHP_NIC0_PWRGD_RRST_HP_NIC0_NRST_NIC0_PERST_R_N
PRSNTB0_NIC0_NPRSNTB1_NIC0_NPRSNTB2_NIC0_NPRSNTB3_NIC0_NRST_NIC0_PERST2_R_NRST_NIC0_PERST3_R_NPRSNT_NIC0_N
HP_NIC0_HSC_PWRGD_N



5
5
4
4
3
3
2
2
1
1
D D
C C
B B
A A
PRIMARY CONNECTOR
NIC_1_J21(1/3)
DVT_CHANGENIC1_DATA_IN[171]NIC1_DATA_OUT[171]NIC1_CLK[171]PWRGD_NIC1_PWR_GOOD[171]NIC1_MAIN_PWR_EN_R[171]NIC1_LD_N[171]NIC1_SLOT_ID0[172]NCSI_NIC1_RXD1[171]NCSI_NIC1_RXD0[171]NCSI_NIC1_CRS_DV[171]CLK_50M_NIC1_RBT_REF [171]NIC1_RBT_ARB_OUT [171]NIC1_SLOT_ID1 [172]NCSI_NIC1_TX_EN [171]NCSI_NIC1_TXD1 [171]NCSI_NIC1_TXD0 [171]NIC1_MAIN_PWR_EN[116,171]NIC1_MAIN_PWR_EN_R [171]NIC1_AUX_PWR_EN[116,171]NIC1_AUX_PWR_EN_R [171,172]NIC1_BIF0_N[172]NIC1_BIF1_N[172]NIC1_BIF2_N[172]RST_NIC1_PERST0_R_N[173]PRSNTB0_NIC1_N [171,173]PRSNTB0_NIC1_N[171,173]PRSNTB3_NIC1_N[171,173]PRSNTB1_NIC1_N [171,173]PRSNTB2_NIC1_N [171,173]PRSNTB1_NIC1_N [171,173]PRSNTB2_NIC1_N [171,173]PRSNTB3_NIC1_N [171,173]NIC1_AUX_PWR_EN_R[171,172]NIC1_RBT_ARB_IN [171]RST_SMB_NIC1_MUX_ISO_R_N [172]RST_NIC1_PERST1_R_N [173]RST_NIC1_PERST2_R_N [173]RST_NIC1_PERST3_R_N [173]NIC1_RBT_ARB_IN[171]NIC1_RBT_ARB_OUT [171]
NCSI_NIC1_CRS_DV [171]NCSI_NIC1_RXD0 [171]NCSI_NIC1_RXD1 [171]NCSI_NIC1_TXD0 [171]NCSI_NIC1_TXD1 [171]CLK_50M_NIC1_RBT_REF [171]NCSI_NIC1_TX_EN [171]PWRGD_NIC1_PWR_GOOD [171]NIC1_MAIN_PWR_EN [116,171]NIC1_AUX_PWR_EN [116,171]NIC1_LD_N [171]NIC1_DATA_IN [171]NIC1_DATA_OUT [171]PWRGD_NIC1_PWR_GOOD_R[116]PWRGD_NIC1_PWR_GOOD [171]
NIC1_PWRBRK_R_N [192]P5E_PEX0_STN0_TX_C_DN<0>[10]P5E_PEX0_STN0_RX_DN<0> [10]P5E_PEX0_STN0_TX_C_DP<0>[10]P5E_PEX0_STN0_RX_DP<0> [10]P5E_PEX0_STN0_TX_C_DN<1>[10]P5E_PEX0_STN0_RX_DN<1> [10]P5E_PEX0_STN0_TX_C_DP<1>[10]P5E_PEX0_STN0_RX_DP<1> [10]P5E_PEX0_STN0_TX_C_DN<2>[10]P5E_PEX0_STN0_RX_DN<2> [10]P5E_PEX0_STN0_TX_C_DP<2>[10]P5E_PEX0_STN0_RX_DP<2> [10]P5E_PEX0_STN0_TX_C_DN<3>[10]P5E_PEX0_STN0_RX_DN<3> [10]P5E_PEX0_STN0_TX_C_DP<3>[10]P5E_PEX0_STN0_RX_DP<3> [10]P5E_PEX0_STN0_TX_C_DN<4>[10]P5E_PEX0_STN0_RX_DN<4> [10]P5E_PEX0_STN0_TX_C_DP<4>[10]P5E_PEX0_STN0_RX_DP<4> [10]P5E_PEX0_STN0_TX_C_DN<5>[10]P5E_PEX0_STN0_RX_DN<5> [10]P5E_PEX0_STN0_TX_C_DP<5>[10]P5E_PEX0_STN0_RX_DP<5> [10]P5E_PEX0_STN0_TX_C_DN<6>[10]P5E_PEX0_STN0_RX_DN<6> [10]P5E_PEX0_STN0_TX_C_DP<6>[10]P5E_PEX0_STN0_RX_DP<6> [10]P5E_PEX0_STN0_TX_C_DN<7>[10]P5E_PEX0_STN0_RX_DN<7> [10]P5E_PEX0_STN0_TX_C_DP<7>[10]P5E_PEX0_STN0_RX_DP<7> [10]P5E_PEX0_STN0_TX_C_DN<8>[10]P5E_PEX0_STN0_RX_DN<8> [10]P5E_PEX0_STN0_TX_C_DP<8>[10]P5E_PEX0_STN0_RX_DP<8> [10]P5E_PEX0_STN0_TX_C_DN<9>[10]P5E_PEX0_STN0_RX_DN<9> [10]P5E_PEX0_STN0_TX_C_DP<9>[10]P5E_PEX0_STN0_RX_DP<9> [10]P5E_PEX0_STN0_TX_C_DN<10>[10]P5E_PEX0_STN0_RX_DN<10> [10]P5E_PEX0_STN0_TX_C_DP<10>[10]P5E_PEX0_STN0_RX_DP<10> [10]P5E_PEX0_STN0_TX_C_DN<11>[10]P5E_PEX0_STN0_RX_DN<11> [10]P5E_PEX0_STN0_TX_C_DP<11>[10]P5E_PEX0_STN0_RX_DP<11> [10]P5E_PEX0_STN0_TX_C_DP<12>[10]P5E_PEX0_STN0_RX_DN<12> [10]P5E_PEX0_STN0_TX_C_DN<12>[10]P5E_PEX0_STN0_RX_DP<12> [10]P5E_PEX0_STN0_TX_C_DN<13>[10]P5E_PEX0_STN0_RX_DN<13> [10]P5E_PEX0_STN0_TX_C_DP<13>[10]P5E_PEX0_STN0_RX_DP<13> [10]P5E_PEX0_STN0_TX_C_DP<14>[10]P5E_PEX0_STN0_RX_DN<14> [10]P5E_PEX0_STN0_TX_C_DN<14>[10]P5E_PEX0_STN0_RX_DP<14> [10]P5E_PEX0_STN0_TX_C_DN<15>[10]P5E_PEX0_STN0_RX_DN<15> [10]P5E_PEX0_STN0_TX_C_DP<15>[10]P5E_PEX0_STN0_RX_DP<15> [10]NIC1_CLK [171]SMB_NIC1_R_SCL [87,171]SMB_NIC1_R_SDA [87,171]SMB_NIC1_R_SCL [87,171]SMB_NIC1_R_SDA [87,171]CLK_100M_DB2000QL_NIC1_R_DN[79]CLK_100M_DB2000QL_NIC1_R_DP[79]
P12V_NIC1P3V3_NIC1P12V_NIC1P3V3_NIC1P3V3_AUXP3V3_NIC1
SizeDoc NumberRevDate: SheetofReviewerDesignerDepartmentProject
Page TitleCCBU D171 257Tuesday, August 29, 2023<project_name><Designer> GRANDTETON_SWB_20230829171 NIC_1_J21(1/3)<Reviewer>SizeDoc NumberRevDate: SheetofReviewerDesignerDepartmentProject
Page TitleCCBU D171 257Tuesday, August 29, 2023<project_name><Designer> GRANDTETON_SWB_20230829171 NIC_1_J21(1/3)<Reviewer>SizeDoc NumberRevDate: SheetofReviewerDesignerDepartmentProject
Page TitleCCBU D171 257Tuesday, August 29, 2023<project_name><Designer> GRANDTETON_SWB_20230829171 NIC_1_J21(1/3)<Reviewer>
C8630.1UFX6SC020110%16V<Part Number>
R71100K1% R0402-0201<Part Number>
C86122UFX6SC0805_H5720%16V<Part Number>R561K1% R0402-0201<Part Number>R67100K1% R0402-0201<Part Number>R7510K1% R0402-0201<Part Number>
R5505% R0402-0201<Part Number>C8650.1UFX6SC020110%16V<Part Number>
R621K1% R0402-0201<Part Number>KEYKEYKEYSCONN168_G64V35313HR
J21
<Part Number>
NIC_PWR_GOODOB1MAIN_PWR_ENOB2LD#OB3DATA_INOB4DATA_OUTOB5CLKOB6SLOT_ID0OB7RBT_RXD1OB8RBT_RXD0OB9GND_OB10OB10REFCLKn2OB11REFCLKp2OB12GND_OB13OB13RBT_CRS_DVOB14+12V_EDGE_B1B1+12V_EDGE_B2B2+12V_EDGE_B3B3+12V_EDGE_B4B4+12V_EDGE_B5B5+12V_EDGE_B6B6BIF0#B7BIF1#B8BIF2#B9PERST0#B10+3.3V_EDGEB11AUX_PWR_ENB12GND_B13B13REFCLKn0B14REFCLKp0B15GND_B16B16PETn0B17PETp0B18GND_B19B19PETn1B20PETp1B21GND_B22B22PETn2B23PETp2B24GND_B25B25PETn3B26PETp3B27GND_B28B28GND_B29B29PETn4B30PETp4B31GND_B32B32PETn5B33PETp5B34GND_B35B35PETn6B36PETp6B37GND_B38B38PETn7B39PETp7B40GND_B41B41PRSNTB0#B42GND_B43B43PETn8B44PETp8B45GND_B46B46PETn9B47PETp9B48GND_B49B49PETn10B50PETp10B51GND_B52B52PETn11B53PETp11B54GND_B55B55PETn12B56
PERST2#OA1PERST3#OA2WAKE#OA3RBT_ARB_INOA4RBT_ARB_OUTOA5SLOT_ID1OA6RBT_TX_ENOA7RBT_TXD1OA8RBT_TXD0OA9GND_OA10OA10REFCLKn3OA11REFCLKp3OA12GND_OA13OA13RBT_CLK_INOA14GND_A1A1GND_A2A2GND_A3A3GND_A4A4GND_A5A5GND_A6A6SMCLKA7SMDATA8SMRST#A9PRSNTA#A10PERST1#A11PRSNTB2#A12GND_A13A13REFCLKn1A14REFCLKp1A15GND_A16A16PERn0A17PERp0A18GND_A19A19PERn1A20PERp1A21GND_A22A22PERn2A23PERp2A24GND_A25A25PERn3A26PERp3A27GND_A28A28GND_A29A29PERn4A30PERp4A31GND_A32A32PERn5A33PERp5A34GND_A35A35PERn6A36PERp6A37GND_A38A38PERn7A39PERp7A40GND_A41A41PRSNTB1#A42GND_A43A43PERn8A44PERp8A45GND_A46A46PERn9A47PERp9A48GND_A49A49PERn10A50PERp10A51GND_A52A52PERn11A53PERp11A54GND_A55A55PERn12A56PERp12A57GND_A58A58PERn13A59PERp13A60GND_A61A61PERn14A62PERp14A63GND_A64A64PERn15A65PERp15A66GND_A67A67USB_DATnA68USB_DATpA69PWRBRK0#A70PETp12B57GND_B58B58PETn13B59PETp13B60GND_B61B61PETn14B62PETp14B63GND_B64B64PETn15B65PETp15B66GND_B67B67RFU1_NCB68RFU2_NCB69PRSNTB3#B70G1G1G2G2G3G3G4G4G5G5G6G6G7G7G8G8G9G9
C8680.1UFX6SC0402-020110%25V<Part Number>R5405% R0402-0201<Part Number>
R69100K1% R0402-0201<Part Number>R72100K1% R0402-0201<Part Number>
C8620.1UFX6SC020110%16V<Part Number>C8690.1UFX6SC0402-020110%25V<Part Number>C8660.1UFX6SC020110%16V<Part Number>C8670.1UFX6SC0402-020110%25V<Part Number>C8700.1UFX6SC0402-020110%25V<Part Number>R581K1% R0402-0201<Part Number>R5205% R0402-0201<Part Number>
R7410K1% R0402-0201<Part Number>R602.2K5%R0402-0201R70100K1% R0402-0201<Part Number>R66100K1% R0402-0201<Part Number>R612.2K5%R0402-0201R68100K1% R0402-0201<Part Number>R6310K1% R0402-0201<Part Number>R591K1% R0402-0201<Part Number>R641K1% R0402-0201<Part Number>R571K1% R0402-0201<Part Number>C86022UFX6SC0805_H5720%16V<Part Number>C8640.1UFX6SC020110%16V<Part Number>
R73100K1% R0402-0201<Part Number>R65100K1% R0402-0201<Part Number>R5305% R0402-0201<Part Number>PWRGD_NIC1_PWR_GOODNIC1_MAIN_PWR_EN_RNIC1_LD_NNIC1_DATA_INNIC1_DATA_OUTNIC1_CLKNIC1_SLOT_ID0NCSI_NIC1_RXD1NCSI_NIC1_RXD0NCSI_NIC1_CRS_DVCLK_50M_NIC1_RBT_REFNIC1_RBT_ARB_OUTNIC1_SLOT_ID1NCSI_NIC1_TX_ENNCSI_NIC1_TXD1NCSI_NIC1_TXD0NIC1_RBT_ARB_INNIC1_MAIN_PWR_ENNIC1_MAIN_PWR_EN_RNIC1_AUX_PWR_ENNIC1_AUX_PWR_EN_RNIC1_BIF0_NNIC1_BIF1_NNIC1_BIF2_NPRSNTB3_NIC1_NPRSNTB0_NIC1_NPRSNTB1_NIC1_NPRSNTB2_NIC1_NRST_NIC1_PERST0_R_NPRSNTB0_NIC1_NPRSNTB1_NIC1_NPRSNTB2_NIC1_NPRSNTB3_NIC1_NNIC1_AUX_PWR_EN_RRST_NIC1_PERST1_R_NRST_NIC1_PERST2_R_NRST_NIC1_PERST3_R_NNIC1_RBT_ARB_INNIC1_RBT_ARB_OUT
NCSI_NIC1_CRS_DVNCSI_NIC1_RXD0NCSI_NIC1_RXD1NCSI_NIC1_TXD0NCSI_NIC1_TXD1CLK_50M_NIC1_RBT_REFNCSI_NIC1_TX_ENPWRGD_NIC1_PWR_GOODNIC1_MAIN_PWR_ENNIC1_AUX_PWR_ENNIC1_LD_NNIC1_DATA_INNIC1_DATA_OUTNIC1_PWRBRK_R_N
PWRGD_NIC1_PWR_GOOD_RPWRGD_NIC1_PWR_GOODP5E_PEX0_STN0_TX_C_DN<0>P5E_PEX0_STN0_RX_DN<0>P5E_PEX0_STN0_TX_C_DP<0>P5E_PEX0_STN0_RX_DP<0>P5E_PEX0_STN0_TX_C_DN<1>P5E_PEX0_STN0_RX_DN<1>P5E_PEX0_STN0_TX_C_DP<1>P5E_PEX0_STN0_RX_DP<1>P5E_PEX0_STN0_TX_C_DN<2>P5E_PEX0_STN0_RX_DN<2>P5E_PEX0_STN0_TX_C_DP<2>P5E_PEX0_STN0_RX_DP<2>P5E_PEX0_STN0_TX_C_DN<3>P5E_PEX0_STN0_RX_DN<3>P5E_PEX0_STN0_TX_C_DP<3>P5E_PEX0_STN0_RX_DP<3>P5E_PEX0_STN0_TX_C_DN<4>P5E_PEX0_STN0_RX_DN<4>P5E_PEX0_STN0_TX_C_DP<4>P5E_PEX0_STN0_RX_DP<4>P5E_PEX0_STN0_TX_C_DN<5>P5E_PEX0_STN0_RX_DN<5>P5E_PEX0_STN0_TX_C_DP<5>P5E_PEX0_STN0_RX_DP<5>P5E_PEX0_STN0_TX_C_DN<6>P5E_PEX0_STN0_RX_DN<6>P5E_PEX0_STN0_TX_C_DP<6>P5E_PEX0_STN0_RX_DP<6>P5E_PEX0_STN0_TX_C_DN<7>P5E_PEX0_STN0_RX_DN<7>P5E_PEX0_STN0_TX_C_DP<7>P5E_PEX0_STN0_RX_DP<7>P5E_PEX0_STN0_TX_C_DN<8>P5E_PEX0_STN0_RX_DN<8>P5E_PEX0_STN0_TX_C_DP<8>P5E_PEX0_STN0_RX_DP<8>P5E_PEX0_STN0_TX_C_DN<9>P5E_PEX0_STN0_RX_DN<9>P5E_PEX0_STN0_TX_C_DP<9>P5E_PEX0_STN0_RX_DP<9>P5E_PEX0_STN0_TX_C_DN<10>P5E_PEX0_STN0_RX_DN<10>P5E_PEX0_STN0_TX_C_DP<10>P5E_PEX0_STN0_RX_DP<10>P5E_PEX0_STN0_TX_C_DN<11>P5E_PEX0_STN0_RX_DN<11>P5E_PEX0_STN0_TX_C_DP<11>P5E_PEX0_STN0_RX_DP<11>P5E_PEX0_STN0_TX_C_DP<12>P5E_PEX0_STN0_RX_DN<12>P5E_PEX0_STN0_TX_C_DN<12>P5E_PEX0_STN0_RX_DP<12>P5E_PEX0_STN0_TX_C_DN<13>P5E_PEX0_STN0_RX_DN<13>P5E_PEX0_STN0_TX_C_DP<13>P5E_PEX0_STN0_RX_DP<13>P5E_PEX0_STN0_TX_C_DP<14>P5E_PEX0_STN0_RX_DN<14>P5E_PEX0_STN0_TX_C_DN<14>P5E_PEX0_STN0_RX_DP<14>P5E_PEX0_STN0_TX_C_DN<15>P5E_PEX0_STN0_RX_DN<15>P5E_PEX0_STN0_TX_C_DP<15>P5E_PEX0_STN0_RX_DP<15>NIC1_CLKSMB_NIC1_R_SCLSMB_NIC1_R_SDARST_SMB_NIC1_MUX_ISO_R_NCLK_100M_DB2000QL_NIC1_R_DNSMB_NIC1_R_SCLCLK_100M_DB2000QL_NIC1_R_DPSMB_NIC1_R_SDA



5
5
4
4
3
3
2
2
1
1
D D
C C
B B
A A
NIC_1_J21(2/3)
RST_SMB_NIC_MUX_R_N[87,169,175,178,181,184,187,190]NIC1_AUX_PWR_EN_R[171]RST_SMB_NIC1_MUX_ISO_R_N [171]
NIC1_BIF0_N [171]NIC1_BIF1_N [171]NIC1_BIF2_N [171]NIC1_SLOT_ID0 [171]NIC1_SLOT_ID1 [171]
P3V3_AUXP3V3_AUXP3V3_AUXP3V3_AUXP3V3_NIC1P3V3_NIC1
P3V3_NIC1SizeDoc NumberRevDate: SheetofReviewerDesignerDepartmentProject
Page TitleCCBU D172 257Tuesday, August 29, 2023<project_name><Designer> GRANDTETON_SWB_20230829172 NIC_1_J21(2/3)<Reviewer>SizeDoc NumberRevDate: SheetofReviewerDesignerDepartmentProject
Page TitleCCBU D172 257Tuesday, August 29, 2023<project_name><Designer> GRANDTETON_SWB_20230829172 NIC_1_J21(2/3)<Reviewer>SizeDoc NumberRevDate: SheetofReviewerDesignerDepartmentProject
Page TitleCCBU D172 257Tuesday, August 29, 2023<project_name><Designer> GRANDTETON_SWB_20230829172 NIC_1_J21(2/3)<Reviewer>R8805% R0402-0201<Part Number>
R764.7K1% R0402-0201<Part Number>NI
R87 33 R0402-02011%R864.75KR0402-02011%NI3 state outputU1374HC1G126GW<Part Number>24513R8505% R0402-0201<Part Number>R89100K1%R0402-0201<Part Number>
R791001% R0402-0201<Part Number>R8105% R0402-0201<Part Number>R84100K1% R0402-0201<Part Number>NIC8710.1UFX6SC0402-020110%25V<Part Number>R8305% R0402-0201<Part Number>R771001% R0402-0201<Part Number>R82100K1% R0402-0201<Part Number>NIR80100K1% R0402-0201<Part Number>NIR784.7K1% R0402-0201<Part Number>NI
RST_SMB_NIC1_MUX_ISO_R_NRST_SMB_NIC1_MUX_ISO_NRST_SMB_NIC1_MUX_NNIC1_AUX_PWR_EN_RNIC1_BIF0_NNIC1_BIF1_NNIC1_BIF2_NNIC1_SLOT_ID0NIC1_SLOT_ID1



5
5
4
4
3
3
2
2
1
1
D D
C C
B B
A A
NIC_1_J21(3/3)
PRSNT_NIC1_R_N [86,116,173]HP_NIC1_EN [235,238,242,248]PRSNT_NIC1_R_N[86,116,173]RST_NIC1_PERST0_R_N [171]RST_NIC1_PERST1_R_N [171]RST_HP_NIC1_N[173]HP_NIC1_PWRGD_R [173]HP_NIC1_PWRGD_R[173]RST_HP_NIC1_N [173]RST_NIC1_PERST_R_N[116]
PRSNTB0_NIC1_N[171]PRSNTB1_NIC1_N[171]PRSNTB2_NIC1_N[171]PRSNTB3_NIC1_N[171]RST_NIC1_PERST2_R_N [171]RST_NIC1_PERST3_R_N [171]PWRGD_P12V_NIC1_R[116,235,242]
P3V3_AUXP3V3_AUXP3V3_NIC1P3V3_AUXP3V3_NIC1P3V3_AUXSizeDoc NumberRevDate: SheetofReviewerDesignerDepartmentProject
Page TitleCCBU D173 257Tuesday, August 29, 2023<project_name><Designer> GRANDTETON_SWB_20230829173 NIC_1_J21(3/3)<Reviewer>SizeDoc NumberRevDate: SheetofReviewerDesignerDepartmentProject
Page TitleCCBU D173 257Tuesday, August 29, 2023<project_name><Designer> GRANDTETON_SWB_20230829173 NIC_1_J21(3/3)<Reviewer>SizeDoc NumberRevDate: SheetofReviewerDesignerDepartmentProject
Page TitleCCBU D173 257Tuesday, August 29, 2023<project_name><Designer> GRANDTETON_SWB_20230829173 NIC_1_J21(3/3)<Reviewer>
U14BSS138K<Part Number>GDSR9933.21% R0402-0201<Part Number>R9433.21% R0402-0201<Part Number>R9005% R0402-0201<Part Number>
Q2ADMN53D0LDW-7<Part Number>S11G12D16
R9105% R0402-0201<Part Number>
U17DS1818-5<Part Number>RST#1VCC2GND3C8740.1UFX6SC0402-020110%25V<Part Number>
R9205% R0402-0201<Part Number>R951K1%R0402-0201<Part Number>C8720.1UFX6SC0402-020110%25V<Part Number>R9833.21% R0402-0201<Part Number>R9305% R0402-0201<Part Number>U1674LVC1G08GV12453U15SN74LVC1G17DCKR<Part Number>24531R1001K1%R0402-0201<Part Number>R9733.21% R0402-0201<Part Number>R9633.21% R0402-0201<Part Number>R10233.21% R0402-0201<Part Number>C8730.1UFX6SC0402-020110%25V<Part Number>Q2BDMN53D0LDW-7<Part Number>D23G25S24
C39990.1UF25V10%C0402-0201X7R
R10110K1%R0402-0201<Part Number>
PRSNT_NIC1_R_NHP_NIC1_ENPRSNT_NIC1_R_NRST_NIC1_PERST0_R_NRST_HP_NIC1_BUF_NRST_NIC1_PERST1_R_NRST_HP_NIC1_NHP_NIC1_PWRGDHP_NIC1_PWRGD_RHP_NIC1_PWRGD_RRST_HP_NIC1_NRST_NIC1_PERST_R_N
PRSNTB0_NIC1_NPRSNTB1_NIC1_NPRSNTB2_NIC1_NPRSNTB3_NIC1_NRST_NIC1_PERST2_R_NRST_NIC1_PERST3_R_NPRSNT_NIC1_N
HP_NIC1_HSC_PWRGD_N



5
5
4
4
3
3
2
2
1
1
D D
C C
B B
A A
PRIMARY CONNECTOR
NIC_2_J22(1/3)
LANE REVERSAL
DVT_CHANGENIC2_DATA_IN[174]NIC2_DATA_OUT[174]NIC2_CLK[174]PWRGD_NIC2_PWR_GOOD[174]NIC2_MAIN_PWR_EN_R[174]NIC2_LD_N[174]NIC2_SLOT_ID0[175]NCSI_NIC2_RXD1[174]NCSI_NIC2_RXD0[174]NCSI_NIC2_CRS_DV[174]CLK_50M_NIC2_RBT_REF [174]NIC2_RBT_ARB_OUT [174]NIC2_SLOT_ID1 [175]NCSI_NIC2_TX_EN [174]NCSI_NIC2_TXD1 [174]NCSI_NIC2_TXD0 [174]NIC2_MAIN_PWR_EN[116,174]NIC2_MAIN_PWR_EN_R [174]NIC2_AUX_PWR_EN[116,174]NIC2_AUX_PWR_EN_R [174,175]NIC2_BIF0_N[175]NIC2_BIF1_N[175]NIC2_BIF2_N[175]RST_NIC2_PERST0_R_N[176]PRSNTB0_NIC2_N [174,176]PRSNTB0_NIC2_N[174,176]PRSNTB3_NIC2_N[174,176]PRSNTB1_NIC2_N [174,176]PRSNTB2_NIC2_N [174,176]PRSNTB1_NIC2_N [174,176]PRSNTB2_NIC2_N [174,176]PRSNTB3_NIC2_N [174,176]NIC2_AUX_PWR_EN_R[174,175]NIC2_RBT_ARB_IN [174]RST_SMB_NIC2_MUX_ISO_R_N [175]RST_NIC2_PERST1_R_N [176]RST_NIC2_PERST2_R_N [176]RST_NIC2_PERST3_R_N [176]NIC2_RBT_ARB_IN[174]NIC2_RBT_ARB_OUT [174]
NCSI_NIC2_CRS_DV [174]NCSI_NIC2_RXD0 [174]NCSI_NIC2_RXD1 [174]NCSI_NIC2_TXD0 [174]NCSI_NIC2_TXD1 [174]CLK_50M_NIC2_RBT_REF [174]NCSI_NIC2_TX_EN [174]PWRGD_NIC2_PWR_GOOD [174]NIC2_MAIN_PWR_EN [116,174]NIC2_AUX_PWR_EN [116,174]NIC2_LD_N [174]NIC2_DATA_IN [174]NIC2_DATA_OUT [174]PWRGD_NIC2_PWR_GOOD_R[116]PWRGD_NIC2_PWR_GOOD [174]
NIC2_PWRBRK_R_N [192]NIC2_CLK [174]P5E_PEX1_STN1_TX_C_DP<31>[23]P5E_PEX1_STN1_RX_DN<31> [23]P5E_PEX1_STN1_TX_C_DN<31>[23]P5E_PEX1_STN1_RX_DP<31> [23]P5E_PEX1_STN1_TX_C_DN<30>[23]P5E_PEX1_STN1_RX_DN<30> [23]P5E_PEX1_STN1_TX_C_DP<30>[23]P5E_PEX1_STN1_RX_DP<30> [23]P5E_PEX1_STN1_TX_C_DP<29>[23]P5E_PEX1_STN1_RX_DN<29> [23]P5E_PEX1_STN1_TX_C_DN<29>[23]P5E_PEX1_STN1_RX_DP<29> [23]P5E_PEX1_STN1_TX_C_DN<28>[23]P5E_PEX1_STN1_RX_DN<28> [23]P5E_PEX1_STN1_TX_C_DP<28>[23]P5E_PEX1_STN1_RX_DP<28> [23]P5E_PEX1_STN1_TX_C_DP<27>[23]P5E_PEX1_STN1_RX_DN<27> [23]P5E_PEX1_STN1_TX_C_DN<27>[23]P5E_PEX1_STN1_RX_DP<27> [23]P5E_PEX1_STN1_TX_C_DN<26>[23]P5E_PEX1_STN1_RX_DN<26> [23]P5E_PEX1_STN1_TX_C_DP<26>[23]P5E_PEX1_STN1_RX_DP<26> [23]P5E_PEX1_STN1_TX_C_DP<25>[23]P5E_PEX1_STN1_RX_DN<25> [23]P5E_PEX1_STN1_TX_C_DN<25>[23]P5E_PEX1_STN1_RX_DP<25> [23]P5E_PEX1_STN1_TX_C_DN<24>[23]P5E_PEX1_STN1_RX_DN<24> [23]P5E_PEX1_STN1_TX_C_DP<24>[23]P5E_PEX1_STN1_RX_DP<24> [23]P5E_PEX1_STN1_TX_C_DP<23>[23]P5E_PEX1_STN1_RX_DN<23> [23]P5E_PEX1_STN1_TX_C_DN<23>[23]P5E_PEX1_STN1_RX_DP<23> [23]P5E_PEX1_STN1_TX_C_DN<22>[23]P5E_PEX1_STN1_RX_DN<22> [23]P5E_PEX1_STN1_TX_C_DP<22>[23]P5E_PEX1_STN1_RX_DP<22> [23]P5E_PEX1_STN1_TX_C_DP<21>[23]P5E_PEX1_STN1_RX_DN<21> [23]P5E_PEX1_STN1_TX_C_DN<21>[23]P5E_PEX1_STN1_RX_DP<21> [23]P5E_PEX1_STN1_TX_C_DN<20>[23]P5E_PEX1_STN1_RX_DN<20> [23]P5E_PEX1_STN1_TX_C_DP<20>[23]P5E_PEX1_STN1_RX_DP<20> [23]P5E_PEX1_STN1_TX_C_DP<19>[23]P5E_PEX1_STN1_RX_DN<19> [23]P5E_PEX1_STN1_TX_C_DN<19>[23]P5E_PEX1_STN1_RX_DP<19> [23]P5E_PEX1_STN1_TX_C_DN<18>[23]P5E_PEX1_STN1_RX_DN<18> [23]P5E_PEX1_STN1_TX_C_DP<18>[23]P5E_PEX1_STN1_RX_DP<18> [23]P5E_PEX1_STN1_TX_C_DP<17>[23]P5E_PEX1_STN1_RX_DN<17> [23]P5E_PEX1_STN1_TX_C_DN<17>[23]P5E_PEX1_STN1_RX_DP<17> [23]P5E_PEX1_STN1_TX_C_DN<16>[23]P5E_PEX1_STN1_RX_DN<16> [23]P5E_PEX1_STN1_TX_C_DP<16>[23]P5E_PEX1_STN1_RX_DP<16> [23]SMB_NIC2_R_SCL [87,174]SMB_NIC2_R_SDA [87,174]SMB_NIC2_R_SCL [87,174]SMB_NIC2_R_SDA [87,174]CLK_100M_DB2000QL_NIC2_R_DN[79]CLK_100M_DB2000QL_NIC2_R_DP[79]
P12V_NIC2P3V3_NIC2P12V_NIC2P3V3_NIC2P3V3_AUXP3V3_NIC2
SizeDoc NumberRevDate: SheetofReviewerDesignerDepartmentProject
Page TitleCCBU D174 257Tuesday, August 29, 2023<project_name><Designer> GRANDTETON_SWB_20230829174 NIC_2_J22(1/3)<Reviewer>SizeDoc NumberRevDate: SheetofReviewerDesignerDepartmentProject
Page TitleCCBU D174 257Tuesday, August 29, 2023<project_name><Designer> GRANDTETON_SWB_20230829174 NIC_2_J22(1/3)<Reviewer>SizeDoc NumberRevDate: SheetofReviewerDesignerDepartmentProject
Page TitleCCBU D174 257Tuesday, August 29, 2023<project_name><Designer> GRANDTETON_SWB_20230829174 NIC_2_J22(1/3)<Reviewer>
C8800.1UFX6SC020110%16V<Part Number>C8830.1UFX6SC0402-020110%25V<Part Number>
R12610K1% R0402-0201<Part Number>KEYKEYKEYSCONN168_G64V35313HR
J22
<Part Number>
NIC_PWR_GOODOB1MAIN_PWR_ENOB2LD#OB3DATA_INOB4DATA_OUTOB5CLKOB6SLOT_ID0OB7RBT_RXD1OB8RBT_RXD0OB9GND_OB10OB10REFCLKn2OB11REFCLKp2OB12GND_OB13OB13RBT_CRS_DVOB14+12V_EDGE_B1B1+12V_EDGE_B2B2+12V_EDGE_B3B3+12V_EDGE_B4B4+12V_EDGE_B5B5+12V_EDGE_B6B6BIF0#B7BIF1#B8BIF2#B9PERST0#B10+3.3V_EDGEB11AUX_PWR_ENB12GND_B13B13REFCLKn0B14REFCLKp0B15GND_B16B16PETn0B17PETp0B18GND_B19B19PETn1B20PETp1B21GND_B22B22PETn2B23PETp2B24GND_B25B25PETn3B26PETp3B27GND_B28B28GND_B29B29PETn4B30PETp4B31GND_B32B32PETn5B33PETp5B34GND_B35B35PETn6B36PETp6B37GND_B38B38PETn7B39PETp7B40GND_B41B41PRSNTB0#B42GND_B43B43PETn8B44PETp8B45GND_B46B46PETn9B47PETp9B48GND_B49B49PETn10B50PETp10B51GND_B52B52PETn11B53PETp11B54GND_B55B55PETn12B56
PERST2#OA1PERST3#OA2WAKE#OA3RBT_ARB_INOA4RBT_ARB_OUTOA5SLOT_ID1OA6RBT_TX_ENOA7RBT_TXD1OA8RBT_TXD0OA9GND_OA10OA10REFCLKn3OA11REFCLKp3OA12GND_OA13OA13RBT_CLK_INOA14GND_A1A1GND_A2A2GND_A3A3GND_A4A4GND_A5A5GND_A6A6SMCLKA7SMDATA8SMRST#A9PRSNTA#A10PERST1#A11PRSNTB2#A12GND_A13A13REFCLKn1A14REFCLKp1A15GND_A16A16PERn0A17PERp0A18GND_A19A19PERn1A20PERp1A21GND_A22A22PERn2A23PERp2A24GND_A25A25PERn3A26PERp3A27GND_A28A28GND_A29A29PERn4A30PERp4A31GND_A32A32PERn5A33PERp5A34GND_A35A35PERn6A36PERp6A37GND_A38A38PERn7A39PERp7A40GND_A41A41PRSNTB1#A42GND_A43A43PERn8A44PERp8A45GND_A46A46PERn9A47PERp9A48GND_A49A49PERn10A50PERp10A51GND_A52A52PERn11A53PERp11A54GND_A55A55PERn12A56PERp12A57GND_A58A58PERn13A59PERp13A60GND_A61A61PERn14A62PERp14A63GND_A64A64PERn15A65PERp15A66GND_A67A67USB_DATnA68USB_DATpA69PWRBRK0#A70PETp12B57GND_B58B58PETn13B59PETp13B60GND_B61B61PETn14B62PETp14B63GND_B64B64PETn15B65PETp15B66GND_B67B67RFU1_NCB68RFU2_NCB69PRSNTB3#B70G1G1G2G2G3G3G4G4G5G5G6G6G7G7G8G8G9G9
R1091K1% R0402-0201<Part Number>R1112.2K5%R0402-0201
R10305% R0402-0201<Part Number>C8850.1UFX6SC0402-020110%25V<Part Number>C8770.1UFX6SC020110%16V<Part Number>
R11410K1% R0402-0201<Part Number>R1122.2K5%R0402-0201
C87622UFX6SC0805_H5720%16V<Part Number>C8840.1UFX6SC0402-020110%25V<Part Number>
R121100K1% R0402-0201<Part Number>R123100K1% R0402-0201<Part Number>R117100K1% R0402-0201<Part Number>
C8790.1UFX6SC020110%16V<Part Number>
R12510K1% R0402-0201<Part Number>R124100K1% R0402-0201<Part Number>R1101K1% R0402-0201<Part Number>R1081K1% R0402-0201<Part Number>C8820.1UFX6SC0402-020110%25V<Part Number>
R119100K1% R0402-0201<Part Number>R122100K1% R0402-0201<Part Number>R116100K1% R0402-0201<Part Number>
C87522UFX6SC0805_H5720%16V<Part Number>R1071K1% R0402-0201<Part Number>R1151K1% R0402-0201<Part Number>R10605% R0402-0201<Part Number>R118100K1% R0402-0201<Part Number>
R10505% R0402-0201<Part Number>C8780.1UFX6SC020110%16V<Part Number>
R1131K1% R0402-0201<Part Number>R10405% R0402-0201<Part Number>
R120100K1% R0402-0201<Part Number>
C8810.1UFX6SC020110%16V<Part Number>PWRGD_NIC2_PWR_GOODNIC2_MAIN_PWR_EN_RNIC2_LD_NNIC2_DATA_INNIC2_DATA_OUTNIC2_CLKNIC2_SLOT_ID0NCSI_NIC2_RXD1NCSI_NIC2_RXD0NCSI_NIC2_CRS_DVCLK_50M_NIC2_RBT_REFNIC2_RBT_ARB_OUTNIC2_SLOT_ID1NCSI_NIC2_TX_ENNCSI_NIC2_TXD1NCSI_NIC2_TXD0NIC2_RBT_ARB_INNIC2_MAIN_PWR_ENNIC2_MAIN_PWR_EN_RNIC2_AUX_PWR_ENNIC2_AUX_PWR_EN_RNIC2_BIF0_NNIC2_BIF1_NNIC2_BIF2_NPRSNTB3_NIC2_NPRSNTB0_NIC2_NPRSNTB1_NIC2_NPRSNTB2_NIC2_NRST_NIC2_PERST0_R_NPRSNTB0_NIC2_NPRSNTB1_NIC2_NPRSNTB2_NIC2_NPRSNTB3_NIC2_NNIC2_AUX_PWR_EN_RRST_NIC2_PERST1_R_NRST_NIC2_PERST2_R_NRST_NIC2_PERST3_R_NNIC2_RBT_ARB_INNIC2_RBT_ARB_OUT
NCSI_NIC2_CRS_DVNCSI_NIC2_RXD0NCSI_NIC2_RXD1NCSI_NIC2_TXD0NCSI_NIC2_TXD1CLK_50M_NIC2_RBT_REFNCSI_NIC2_TX_ENPWRGD_NIC2_PWR_GOODNIC2_MAIN_PWR_ENNIC2_AUX_PWR_ENNIC2_LD_NNIC2_DATA_INNIC2_DATA_OUTNIC2_PWRBRK_R_N
PWRGD_NIC2_PWR_GOOD_RPWRGD_NIC2_PWR_GOODNIC2_CLKP5E_PEX1_STN1_TX_C_DP<31>P5E_PEX1_STN1_RX_DN<31>P5E_PEX1_STN1_TX_C_DN<31>P5E_PEX1_STN1_RX_DP<31>P5E_PEX1_STN1_TX_C_DN<30>P5E_PEX1_STN1_RX_DN<30>P5E_PEX1_STN1_TX_C_DP<30>P5E_PEX1_STN1_RX_DP<30>P5E_PEX1_STN1_TX_C_DP<29>P5E_PEX1_STN1_RX_DN<29>P5E_PEX1_STN1_TX_C_DN<29>P5E_PEX1_STN1_RX_DP<29>P5E_PEX1_STN1_TX_C_DN<28>P5E_PEX1_STN1_RX_DN<28>P5E_PEX1_STN1_TX_C_DP<28>P5E_PEX1_STN1_RX_DP<28>P5E_PEX1_STN1_TX_C_DP<27>P5E_PEX1_STN1_RX_DN<27>P5E_PEX1_STN1_TX_C_DN<27>P5E_PEX1_STN1_RX_DP<27>P5E_PEX1_STN1_TX_C_DN<26>P5E_PEX1_STN1_RX_DN<26>P5E_PEX1_STN1_TX_C_DP<26>P5E_PEX1_STN1_RX_DP<26>P5E_PEX1_STN1_TX_C_DP<25>P5E_PEX1_STN1_RX_DN<25>P5E_PEX1_STN1_TX_C_DN<25>P5E_PEX1_STN1_RX_DP<25>P5E_PEX1_STN1_TX_C_DN<24>P5E_PEX1_STN1_RX_DN<24>P5E_PEX1_STN1_TX_C_DP<24>P5E_PEX1_STN1_RX_DP<24>P5E_PEX1_STN1_TX_C_DP<23>P5E_PEX1_STN1_RX_DN<23>P5E_PEX1_STN1_TX_C_DN<23>P5E_PEX1_STN1_RX_DP<23>P5E_PEX1_STN1_TX_C_DN<22>P5E_PEX1_STN1_RX_DN<22>P5E_PEX1_STN1_TX_C_DP<22>P5E_PEX1_STN1_RX_DP<22>P5E_PEX1_STN1_TX_C_DP<21>P5E_PEX1_STN1_RX_DN<21>P5E_PEX1_STN1_TX_C_DN<21>P5E_PEX1_STN1_RX_DP<21>P5E_PEX1_STN1_TX_C_DN<20>P5E_PEX1_STN1_RX_DN<20>P5E_PEX1_STN1_TX_C_DP<20>P5E_PEX1_STN1_RX_DP<20>P5E_PEX1_STN1_TX_C_DP<19>P5E_PEX1_STN1_RX_DN<19>P5E_PEX1_STN1_TX_C_DN<19>P5E_PEX1_STN1_RX_DP<19>P5E_PEX1_STN1_TX_C_DN<18>P5E_PEX1_STN1_RX_DN<18>P5E_PEX1_STN1_TX_C_DP<18>P5E_PEX1_STN1_RX_DP<18>P5E_PEX1_STN1_TX_C_DP<17>P5E_PEX1_STN1_RX_DN<17>P5E_PEX1_STN1_TX_C_DN<17>P5E_PEX1_STN1_RX_DP<17>P5E_PEX1_STN1_TX_C_DN<16>P5E_PEX1_STN1_RX_DN<16>P5E_PEX1_STN1_TX_C_DP<16>P5E_PEX1_STN1_RX_DP<16>SMB_NIC2_R_SCLSMB_NIC2_R_SDARST_SMB_NIC2_MUX_ISO_R_NCLK_100M_DB2000QL_NIC2_R_DNSMB_NIC2_R_SCLCLK_100M_DB2000QL_NIC2_R_DPSMB_NIC2_R_SDA



5
5
4
4
3
3
2
2
1
1
D D
C C
B B
A A
NIC_2_J22(2/3)
RST_SMB_NIC_MUX_R_N[87,169,172,178,181,184,187,190]NIC2_AUX_PWR_EN_R[174]RST_SMB_NIC2_MUX_ISO_R_N [174]
NIC2_BIF0_N [174]NIC2_BIF1_N [174]NIC2_BIF2_N [174]NIC2_SLOT_ID0 [174]NIC2_SLOT_ID1 [174]
P3V3_AUXP3V3_AUXP3V3_AUXP3V3_AUXP3V3_NIC2P3V3_NIC2
P3V3_NIC2SizeDoc NumberRevDate: SheetofReviewerDesignerDepartmentProject
Page TitleCCBU D175 257Tuesday, August 29, 2023<project_name><Designer> GRANDTETON_SWB_20230829175 NIC_2_J22(2/3)<Reviewer>SizeDoc NumberRevDate: SheetofReviewerDesignerDepartmentProject
Page TitleCCBU D175 257Tuesday, August 29, 2023<project_name><Designer> GRANDTETON_SWB_20230829175 NIC_2_J22(2/3)<Reviewer>SizeDoc NumberRevDate: SheetofReviewerDesignerDepartmentProject
Page TitleCCBU D175 257Tuesday, August 29, 2023<project_name><Designer> GRANDTETON_SWB_20230829175 NIC_2_J22(2/3)<Reviewer>
R135100K1% R0402-0201<Part Number>NIR1294.7K1% R0402-0201<Part Number>NIR1274.7K1% R0402-0201<Part Number>NI
R138 33 R0402-02011%R1374.75KR0402-02011%NIR140100K1%R0402-0201<Part Number>
R1301001% R0402-0201<Part Number>
R13905% R0402-0201<Part Number>
R13205% R0402-0201<Part Number>
3 state outputU1874HC1G126GW<Part Number>24513R13605% R0402-0201<Part Number>R1281001% R0402-0201<Part Number>
C8860.1UFX6SC0402-020110%25V<Part Number>R13405% R0402-0201<Part Number>R133100K1% R0402-0201<Part Number>NIR131100K1% R0402-0201<Part Number>NI
RST_SMB_NIC2_MUX_ISO_R_NRST_SMB_NIC2_MUX_ISO_NRST_SMB_NIC2_MUX_NNIC2_AUX_PWR_EN_RNIC2_BIF0_NNIC2_BIF1_NNIC2_BIF2_NNIC2_SLOT_ID0NIC2_SLOT_ID1



5
5
4
4
3
3
2
2
1
1
D D
C C
B B
A A
NIC_2_J22(3/3)
PRSNT_NIC2_R_N [86,116,176]HP_NIC2_EN [235,238,242,248]PRSNT_NIC2_R_N[86,116,176]RST_NIC2_PERST0_R_N [174]RST_NIC2_PERST1_R_N [174]RST_HP_NIC2_N[176]HP_NIC2_PWRGD_R [176]HP_NIC2_PWRGD_R[176]RST_HP_NIC2_N [176]RST_NIC2_PERST_R_N[116]
PRSNTB0_NIC2_N[174]PRSNTB1_NIC2_N[174]PRSNTB2_NIC2_N[174]PRSNTB3_NIC2_N[174]RST_NIC2_PERST2_R_N [174]RST_NIC2_PERST3_R_N [174]PWRGD_P12V_NIC2_R[116,235,242]
P3V3_AUXP3V3_AUXP3V3_NIC2P3V3_AUXP3V3_NIC2P3V3_AUXSizeDoc NumberRevDate: SheetofReviewerDesignerDepartmentProject
Page TitleCCBU D176 257Tuesday, August 29, 2023<project_name><Designer> GRANDTETON_SWB_20230829176 NIC_2_J22(3/3)<Reviewer>SizeDoc NumberRevDate: SheetofReviewerDesignerDepartmentProject
Page TitleCCBU D176 257Tuesday, August 29, 2023<project_name><Designer> GRANDTETON_SWB_20230829176 NIC_2_J22(3/3)<Reviewer>SizeDoc NumberRevDate: SheetofReviewerDesignerDepartmentProject
Page TitleCCBU D176 257Tuesday, August 29, 2023<project_name><Designer> GRANDTETON_SWB_20230829176 NIC_2_J22(3/3)<Reviewer>
C40000.1UF25V10%C0402-0201X7RU20SN74LVC1G17DCKR<Part Number>24531 R1461K1%R0402-0201<Part Number>
R1511K1%R0402-0201<Part Number>
R14405% R0402-0201<Part Number>C8880.1UFX6SC0402-020110%25V<Part Number>R15333.21% R0402-0201<Part Number>R14833.21% R0402-0201<Part Number>R14733.21% R0402-0201<Part Number>U2174LVC1G08GV12453Q3BDMN53D0LDW-7<Part Number>D23G25S24
R14533.21% R0402-0201<Part Number>R15033.21% R0402-0201<Part Number>R15210K1%R0402-0201<Part Number>
R14205% R0402-0201<Part Number>
C8890.1UFX6SC0402-020110%25V<Part Number>
R14105% R0402-0201<Part Number>
Q3ADMN53D0LDW-7<Part Number>S11G12D16U19BSS138K<Part Number>GDSU22DS1818-5<Part Number>RST#1VCC2GND3R14933.21% R0402-0201<Part Number>C8870.1UFX6SC0402-020110%25V<Part Number>R14305% R0402-0201<Part Number>PRSNT_NIC2_R_NHP_NIC2_ENPRSNT_NIC2_R_NRST_NIC2_PERST0_R_NRST_HP_NIC2_BUF_NRST_NIC2_PERST1_R_NRST_HP_NIC2_NHP_NIC2_PWRGDHP_NIC2_PWRGD_RHP_NIC2_PWRGD_RRST_HP_NIC2_NRST_NIC2_PERST_R_N
PRSNTB0_NIC2_NPRSNTB1_NIC2_NPRSNTB2_NIC2_NPRSNTB3_NIC2_NRST_NIC2_PERST2_R_NRST_NIC2_PERST3_R_NPRSNT_NIC2_N
HP_NIC2_HSC_PWRGD_N



5
5
4
4
3
3
2
2
1
1
D D
C C
B B
A A
PRIMARY CONNECTOR
NIC_3_J23(1/3)
PVT2_BOM_CHANGENIC3_DATA_IN[177]NIC3_DATA_OUT[177]NIC3_CLK[177]PWRGD_NIC3_PWR_GOOD[177]NIC3_MAIN_PWR_EN_R[177]NIC3_LD_N[177]NIC3_SLOT_ID0[178]NCSI_NIC3_RXD1[177]NCSI_NIC3_RXD0[177]NCSI_NIC3_CRS_DV[177]CLK_50M_NIC3_RBT_REF [177]NIC3_RBT_ARB_OUT [177]NIC3_SLOT_ID1 [178]NCSI_NIC3_TX_EN [177]NCSI_NIC3_TXD1 [177]NCSI_NIC3_TXD0 [177]NIC3_MAIN_PWR_EN[116,177]NIC3_MAIN_PWR_EN_R [177]NIC3_AUX_PWR_EN[116,177]NIC3_AUX_PWR_EN_R [177,178]NIC3_BIF0_N[178]NIC3_BIF1_N[178]NIC3_BIF2_N[178]RST_NIC3_PERST0_R_N[179]PRSNTB0_NIC3_N [177,179]PRSNTB0_NIC3_N[177,179]PRSNTB3_NIC3_N[177,179]PRSNTB1_NIC3_N [177,179]PRSNTB2_NIC3_N [177,179]PRSNTB1_NIC3_N [177,179]PRSNTB2_NIC3_N [177,179]PRSNTB3_NIC3_N [177,179]NIC3_AUX_PWR_EN_R[177,178]NIC3_RBT_ARB_IN [177]RST_SMB_NIC3_MUX_ISO_R_N [178]RST_NIC3_PERST1_R_N [179]RST_NIC3_PERST2_R_N [179]RST_NIC3_PERST3_R_N [179]NIC3_RBT_ARB_IN[177]NIC3_RBT_ARB_OUT [177]
NCSI_NIC3_CRS_DV [177]NCSI_NIC3_RXD0 [177]NCSI_NIC3_RXD1 [177]NCSI_NIC3_TXD0 [177]NCSI_NIC3_TXD1 [177]CLK_50M_NIC3_RBT_REF [177]NCSI_NIC3_TX_EN [177]PWRGD_NIC3_PWR_GOOD [177]NIC3_MAIN_PWR_EN [116,177]NIC3_AUX_PWR_EN [116,177]NIC3_LD_N [177]NIC3_DATA_IN [177]NIC3_DATA_OUT [177]PWRGD_NIC3_PWR_GOOD_R[116]PWRGD_NIC3_PWR_GOOD [177]
NIC3_PWRBRK_R_N [192]NIC3_CLK [177]P5E_PEX1_STN0_TX_C_DN<0>[23]P5E_PEX1_STN0_RX_DN<0> [23]P5E_PEX1_STN0_TX_C_DP<0>[23]P5E_PEX1_STN0_RX_DP<0> [23]P5E_PEX1_STN0_TX_C_DN<1>[23]P5E_PEX1_STN0_RX_DN<1> [23]P5E_PEX1_STN0_TX_C_DP<1>[23]P5E_PEX1_STN0_RX_DP<1> [23]P5E_PEX1_STN0_TX_C_DN<2>[23]P5E_PEX1_STN0_RX_DN<2> [23]P5E_PEX1_STN0_TX_C_DP<2>[23]P5E_PEX1_STN0_RX_DP<2> [23]P5E_PEX1_STN0_TX_C_DN<3>[23]P5E_PEX1_STN0_RX_DN<3> [23]P5E_PEX1_STN0_TX_C_DP<3>[23]P5E_PEX1_STN0_RX_DP<3> [23]P5E_PEX1_STN0_TX_C_DN<4>[23]P5E_PEX1_STN0_RX_DN<4> [23]P5E_PEX1_STN0_TX_C_DP<4>[23]P5E_PEX1_STN0_RX_DP<4> [23]P5E_PEX1_STN0_TX_C_DN<5>[23]P5E_PEX1_STN0_RX_DN<5> [23]P5E_PEX1_STN0_TX_C_DP<5>[23]P5E_PEX1_STN0_RX_DP<5> [23]P5E_PEX1_STN0_TX_C_DN<6>[23]P5E_PEX1_STN0_RX_DN<6> [23]P5E_PEX1_STN0_TX_C_DP<6>[23]P5E_PEX1_STN0_RX_DP<6> [23]P5E_PEX1_STN0_TX_C_DN<7>[23]P5E_PEX1_STN0_RX_DN<7> [23]P5E_PEX1_STN0_TX_C_DP<7>[23]P5E_PEX1_STN0_RX_DP<7> [23]P5E_PEX1_STN0_TX_C_DN<8>[23]P5E_PEX1_STN0_RX_DN<8> [23]P5E_PEX1_STN0_TX_C_DP<8>[23]P5E_PEX1_STN0_RX_DP<8> [23]P5E_PEX1_STN0_TX_C_DN<9>[23]P5E_PEX1_STN0_RX_DN<9> [23]P5E_PEX1_STN0_TX_C_DP<9>[23]P5E_PEX1_STN0_RX_DP<9> [23]P5E_PEX1_STN0_TX_C_DN<10>[23]P5E_PEX1_STN0_RX_DN<10> [23]P5E_PEX1_STN0_TX_C_DP<10>[23]P5E_PEX1_STN0_RX_DP<10> [23]P5E_PEX1_STN0_TX_C_DN<11>[23]P5E_PEX1_STN0_RX_DN<11> [23]P5E_PEX1_STN0_TX_C_DP<11>[23]P5E_PEX1_STN0_RX_DP<11> [23]P5E_PEX1_STN0_TX_C_DP<12>[23]P5E_PEX1_STN0_RX_DN<12> [23]P5E_PEX1_STN0_TX_C_DN<12>[23]P5E_PEX1_STN0_RX_DP<12> [23]P5E_PEX1_STN0_TX_C_DN<13>[23]P5E_PEX1_STN0_RX_DN<13> [23]P5E_PEX1_STN0_TX_C_DP<13>[23]P5E_PEX1_STN0_RX_DP<13> [23]P5E_PEX1_STN0_TX_C_DP<14>[23]P5E_PEX1_STN0_RX_DN<14> [23]P5E_PEX1_STN0_TX_C_DN<14>[23]P5E_PEX1_STN0_RX_DP<14> [23]P5E_PEX1_STN0_TX_C_DN<15>[23]P5E_PEX1_STN0_RX_DN<15> [23]P5E_PEX1_STN0_TX_C_DP<15>[23]P5E_PEX1_STN0_RX_DP<15> [23]SMB_NIC3_R_SCL [87,177]SMB_NIC3_R_SDA [87,177]SMB_NIC3_R_SCL [87,177]SMB_NIC3_R_SDA [87,177]CLK_100M_DB2000QL_NIC3_R_DN[79]CLK_100M_DB2000QL_NIC3_R_DP[79]
P12V_NIC3P3V3_NIC3P12V_NIC3P3V3_NIC3P3V3_AUXP3V3_NIC3
SizeDoc NumberRevDate: SheetofReviewerDesignerDepartmentProject
Page TitleCCBU D177 257Tuesday, August 29, 2023<project_name><Designer> GRANDTETON_SWB_20230829177 NIC_3_J23(1/3)<Reviewer>SizeDoc NumberRevDate: SheetofReviewerDesignerDepartmentProject
Page TitleCCBU D177 257Tuesday, August 29, 2023<project_name><Designer> GRANDTETON_SWB_20230829177 NIC_3_J23(1/3)<Reviewer>SizeDoc NumberRevDate: SheetofReviewerDesignerDepartmentProject
Page TitleCCBU D177 257Tuesday, August 29, 2023<project_name><Designer> GRANDTETON_SWB_20230829177 NIC_3_J23(1/3)<Reviewer>R167100K1% R0402-0201<Part Number>R17710K1% R0402-0201<Part Number>R169100K1% R0402-0201<Part Number>R1581K1% R0402-0201<Part Number>R172100K1% R0402-0201<Part Number>R1611K1% R0402-0201<Part Number>R168100K1% R0402-0201<Part Number>
C8940.1UFX6SC020110%16V<Part Number>C89122UFX6SC0805_H5720%16V<Part Number>C8950.1UFX6SC020110%16V<Part Number>
R16510K1% R0402-0201<Part Number>R171100K1% R0402-0201<Part Number>R1641K1% R0402-0201<Part Number>R15505% R0402-0201<Part Number>C8930.1UFX6SC020110%16V<Part Number>C8920.1UFX6SC020110%16V<Part Number>
R17610K1% R0402-0201<Part Number>KEYKEYKEYSCONN168_G64V35313HR
J23
<Part Number>
NIC_PWR_GOODOB1MAIN_PWR_ENOB2LD#OB3DATA_INOB4DATA_OUTOB5CLKOB6SLOT_ID0OB7RBT_RXD1OB8RBT_RXD0OB9GND_OB10OB10REFCLKn2OB11REFCLKp2OB12GND_OB13OB13RBT_CRS_DVOB14+12V_EDGE_B1B1+12V_EDGE_B2B2+12V_EDGE_B3B3+12V_EDGE_B4B4+12V_EDGE_B5B5+12V_EDGE_B6B6BIF0#B7BIF1#B8BIF2#B9PERST0#B10+3.3V_EDGEB11AUX_PWR_ENB12GND_B13B13REFCLKn0B14REFCLKp0B15GND_B16B16PETn0B17PETp0B18GND_B19B19PETn1B20PETp1B21GND_B22B22PETn2B23PETp2B24GND_B25B25PETn3B26PETp3B27GND_B28B28GND_B29B29PETn4B30PETp4B31GND_B32B32PETn5B33PETp5B34GND_B35B35PETn6B36PETp6B37GND_B38B38PETn7B39PETp7B40GND_B41B41PRSNTB0#B42GND_B43B43PETn8B44PETp8B45GND_B46B46PETn9B47PETp9B48GND_B49B49PETn10B50PETp10B51GND_B52B52PETn11B53PETp11B54GND_B55B55PETn12B56
PERST2#OA1PERST3#OA2WAKE#OA3RBT_ARB_INOA4RBT_ARB_OUTOA5SLOT_ID1OA6RBT_TX_ENOA7RBT_TXD1OA8RBT_TXD0OA9GND_OA10OA10REFCLKn3OA11REFCLKp3OA12GND_OA13OA13RBT_CLK_INOA14GND_A1A1GND_A2A2GND_A3A3GND_A4A4GND_A5A5GND_A6A6SMCLKA7SMDATA8SMRST#A9PRSNTA#A10PERST1#A11PRSNTB2#A12GND_A13A13REFCLKn1A14REFCLKp1A15GND_A16A16PERn0A17PERp0A18GND_A19A19PERn1A20PERp1A21GND_A22A22PERn2A23PERp2A24GND_A25A25PERn3A26PERp3A27GND_A28A28GND_A29A29PERn4A30PERp4A31GND_A32A32PERn5A33PERp5A34GND_A35A35PERn6A36PERp6A37GND_A38A38PERn7A39PERp7A40GND_A41A41PRSNTB1#A42GND_A43A43PERn8A44PERp8A45GND_A46A46PERn9A47PERp9A48GND_A49A49PERn10A50PERp10A51GND_A52A52PERn11A53PERp11A54GND_A55A55PERn12A56PERp12A57GND_A58A58PERn13A59PERp13A60GND_A61A61PERn14A62PERp14A63GND_A64A64PERn15A65PERp15A66GND_A67A67USB_DATnA68USB_DATpA69PWRBRK0#A70PETp12B57GND_B58B58PETn13B59PETp13B60GND_B61B61PETn14B62PETp14B63GND_B64B64PETn15B65PETp15B66GND_B67B67RFU1_NCB68RFU2_NCB69PRSNTB3#B70G1G1G2G2G3G3G4G4G5G5G6G6G7G7G8G8G9G9R1661K1% R0402-0201<Part Number>R1591K1% R0402-0201<Part Number>R15605% R0402-0201<Part Number>C8990.1UFX6SC0402-020110%25V<Part Number>
R170100K1% R0402-0201<Part Number>
C9000.1UFX6SC0402-020110%25V<Part Number>R1601K1% R0402-0201<Part Number>R175100K1% R0402-0201<Part Number>
C8960.1UFX6SC020110%16V<Part Number>C89022UFX6SC0805_H5720%16V<Part Number>
R173100K1% R0402-0201<Part Number>R1622.2K5% R0402-0201C8970.1UFX6SC0402-020110%25V<Part Number>R15705% R0402-0201<Part Number>R15405% R0402-0201<Part Number>
R1632.2K5% R0402-0201R174100K1% R0402-0201<Part Number>
C8980.1UFX6SC0402-020110%25V<Part Number>PWRGD_NIC3_PWR_GOODNIC3_MAIN_PWR_EN_RNIC3_LD_NNIC3_DATA_INNIC3_DATA_OUTNIC3_CLKNIC3_SLOT_ID0NCSI_NIC3_RXD1NCSI_NIC3_RXD0NCSI_NIC3_CRS_DVCLK_50M_NIC3_RBT_REFNIC3_RBT_ARB_OUTNIC3_SLOT_ID1NCSI_NIC3_TX_ENNCSI_NIC3_TXD1NCSI_NIC3_TXD0NIC3_RBT_ARB_INNIC3_MAIN_PWR_ENNIC3_MAIN_PWR_EN_RNIC3_AUX_PWR_ENNIC3_AUX_PWR_EN_RNIC3_BIF0_NNIC3_BIF1_NNIC3_BIF2_NPRSNTB3_NIC3_NPRSNTB0_NIC3_NPRSNTB1_NIC3_NPRSNTB2_NIC3_NRST_NIC3_PERST0_R_NPRSNTB0_NIC3_NPRSNTB1_NIC3_NPRSNTB2_NIC3_NPRSNTB3_NIC3_NNIC3_AUX_PWR_EN_RRST_NIC3_PERST1_R_NRST_NIC3_PERST2_R_NRST_NIC3_PERST3_R_NNIC3_RBT_ARB_INNIC3_RBT_ARB_OUT
NCSI_NIC3_CRS_DVNCSI_NIC3_RXD0NCSI_NIC3_RXD1NCSI_NIC3_TXD0NCSI_NIC3_TXD1CLK_50M_NIC3_RBT_REFNCSI_NIC3_TX_ENPWRGD_NIC3_PWR_GOODNIC3_MAIN_PWR_ENNIC3_AUX_PWR_ENNIC3_LD_NNIC3_DATA_INNIC3_DATA_OUTNIC3_PWRBRK_R_N
PWRGD_NIC3_PWR_GOOD_RPWRGD_NIC3_PWR_GOODNIC3_CLKP5E_PEX1_STN0_TX_C_DN<0>P5E_PEX1_STN0_RX_DN<0>P5E_PEX1_STN0_TX_C_DP<0>P5E_PEX1_STN0_RX_DP<0>P5E_PEX1_STN0_TX_C_DN<1>P5E_PEX1_STN0_RX_DN<1>P5E_PEX1_STN0_TX_C_DP<1>P5E_PEX1_STN0_RX_DP<1>P5E_PEX1_STN0_TX_C_DN<2>P5E_PEX1_STN0_RX_DN<2>P5E_PEX1_STN0_TX_C_DP<2>P5E_PEX1_STN0_RX_DP<2>P5E_PEX1_STN0_TX_C_DN<3>P5E_PEX1_STN0_RX_DN<3>P5E_PEX1_STN0_TX_C_DP<3>P5E_PEX1_STN0_RX_DP<3>P5E_PEX1_STN0_TX_C_DN<4>P5E_PEX1_STN0_RX_DN<4>P5E_PEX1_STN0_TX_C_DP<4>P5E_PEX1_STN0_RX_DP<4>P5E_PEX1_STN0_TX_C_DN<5>P5E_PEX1_STN0_RX_DN<5>P5E_PEX1_STN0_TX_C_DP<5>P5E_PEX1_STN0_RX_DP<5>P5E_PEX1_STN0_TX_C_DN<6>P5E_PEX1_STN0_RX_DN<6>P5E_PEX1_STN0_TX_C_DP<6>P5E_PEX1_STN0_RX_DP<6>P5E_PEX1_STN0_TX_C_DN<7>P5E_PEX1_STN0_RX_DN<7>P5E_PEX1_STN0_TX_C_DP<7>P5E_PEX1_STN0_RX_DP<7>P5E_PEX1_STN0_TX_C_DN<8>P5E_PEX1_STN0_RX_DN<8>P5E_PEX1_STN0_TX_C_DP<8>P5E_PEX1_STN0_RX_DP<8>P5E_PEX1_STN0_TX_C_DN<9>P5E_PEX1_STN0_RX_DN<9>P5E_PEX1_STN0_TX_C_DP<9>P5E_PEX1_STN0_RX_DP<9>P5E_PEX1_STN0_TX_C_DN<10>P5E_PEX1_STN0_RX_DN<10>P5E_PEX1_STN0_TX_C_DP<10>P5E_PEX1_STN0_RX_DP<10>P5E_PEX1_STN0_TX_C_DN<11>P5E_PEX1_STN0_RX_DN<11>P5E_PEX1_STN0_TX_C_DP<11>P5E_PEX1_STN0_RX_DP<11>P5E_PEX1_STN0_TX_C_DP<12>P5E_PEX1_STN0_RX_DN<12>P5E_PEX1_STN0_TX_C_DN<12>P5E_PEX1_STN0_RX_DP<12>P5E_PEX1_STN0_TX_C_DN<13>P5E_PEX1_STN0_RX_DN<13>P5E_PEX1_STN0_TX_C_DP<13>P5E_PEX1_STN0_RX_DP<13>P5E_PEX1_STN0_TX_C_DP<14>P5E_PEX1_STN0_RX_DN<14>P5E_PEX1_STN0_TX_C_DN<14>P5E_PEX1_STN0_RX_DP<14>P5E_PEX1_STN0_TX_C_DN<15>P5E_PEX1_STN0_RX_DN<15>P5E_PEX1_STN0_TX_C_DP<15>P5E_PEX1_STN0_RX_DP<15>SMB_NIC3_R_SCLSMB_NIC3_R_SDARST_SMB_NIC3_MUX_ISO_R_NCLK_100M_DB2000QL_NIC3_R_DNSMB_NIC3_R_SCLCLK_100M_DB2000QL_NIC3_R_DPSMB_NIC3_R_SDA



5
5
4
4
3
3
2
2
1
1
D D
C C
B B
A A
NIC_3_J23(2/3)
RST_SMB_NIC_MUX_R_N[87,169,172,175,181,184,187,190]NIC3_AUX_PWR_EN_R[177]RST_SMB_NIC3_MUX_ISO_R_N [177]
NIC3_BIF0_N [177]NIC3_BIF1_N [177]NIC3_BIF2_N [177]NIC3_SLOT_ID0 [177]NIC3_SLOT_ID1 [177]
P3V3_AUXP3V3_AUXP3V3_AUXP3V3_AUXP3V3_NIC3P3V3_NIC3
P3V3_NIC3SizeDoc NumberRevDate: SheetofReviewerDesignerDepartmentProject
Page TitleCCBU D178 257Tuesday, August 29, 2023<project_name><Designer> GRANDTETON_SWB_20230829178 NIC_3_J23(2/3)<Reviewer>SizeDoc NumberRevDate: SheetofReviewerDesignerDepartmentProject
Page TitleCCBU D178 257Tuesday, August 29, 2023<project_name><Designer> GRANDTETON_SWB_20230829178 NIC_3_J23(2/3)<Reviewer>SizeDoc NumberRevDate: SheetofReviewerDesignerDepartmentProject
Page TitleCCBU D178 257Tuesday, August 29, 2023<project_name><Designer> GRANDTETON_SWB_20230829178 NIC_3_J23(2/3)<Reviewer>
R1811001% R0402-0201<Part Number>
R19005% R0402-0201<Part Number>R18705% R0402-0201<Part Number>R1791001% R0402-0201<Part Number>
3 state outputU2374HC1G126GW<Part Number>24513R189 33 R0402-02011%R18505% R0402-0201<Part Number>R182100K1% R0402-0201<Part Number>NIR1804.7K1% R0402-0201<Part Number>NI
R191100K1%R0402-0201<Part Number>
R18305% R0402-0201<Part Number>C9010.1UFX6SC0402-020110%25V<Part Number>R184100K1% R0402-0201<Part Number>NIR1884.75KR0402-02011%NI
R1784.7K1% R0402-0201<Part Number>NIR186100K1% R0402-0201<Part Number>NIRST_SMB_NIC3_MUX_ISO_R_NRST_SMB_NIC3_MUX_ISO_NRST_SMB_NIC3_MUX_NNIC3_AUX_PWR_EN_RNIC3_BIF0_NNIC3_BIF1_NNIC3_BIF2_NNIC3_SLOT_ID0NIC3_SLOT_ID1



5
5
4
4
3
3
2
2
1
1
D D
C C
B B
A A
NIC_3_J23(3/3)
PRSNT_NIC3_R_N [86,116,179]HP_NIC3_EN [235,238,242,248]PRSNT_NIC3_R_N[86,116,179]RST_NIC3_PERST0_R_N [177]RST_NIC3_PERST1_R_N [177]RST_HP_NIC3_N[179]HP_NIC3_PWRGD_R [179]HP_NIC3_PWRGD_R[179]RST_HP_NIC3_N [179]RST_NIC3_PERST_R_N[116]
PRSNTB0_NIC3_N[177]PRSNTB1_NIC3_N[177]PRSNTB2_NIC3_N[177]PRSNTB3_NIC3_N[177]RST_NIC3_PERST2_R_N [177]RST_NIC3_PERST3_R_N [177]PWRGD_P12V_NIC3_R[116,235,242]
P3V3_AUXP3V3_AUXP3V3_NIC3P3V3_AUXP3V3_NIC3P3V3_AUXSizeDoc NumberRevDate: SheetofReviewerDesignerDepartmentProject
Page TitleCCBU D179 257Tuesday, August 29, 2023<project_name><Designer> GRANDTETON_SWB_20230829179 NIC_3_J23(3/3)<Reviewer>SizeDoc NumberRevDate: SheetofReviewerDesignerDepartmentProject
Page TitleCCBU D179 257Tuesday, August 29, 2023<project_name><Designer> GRANDTETON_SWB_20230829179 NIC_3_J23(3/3)<Reviewer>SizeDoc NumberRevDate: SheetofReviewerDesignerDepartmentProject
Page TitleCCBU D179 257Tuesday, August 29, 2023<project_name><Designer> GRANDTETON_SWB_20230829179 NIC_3_J23(3/3)<Reviewer>
R19505% R0402-0201<Part Number>R1971K1%R0402-0201<Part Number>
U27DS1818-5<Part Number>RST#1VCC2GND3
R19205% R0402-0201<Part Number>R19405% R0402-0201<Part Number>
R20433.21% R0402-0201<Part Number>
C40010.1UF25V10%C0402-0201X7R
R2021K1%R0402-0201<Part Number>R20310K1%R0402-0201<Part Number>
R19305% R0402-0201<Part Number>R19633.21% R0402-0201<Part Number>R19833.21% R0402-0201<Part Number>U25SN74LVC1G17DCKR<Part Number>24531R20033.21% R0402-0201<Part Number>Q4ADMN53D0LDW-7<Part Number>S11G12D16R20133.21% R0402-0201<Part Number>C9030.1UFX6SC0402-020110%25V<Part Number>U2674LVC1G08GV12453C9020.1UFX6SC0402-020110%25V<Part Number>C9040.1UFX6SC0402-020110%25V<Part Number>
U24BSS138K<Part Number>GDS
Q4BDMN53D0LDW-7<Part Number>D23G25S24R19933.21% R0402-0201<Part Number>PRSNT_NIC3_R_NHP_NIC3_ENPRSNT_NIC3_R_NRST_NIC3_PERST0_R_NRST_HP_NIC3_BUF_NRST_NIC3_PERST1_R_NRST_HP_NIC3_NHP_NIC3_PWRGDHP_NIC3_PWRGD_RHP_NIC3_PWRGD_RRST_HP_NIC3_NRST_NIC3_PERST_R_N
PRSNTB0_NIC3_NPRSNTB1_NIC3_NPRSNTB2_NIC3_NPRSNTB3_NIC3_NRST_NIC3_PERST2_R_NRST_NIC3_PERST3_R_NPRSNT_NIC3_N
HP_NIC3_HSC_PWRGD_N



5
5
4
4
3
3
2
2
1
1
D D
C C
B B
A A
PRIMARY CONNECTOR
NIC_4_J24(1/3)
LANE REVERSAL
DVT_CHANGENIC4_DATA_IN[180]NIC4_DATA_OUT[180]NIC4_CLK[180]PWRGD_NIC4_PWR_GOOD[180]NIC4_MAIN_PWR_EN_R[180]NIC4_LD_N[180]NIC4_SLOT_ID0[181]NCSI_NIC4_RXD1[180]NCSI_NIC4_RXD0[180]NCSI_NIC4_CRS_DV[180]CLK_50M_NIC4_RBT_REF [180]NIC4_RBT_ARB_OUT [180]NIC4_SLOT_ID1 [181]NCSI_NIC4_TX_EN [180]NCSI_NIC4_TXD1 [180]NCSI_NIC4_TXD0 [180]NIC4_MAIN_PWR_EN[116,180]NIC4_MAIN_PWR_EN_R [180]NIC4_AUX_PWR_EN[116,180]NIC4_AUX_PWR_EN_R [180,181]NIC4_BIF0_N[181]NIC4_BIF1_N[181]NIC4_BIF2_N[181]RST_NIC4_PERST0_R_N[182]PRSNTB0_NIC4_N [180,182]PRSNTB0_NIC4_N[180,182]PRSNTB3_NIC4_N[180,182]PRSNTB1_NIC4_N [180,182]PRSNTB2_NIC4_N [180,182]PRSNTB1_NIC4_N [180,182]PRSNTB2_NIC4_N [180,182]PRSNTB3_NIC4_N [180,182]NIC4_AUX_PWR_EN_R[180,181]NIC4_RBT_ARB_IN [180]RST_SMB_NIC4_MUX_ISO_R_N [181]RST_NIC4_PERST1_R_N [182]RST_NIC4_PERST2_R_N [182]RST_NIC4_PERST3_R_N [182]NIC4_RBT_ARB_IN[180]NIC4_RBT_ARB_OUT [180]
NCSI_NIC4_CRS_DV [180]NCSI_NIC4_RXD0 [180]NCSI_NIC4_RXD1 [180]NCSI_NIC4_TXD0 [180]NCSI_NIC4_TXD1 [180]CLK_50M_NIC4_RBT_REF [180]NCSI_NIC4_TX_EN [180]PWRGD_NIC4_PWR_GOOD [180]NIC4_MAIN_PWR_EN [116,180]NIC4_AUX_PWR_EN [116,180]NIC4_LD_N [180]NIC4_DATA_IN [180]NIC4_DATA_OUT [180]PWRGD_NIC4_PWR_GOOD_R[116]PWRGD_NIC4_PWR_GOOD [180]
NIC4_PWRBRK_R_N [192]NIC4_CLK [180]P5E_PEX2_STN1_TX_C_DP<31>[36]P5E_PEX2_STN1_RX_DN<31> [36]P5E_PEX2_STN1_TX_C_DN<31>[36]P5E_PEX2_STN1_RX_DP<31> [36]P5E_PEX2_STN1_TX_C_DN<30>[36]P5E_PEX2_STN1_RX_DN<30> [36]P5E_PEX2_STN1_TX_C_DP<30>[36]P5E_PEX2_STN1_RX_DP<30> [36]P5E_PEX2_STN1_TX_C_DP<29>[36]P5E_PEX2_STN1_RX_DN<29> [36]P5E_PEX2_STN1_TX_C_DN<29>[36]P5E_PEX2_STN1_RX_DP<29> [36]P5E_PEX2_STN1_TX_C_DN<28>[36]P5E_PEX2_STN1_RX_DN<28> [36]P5E_PEX2_STN1_TX_C_DP<28>[36]P5E_PEX2_STN1_RX_DP<28> [36]P5E_PEX2_STN1_TX_C_DP<27>[36]P5E_PEX2_STN1_RX_DN<27> [36]P5E_PEX2_STN1_TX_C_DN<27>[36]P5E_PEX2_STN1_RX_DP<27> [36]P5E_PEX2_STN1_TX_C_DN<26>[36]P5E_PEX2_STN1_RX_DN<26> [36]P5E_PEX2_STN1_TX_C_DP<26>[36]P5E_PEX2_STN1_RX_DP<26> [36]P5E_PEX2_STN1_TX_C_DP<25>[36]P5E_PEX2_STN1_RX_DN<25> [36]P5E_PEX2_STN1_TX_C_DN<25>[36]P5E_PEX2_STN1_RX_DP<25> [36]P5E_PEX2_STN1_TX_C_DN<24>[36]P5E_PEX2_STN1_RX_DN<24> [36]P5E_PEX2_STN1_TX_C_DP<24>[36]P5E_PEX2_STN1_RX_DP<24> [36]P5E_PEX2_STN1_TX_C_DP<23>[36]P5E_PEX2_STN1_RX_DN<23> [36]P5E_PEX2_STN1_TX_C_DN<23>[36]P5E_PEX2_STN1_RX_DP<23> [36]P5E_PEX2_STN1_TX_C_DN<22>[36]P5E_PEX2_STN1_RX_DN<22> [36]P5E_PEX2_STN1_TX_C_DP<22>[36]P5E_PEX2_STN1_RX_DP<22> [36]P5E_PEX2_STN1_TX_C_DP<21>[36]P5E_PEX2_STN1_RX_DN<21> [36]P5E_PEX2_STN1_TX_C_DN<21>[36]P5E_PEX2_STN1_RX_DP<21> [36]P5E_PEX2_STN1_TX_C_DN<20>[36]P5E_PEX2_STN1_RX_DN<20> [36]P5E_PEX2_STN1_TX_C_DP<20>[36]P5E_PEX2_STN1_RX_DP<20> [36]P5E_PEX2_STN1_TX_C_DN<19>[36]P5E_PEX2_STN1_RX_DN<19> [36]P5E_PEX2_STN1_TX_C_DP<19>[36]P5E_PEX2_STN1_RX_DP<19> [36]P5E_PEX2_STN1_TX_C_DN<18>[36]P5E_PEX2_STN1_RX_DN<18> [36]P5E_PEX2_STN1_TX_C_DP<18>[36]P5E_PEX2_STN1_RX_DP<18> [36]P5E_PEX2_STN1_TX_C_DN<17>[36]P5E_PEX2_STN1_RX_DN<17> [36]P5E_PEX2_STN1_TX_C_DP<17>[36]P5E_PEX2_STN1_RX_DP<17> [36]P5E_PEX2_STN1_TX_C_DN<16>[36]P5E_PEX2_STN1_RX_DN<16> [36]P5E_PEX2_STN1_TX_C_DP<16>[36]P5E_PEX2_STN1_RX_DP<16> [36]SMB_NIC4_LS_SCL [94,180]SMB_NIC4_LS_SDA [94,180]SMB_NIC4_LS_SCL [94,180]SMB_NIC4_LS_SDA [94,180]CLK_100M_DB2000QL_NIC4_R_DN[79]CLK_100M_DB2000QL_NIC4_R_DP[79]
P12V_NIC4P3V3_NIC4P12V_NIC4P3V3_NIC4P3V3_AUXP3V3_NIC4
SizeDoc NumberRevDate: SheetofReviewerDesignerDepartmentProject
Page TitleCCBU D180 257Tuesday, August 29, 2023<project_name><Designer> GRANDTETON_SWB_20230829180 NIC_4_J24(1/3)<Reviewer>SizeDoc NumberRevDate: SheetofReviewerDesignerDepartmentProject
Page TitleCCBU D180 257Tuesday, August 29, 2023<project_name><Designer> GRANDTETON_SWB_20230829180 NIC_4_J24(1/3)<Reviewer>SizeDoc NumberRevDate: SheetofReviewerDesignerDepartmentProject
Page TitleCCBU D180 257Tuesday, August 29, 2023<project_name><Designer> GRANDTETON_SWB_20230829180 NIC_4_J24(1/3)<Reviewer>R224100K1% R0402-0201<Part Number>R218100K1% R0402-0201<Part Number>R225100K1% R0402-0201<Part Number>R2101K1% R0402-0201<Part Number>R2171K1% R0402-0201<Part Number>R20805% R0402-0201<Part Number>R220100K1% R0402-0201<Part Number>R2091K1% R0402-0201<Part Number>C9080.1UFX6SC020110%16V<Part Number>
R2151K1% R0402-0201<Part Number>R20605% R0402-0201<Part Number>
R222100K1% R0402-0201<Part Number>
C90522UFX6SC0805_H5720%16V<Part Number>C9130.1UFX6SC0402-020110%25V<Part Number>C9100.1UFX6SC020110%16V<Part Number>
R22810K1% R0402-0201<Part Number>KEYKEYKEYSCONN168_G64V35313HR
J24
<Part Number>
NIC_PWR_GOODOB1MAIN_PWR_ENOB2LD#OB3DATA_INOB4DATA_OUTOB5CLKOB6SLOT_ID0OB7RBT_RXD1OB8RBT_RXD0OB9GND_OB10OB10REFCLKn2OB11REFCLKp2OB12GND_OB13OB13RBT_CRS_DVOB14+12V_EDGE_B1B1+12V_EDGE_B2B2+12V_EDGE_B3B3+12V_EDGE_B4B4+12V_EDGE_B5B5+12V_EDGE_B6B6BIF0#B7BIF1#B8BIF2#B9PERST0#B10+3.3V_EDGEB11AUX_PWR_ENB12GND_B13B13REFCLKn0B14REFCLKp0B15GND_B16B16PETn0B17PETp0B18GND_B19B19PETn1B20PETp1B21GND_B22B22PETn2B23PETp2B24GND_B25B25PETn3B26PETp3B27GND_B28B28GND_B29B29PETn4B30PETp4B31GND_B32B32PETn5B33PETp5B34GND_B35B35PETn6B36PETp6B37GND_B38B38PETn7B39PETp7B40GND_B41B41PRSNTB0#B42GND_B43B43PETn8B44PETp8B45GND_B46B46PETn9B47PETp9B48GND_B49B49PETn10B50PETp10B51GND_B52B52PETn11B53PETp11B54GND_B55B55PETn12B56
PERST2#OA1PERST3#OA2WAKE#OA3RBT_ARB_INOA4RBT_ARB_OUTOA5SLOT_ID1OA6RBT_TX_ENOA7RBT_TXD1OA8RBT_TXD0OA9GND_OA10OA10REFCLKn3OA11REFCLKp3OA12GND_OA13OA13RBT_CLK_INOA14GND_A1A1GND_A2A2GND_A3A3GND_A4A4GND_A5A5GND_A6A6SMCLKA7SMDATA8SMRST#A9PRSNTA#A10PERST1#A11PRSNTB2#A12GND_A13A13REFCLKn1A14REFCLKp1A15GND_A16A16PERn0A17PERp0A18GND_A19A19PERn1A20PERp1A21GND_A22A22PERn2A23PERp2A24GND_A25A25PERn3A26PERp3A27GND_A28A28GND_A29A29PERn4A30PERp4A31GND_A32A32PERn5A33PERp5A34GND_A35A35PERn6A36PERp6A37GND_A38A38PERn7A39PERp7A40GND_A41A41PRSNTB1#A42GND_A43A43PERn8A44PERp8A45GND_A46A46PERn9A47PERp9A48GND_A49A49PERn10A50PERp10A51GND_A52A52PERn11A53PERp11A54GND_A55A55PERn12A56PERp12A57GND_A58A58PERn13A59PERp13A60GND_A61A61PERn14A62PERp14A63GND_A64A64PERn15A65PERp15A66GND_A67A67USB_DATnA68USB_DATpA69PWRBRK0#A70PETp12B57GND_B58B58PETn13B59PETp13B60GND_B61B61PETn14B62PETp14B63GND_B64B64PETn15B65PETp15B66GND_B67B67RFU1_NCB68RFU2_NCB69PRSNTB3#B70G1G1G2G2G3G3G4G4G5G5G6G6G7G7G8G8G9G9R2133.3K1%R0402-0201
C9110.1UFX6SC020110%16V<Part Number>R20505% R0402-0201<Part Number>C9150.1UFX6SC0402-020110%25V<Part Number>C9070.1UFX6SC020110%16V<Part Number>R2143.3K1%R0402-0201R223100K1% R0402-0201<Part Number>
R20705% R0402-0201<Part Number>C9140.1UFX6SC0402-020110%25V<Part Number>R21610K1% R0402-0201<Part Number>R2111K1% R0402-0201<Part Number>R219100K1% R0402-0201<Part Number>
C9090.1UFX6SC020110%16V<Part Number>
R22710K1% R0402-0201<Part Number>R226100K1% R0402-0201<Part Number>
C90622UFX6SC0805_H5720%16V<Part Number>R2121K1% R0402-0201<Part Number>R221100K1% R0402-0201<Part Number>
C9120.1UFX6SC0402-020110%25V<Part Number>PWRGD_NIC4_PWR_GOODNIC4_MAIN_PWR_EN_RNIC4_LD_NNIC4_DATA_INNIC4_DATA_OUTNIC4_CLKNIC4_SLOT_ID0NCSI_NIC4_RXD1NCSI_NIC4_RXD0NCSI_NIC4_CRS_DVCLK_50M_NIC4_RBT_REFNIC4_RBT_ARB_OUTNIC4_SLOT_ID1NCSI_NIC4_TX_ENNCSI_NIC4_TXD1NCSI_NIC4_TXD0NIC4_RBT_ARB_INNIC4_MAIN_PWR_ENNIC4_MAIN_PWR_EN_RNIC4_AUX_PWR_ENNIC4_AUX_PWR_EN_RNIC4_BIF0_NNIC4_BIF1_NNIC4_BIF2_NPRSNTB3_NIC4_NPRSNTB0_NIC4_NPRSNTB1_NIC4_NPRSNTB2_NIC4_NRST_NIC4_PERST0_R_NPRSNTB0_NIC4_NPRSNTB1_NIC4_NPRSNTB2_NIC4_NPRSNTB3_NIC4_NNIC4_AUX_PWR_EN_RRST_SMB_NIC4_MUX_ISO_R_NRST_NIC4_PERST1_R_NRST_NIC4_PERST2_R_NRST_NIC4_PERST3_R_NNIC4_RBT_ARB_INNIC4_RBT_ARB_OUT
NCSI_NIC4_CRS_DVNCSI_NIC4_RXD0NCSI_NIC4_RXD1NCSI_NIC4_TXD0NCSI_NIC4_TXD1CLK_50M_NIC4_RBT_REFNCSI_NIC4_TX_ENPWRGD_NIC4_PWR_GOODNIC4_MAIN_PWR_ENNIC4_AUX_PWR_ENNIC4_LD_NNIC4_DATA_INNIC4_DATA_OUTNIC4_PWRBRK_R_N
PWRGD_NIC4_PWR_GOOD_RPWRGD_NIC4_PWR_GOODNIC4_CLKP5E_PEX2_STN1_TX_C_DP<31>P5E_PEX2_STN1_RX_DN<31>P5E_PEX2_STN1_TX_C_DN<31>P5E_PEX2_STN1_RX_DP<31>P5E_PEX2_STN1_TX_C_DN<30>P5E_PEX2_STN1_RX_DN<30>P5E_PEX2_STN1_TX_C_DP<30>P5E_PEX2_STN1_RX_DP<30>P5E_PEX2_STN1_TX_C_DP<29>P5E_PEX2_STN1_RX_DN<29>P5E_PEX2_STN1_TX_C_DN<29>P5E_PEX2_STN1_RX_DP<29>P5E_PEX2_STN1_TX_C_DN<28>P5E_PEX2_STN1_RX_DN<28>P5E_PEX2_STN1_TX_C_DP<28>P5E_PEX2_STN1_RX_DP<28>P5E_PEX2_STN1_TX_C_DP<27>P5E_PEX2_STN1_RX_DN<27>P5E_PEX2_STN1_TX_C_DN<27>P5E_PEX2_STN1_RX_DP<27>P5E_PEX2_STN1_TX_C_DN<26>P5E_PEX2_STN1_RX_DN<26>P5E_PEX2_STN1_TX_C_DP<26>P5E_PEX2_STN1_RX_DP<26>P5E_PEX2_STN1_TX_C_DP<25>P5E_PEX2_STN1_RX_DN<25>P5E_PEX2_STN1_TX_C_DN<25>P5E_PEX2_STN1_RX_DP<25>P5E_PEX2_STN1_TX_C_DN<24>P5E_PEX2_STN1_RX_DN<24>P5E_PEX2_STN1_TX_C_DP<24>P5E_PEX2_STN1_RX_DP<24>P5E_PEX2_STN1_TX_C_DP<23>P5E_PEX2_STN1_RX_DN<23>P5E_PEX2_STN1_TX_C_DN<23>P5E_PEX2_STN1_RX_DP<23>P5E_PEX2_STN1_TX_C_DN<22>P5E_PEX2_STN1_RX_DN<22>P5E_PEX2_STN1_TX_C_DP<22>P5E_PEX2_STN1_RX_DP<22>P5E_PEX2_STN1_TX_C_DP<21>P5E_PEX2_STN1_RX_DN<21>P5E_PEX2_STN1_TX_C_DN<21>P5E_PEX2_STN1_RX_DP<21>P5E_PEX2_STN1_TX_C_DN<20>P5E_PEX2_STN1_RX_DN<20>P5E_PEX2_STN1_TX_C_DP<20>P5E_PEX2_STN1_RX_DP<20>P5E_PEX2_STN1_TX_C_DN<19>P5E_PEX2_STN1_RX_DN<19>P5E_PEX2_STN1_TX_C_DP<19>P5E_PEX2_STN1_RX_DP<19>P5E_PEX2_STN1_TX_C_DN<18>P5E_PEX2_STN1_RX_DN<18>P5E_PEX2_STN1_TX_C_DP<18>P5E_PEX2_STN1_RX_DP<18>P5E_PEX2_STN1_TX_C_DN<17>P5E_PEX2_STN1_RX_DN<17>P5E_PEX2_STN1_TX_C_DP<17>P5E_PEX2_STN1_RX_DP<17>P5E_PEX2_STN1_TX_C_DN<16>P5E_PEX2_STN1_RX_DN<16>P5E_PEX2_STN1_TX_C_DP<16>P5E_PEX2_STN1_RX_DP<16>SMB_NIC4_LS_SCLSMB_NIC4_LS_SDASMB_NIC4_LS_SCLSMB_NIC4_LS_SDACLK_100M_DB2000QL_NIC4_R_DNCLK_100M_DB2000QL_NIC4_R_DP



5
5
4
4
3
3
2
2
1
1
D D
C C
B B
A A
NIC_4_J24(2/3)
RST_SMB_NIC_MUX_R_N[87,169,172,175,178,184,187,190]NIC4_AUX_PWR_EN_R[180]RST_SMB_NIC4_MUX_ISO_R_N [180]
NIC4_BIF0_N [180]NIC4_BIF1_N [180]NIC4_BIF2_N [180]NIC4_SLOT_ID0 [180]NIC4_SLOT_ID1 [180]
P3V3_AUXP3V3_AUXP3V3_AUXP3V3_AUXP3V3_NIC4P3V3_NIC4
P3V3_NIC4SizeDoc NumberRevDate: SheetofReviewerDesignerDepartmentProject
Page TitleCCBU D181 257Tuesday, August 29, 2023<project_name><Designer> GRANDTETON_SWB_20230829181 NIC_4_J24(2/3)<Reviewer>SizeDoc NumberRevDate: SheetofReviewerDesignerDepartmentProject
Page TitleCCBU D181 257Tuesday, August 29, 2023<project_name><Designer> GRANDTETON_SWB_20230829181 NIC_4_J24(2/3)<Reviewer>SizeDoc NumberRevDate: SheetofReviewerDesignerDepartmentProject
Page TitleCCBU D181 257Tuesday, August 29, 2023<project_name><Designer> GRANDTETON_SWB_20230829181 NIC_4_J24(2/3)<Reviewer>R2394.75KR0402-02011%NIR240 33 R0402-02011%
R2294.7K1% R0402-0201<Part Number>NI
R242100K1%R0402-0201<Part Number>R24105% R0402-0201<Part Number>
R23405% R0402-0201<Part Number>R2321001% R0402-0201<Part Number>R23805% R0402-0201<Part Number>3 state outputU2874HC1G126GW<Part Number>24513C9160.1UFX6SC0402-020110%25V<Part Number>R233100K1% R0402-0201<Part Number>NIR2301001% R0402-0201<Part Number>R235100K1% R0402-0201<Part Number>NIR23605% R0402-0201<Part Number>R237100K1% R0402-0201<Part Number>NIR2314.7K1% R0402-0201<Part Number>NI
RST_SMB_NIC4_MUX_ISO_R_NRST_SMB_NIC4_MUX_ISO_NRST_SMB_NIC4_MUX_NNIC4_AUX_PWR_EN_RNIC4_BIF0_NNIC4_BIF1_NNIC4_BIF2_NNIC4_SLOT_ID0NIC4_SLOT_ID1



5
5
4
4
3
3
2
2
1
1
D D
C C
B B
A A
NIC_4_J24(3/3)
PRSNT_NIC4_R_N [86,116,182]HP_NIC4_EN [235,238,243,249]PRSNT_NIC4_R_N[86,116,182]RST_NIC4_PERST0_R_N [180]RST_NIC4_PERST1_R_N [180]RST_HP_NIC4_N[182]HP_NIC4_PWRGD_R [182]HP_NIC4_PWRGD_R[182]RST_HP_NIC4_N [182]RST_NIC4_PERST_R_N[116]
PRSNTB0_NIC4_N[180]PRSNTB1_NIC4_N[180]PRSNTB2_NIC4_N[180]PRSNTB3_NIC4_N[180]RST_NIC4_PERST2_R_N [180]RST_NIC4_PERST3_R_N [180]PWRGD_P12V_NIC4_R[116,235,243]
P3V3_AUXP3V3_AUXP3V3_NIC4P3V3_AUXP3V3_NIC4P3V3_AUXSizeDoc NumberRevDate: SheetofReviewerDesignerDepartmentProject
Page TitleCCBU D182 257Tuesday, August 29, 2023<project_name><Designer> GRANDTETON_SWB_20230829182 NIC_4_J24(3/3)<Reviewer>SizeDoc NumberRevDate: SheetofReviewerDesignerDepartmentProject
Page TitleCCBU D182 257Tuesday, August 29, 2023<project_name><Designer> GRANDTETON_SWB_20230829182 NIC_4_J24(3/3)<Reviewer>SizeDoc NumberRevDate: SheetofReviewerDesignerDepartmentProject
Page TitleCCBU D182 257Tuesday, August 29, 2023<project_name><Designer> GRANDTETON_SWB_20230829182 NIC_4_J24(3/3)<Reviewer>
R2481K1%R0402-0201<Part Number>
R2531K1%R0402-0201<Part Number>C9180.1UFX6SC0402-020110%25V<Part Number>R24605% R0402-0201<Part Number>
R25533.21% R0402-0201<Part Number>R25033.21% R0402-0201<Part Number>R24933.21% R0402-0201<Part Number>U3174LVC1G08GV12453Q5BDMN53D0LDW-7<Part Number>D23G25S24
R24733.21% R0402-0201<Part Number>R25233.21% R0402-0201<Part Number>C40020.1UF25V10%C0402-0201X7R
R25410K1%R0402-0201<Part Number>
R24405% R0402-0201<Part Number>
C9190.1UFX6SC0402-020110%25V<Part Number>
R24305% R0402-0201<Part Number>R25133.21% R0402-0201<Part Number>U29BSS138K<Part Number>GDSU32DS1818-5<Part Number>RST#1VCC2GND3 Q5ADMN53D0LDW-7<Part Number>S11G12D16C9170.1UFX6SC0402-020110%25V<Part Number>R24505% R0402-0201<Part Number>U30SN74LVC1G17DCKR<Part Number>24531 PRSNT_NIC4_R_NHP_NIC4_ENPRSNT_NIC4_R_NRST_NIC4_PERST0_R_NRST_HP_NIC4_BUF_NRST_NIC4_PERST1_R_NRST_HP_NIC4_NHP_NIC4_PWRGDHP_NIC4_PWRGD_RHP_NIC4_PWRGD_RRST_HP_NIC4_NRST_NIC4_PERST_R_N
PRSNTB0_NIC4_NPRSNTB1_NIC4_NPRSNTB2_NIC4_NPRSNTB3_NIC4_NRST_NIC4_PERST2_R_NRST_NIC4_PERST3_R_NPRSNT_NIC4_N
HP_NIC4_HSC_PWRGD_N



5
5
4
4
3
3
2
2
1
1
D D
C C
B B
A A
PRIMARY CONNECTOR
NIC_5_J25(1/3)
PVT_CHANGENIC5_DATA_IN[183]NIC5_DATA_OUT[183]NIC5_CLK[183]PWRGD_NIC5_PWR_GOOD[183]NIC5_MAIN_PWR_EN_R[183]NIC5_LD_N[183]NIC5_SLOT_ID0[184]NCSI_NIC5_RXD1[183]NCSI_NIC5_RXD0[183]NCSI_NIC5_CRS_DV[183]CLK_50M_NIC5_RBT_REF [183]NIC5_RBT_ARB_OUT [183]NIC5_SLOT_ID1 [184]NCSI_NIC5_TX_EN [183]NCSI_NIC5_TXD1 [183]NCSI_NIC5_TXD0 [183]NIC5_MAIN_PWR_EN[116,183]NIC5_MAIN_PWR_EN_R [183]NIC5_AUX_PWR_EN[116,183]NIC5_AUX_PWR_EN_R [183,184]NIC5_BIF0_N[184]NIC5_BIF1_N[184]NIC5_BIF2_N[184]RST_NIC5_PERST0_R_N[185]PRSNTB0_NIC5_N [183,185]PRSNTB0_NIC5_N[183,185]PRSNTB3_NIC5_N[183,185]PRSNTB1_NIC5_N [183,185]PRSNTB2_NIC5_N [183,185]PRSNTB1_NIC5_N [183,185]PRSNTB2_NIC5_N [183,185]PRSNTB3_NIC5_N [183,185]NIC5_AUX_PWR_EN_R[183,184]NIC5_RBT_ARB_IN [183]RST_SMB_NIC5_MUX_ISO_R_N [184]RST_NIC5_PERST1_R_N [185]RST_NIC5_PERST2_R_N [185]RST_NIC5_PERST3_R_N [185]NIC5_RBT_ARB_IN[183]NIC5_RBT_ARB_OUT [183]
NCSI_NIC5_CRS_DV [183]NCSI_NIC5_RXD0 [183]NCSI_NIC5_RXD1 [183]NCSI_NIC5_TXD0 [183]NCSI_NIC5_TXD1 [183]CLK_50M_NIC5_RBT_REF [183]NCSI_NIC5_TX_EN [183]PWRGD_NIC5_PWR_GOOD [183]NIC5_MAIN_PWR_EN [116,183]NIC5_AUX_PWR_EN [116,183]NIC5_LD_N [183]NIC5_DATA_IN [183]NIC5_DATA_OUT [183]PWRGD_NIC5_PWR_GOOD_R[116]PWRGD_NIC5_PWR_GOOD [183]
NIC5_PWRBRK_R_N [192]NIC5_CLK [183]P5E_PEX2_STN0_TX_C_DN<0>[36]P5E_PEX2_STN0_RX_DN<0> [36]P5E_PEX2_STN0_TX_C_DP<0>[36]P5E_PEX2_STN0_RX_DP<0> [36]P5E_PEX2_STN0_TX_C_DN<1>[36]P5E_PEX2_STN0_RX_DN<1> [36]P5E_PEX2_STN0_TX_C_DP<1>[36]P5E_PEX2_STN0_RX_DP<1> [36]P5E_PEX2_STN0_TX_C_DN<2>[36]P5E_PEX2_STN0_RX_DN<2> [36]P5E_PEX2_STN0_TX_C_DP<2>[36]P5E_PEX2_STN0_RX_DP<2> [36]P5E_PEX2_STN0_TX_C_DN<3>[36]P5E_PEX2_STN0_RX_DN<3> [36]P5E_PEX2_STN0_TX_C_DP<3>[36]P5E_PEX2_STN0_RX_DP<3> [36]P5E_PEX2_STN0_TX_C_DN<4>[36]P5E_PEX2_STN0_RX_DN<4> [36]P5E_PEX2_STN0_TX_C_DP<4>[36]P5E_PEX2_STN0_RX_DP<4> [36]P5E_PEX2_STN0_TX_C_DN<5>[36]P5E_PEX2_STN0_RX_DN<5> [36]P5E_PEX2_STN0_TX_C_DP<5>[36]P5E_PEX2_STN0_RX_DP<5> [36]P5E_PEX2_STN0_TX_C_DN<6>[36]P5E_PEX2_STN0_RX_DN<6> [36]P5E_PEX2_STN0_TX_C_DP<6>[36]P5E_PEX2_STN0_RX_DP<6> [36]P5E_PEX2_STN0_TX_C_DN<7>[36]P5E_PEX2_STN0_RX_DN<7> [36]P5E_PEX2_STN0_TX_C_DP<7>[36]P5E_PEX2_STN0_RX_DP<7> [36]P5E_PEX2_STN0_TX_C_DN<8>[36]P5E_PEX2_STN0_RX_DN<8> [36]P5E_PEX2_STN0_TX_C_DP<8>[36]P5E_PEX2_STN0_RX_DP<8> [36]P5E_PEX2_STN0_TX_C_DN<9>[36]P5E_PEX2_STN0_RX_DN<9> [36]P5E_PEX2_STN0_TX_C_DP<9>[36]P5E_PEX2_STN0_RX_DP<9> [36]P5E_PEX2_STN0_TX_C_DN<10>[36]P5E_PEX2_STN0_RX_DN<10> [36]P5E_PEX2_STN0_TX_C_DP<10>[36]P5E_PEX2_STN0_RX_DP<10> [36]P5E_PEX2_STN0_TX_C_DN<11>[36]P5E_PEX2_STN0_RX_DN<11> [36]P5E_PEX2_STN0_TX_C_DP<11>[36]P5E_PEX2_STN0_RX_DP<11> [36]P5E_PEX2_STN0_TX_C_DP<12>[36]P5E_PEX2_STN0_RX_DN<12> [36]P5E_PEX2_STN0_TX_C_DN<12>[36]P5E_PEX2_STN0_RX_DP<12> [36]P5E_PEX2_STN0_TX_C_DN<13>[36]P5E_PEX2_STN0_RX_DN<13> [36]P5E_PEX2_STN0_TX_C_DP<13>[36]P5E_PEX2_STN0_RX_DP<13> [36]P5E_PEX2_STN0_TX_C_DP<14>[36]P5E_PEX2_STN0_RX_DN<14> [36]P5E_PEX2_STN0_TX_C_DN<14>[36]P5E_PEX2_STN0_RX_DP<14> [36]P5E_PEX2_STN0_TX_C_DN<15>[36]P5E_PEX2_STN0_RX_DN<15> [36]P5E_PEX2_STN0_TX_C_DP<15>[36]P5E_PEX2_STN0_RX_DP<15> [36]SMB_NIC5_LS_SCL [94,183]SMB_NIC5_LS_SDA [94,183]SMB_NIC5_LS_SCL [94,183]SMB_NIC5_LS_SDA [94,183]CLK_100M_DB2000QL_NIC5_R_DN[79]CLK_100M_DB2000QL_NIC5_R_DP[79]
P12V_NIC5P3V3_NIC5P12V_NIC5P3V3_NIC5P3V3_AUXP3V3_NIC5
SizeDoc NumberRevDate: SheetofReviewerDesignerDepartmentProject
Page TitleCCBU D183 257Tuesday, August 29, 2023<project_name><Designer> GRANDTETON_SWB_20230829183 NIC_5_J25(1/3)<Reviewer>SizeDoc NumberRevDate: SheetofReviewerDesignerDepartmentProject
Page TitleCCBU D183 257Tuesday, August 29, 2023<project_name><Designer> GRANDTETON_SWB_20230829183 NIC_5_J25(1/3)<Reviewer>SizeDoc NumberRevDate: SheetofReviewerDesignerDepartmentProject
Page TitleCCBU D183 257Tuesday, August 29, 2023<project_name><Designer> GRANDTETON_SWB_20230829183 NIC_5_J25(1/3)<Reviewer>R275100K1% R0402-0201<Part Number>R2681K1% R0402-0201<Part Number>C9280.1UFX6SC0402-020110%25V<Part Number>R25905% R0402-0201<Part Number>R25605% R0402-0201<Part Number>C9270.1UFX6SC0402-020110%25V<Part Number>C9290.1UFX6SC0402-020110%25V<Part Number>R2643.3K1%R0402-0201R269100K1% R0402-0201<Part Number>
C92022UFX6SC0805_H5720%16V<Part Number>
R271100K1% R0402-0201<Part Number>R2653.3K1%R0402-0201R2601K1% R0402-0201<Part Number>C9250.1UFX6SC020110%16V<Part Number>
R276100K1% R0402-0201<Part Number>
C9240.1UFX6SC020110%16V<Part Number>C92122UFX6SC0805_H5720%16V<Part Number>
R26710K1% R0402-0201<Part Number>R274100K1% R0402-0201<Part Number>R27910K1% R0402-0201<Part Number>R2661K1% R0402-0201<Part Number>R25705% R0402-0201<Part Number>C9220.1UFX6SC020110%16V<Part Number>C9230.1UFX6SC020110%16V<Part Number>
R27810K1% R0402-0201<Part Number>KEYKEYKEYSCONN168_G64V35313HR
J25
<Part Number>
NIC_PWR_GOODOB1MAIN_PWR_ENOB2LD#OB3DATA_INOB4DATA_OUTOB5CLKOB6SLOT_ID0OB7RBT_RXD1OB8RBT_RXD0OB9GND_OB10OB10REFCLKn2OB11REFCLKp2OB12GND_OB13OB13RBT_CRS_DVOB14+12V_EDGE_B1B1+12V_EDGE_B2B2+12V_EDGE_B3B3+12V_EDGE_B4B4+12V_EDGE_B5B5+12V_EDGE_B6B6BIF0#B7BIF1#B8BIF2#B9PERST0#B10+3.3V_EDGEB11AUX_PWR_ENB12GND_B13B13REFCLKn0B14REFCLKp0B15GND_B16B16PETn0B17PETp0B18GND_B19B19PETn1B20PETp1B21GND_B22B22PETn2B23PETp2B24GND_B25B25PETn3B26PETp3B27GND_B28B28GND_B29B29PETn4B30PETp4B31GND_B32B32PETn5B33PETp5B34GND_B35B35PETn6B36PETp6B37GND_B38B38PETn7B39PETp7B40GND_B41B41PRSNTB0#B42GND_B43B43PETn8B44PETp8B45GND_B46B46PETn9B47PETp9B48GND_B49B49PETn10B50PETp10B51GND_B52B52PETn11B53PETp11B54GND_B55B55PETn12B56
PERST2#OA1PERST3#OA2WAKE#OA3RBT_ARB_INOA4RBT_ARB_OUTOA5SLOT_ID1OA6RBT_TX_ENOA7RBT_TXD1OA8RBT_TXD0OA9GND_OA10OA10REFCLKn3OA11REFCLKp3OA12GND_OA13OA13RBT_CLK_INOA14GND_A1A1GND_A2A2GND_A3A3GND_A4A4GND_A5A5GND_A6A6SMCLKA7SMDATA8SMRST#A9PRSNTA#A10PERST1#A11PRSNTB2#A12GND_A13A13REFCLKn1A14REFCLKp1A15GND_A16A16PERn0A17PERp0A18GND_A19A19PERn1A20PERp1A21GND_A22A22PERn2A23PERp2A24GND_A25A25PERn3A26PERp3A27GND_A28A28GND_A29A29PERn4A30PERp4A31GND_A32A32PERn5A33PERp5A34GND_A35A35PERn6A36PERp6A37GND_A38A38PERn7A39PERp7A40GND_A41A41PRSNTB1#A42GND_A43A43PERn8A44PERp8A45GND_A46A46PERn9A47PERp9A48GND_A49A49PERn10A50PERp10A51GND_A52A52PERn11A53PERp11A54GND_A55A55PERn12A56PERp12A57GND_A58A58PERn13A59PERp13A60GND_A61A61PERn14A62PERp14A63GND_A64A64PERn15A65PERp15A66GND_A67A67USB_DATnA68USB_DATpA69PWRBRK0#A70PETp12B57GND_B58B58PETn13B59PETp13B60GND_B61B61PETn14B62PETp14B63GND_B64B64PETn15B65PETp15B66GND_B67B67RFU1_NCB68RFU2_NCB69PRSNTB3#B70G1G1G2G2G3G3G4G4G5G5G6G6G7G7G8G8G9G9
R2631K1% R0402-0201<Part Number>R2611K1% R0402-0201<Part Number>R270100K1% R0402-0201<Part Number>R25805% R0402-0201<Part Number>
R272100K1% R0402-0201<Part Number>
C9300.1UFX6SC0402-020110%25V<Part Number>R2621K1% R0402-0201<Part Number>R273100K1% R0402-0201<Part Number>R277100K1% R0402-0201<Part Number>
C9260.1UFX6SC020110%16V<Part Number>PWRGD_NIC5_PWR_GOODNIC5_MAIN_PWR_EN_RNIC5_LD_NNIC5_DATA_INNIC5_DATA_OUTNIC5_CLKNIC5_SLOT_ID0NCSI_NIC5_RXD1NCSI_NIC5_RXD0NCSI_NIC5_CRS_DVCLK_50M_NIC5_RBT_REFNIC5_RBT_ARB_OUTNIC5_SLOT_ID1NCSI_NIC5_TX_ENNCSI_NIC5_TXD1NCSI_NIC5_TXD0NIC5_RBT_ARB_INNIC5_MAIN_PWR_ENNIC5_MAIN_PWR_EN_RNIC5_AUX_PWR_ENNIC5_AUX_PWR_EN_RNIC5_BIF0_NNIC5_BIF1_NNIC5_BIF2_NPRSNTB3_NIC5_NPRSNTB0_NIC5_NPRSNTB1_NIC5_NPRSNTB2_NIC5_NRST_NIC5_PERST0_R_NPRSNTB0_NIC5_NPRSNTB1_NIC5_NPRSNTB2_NIC5_NPRSNTB3_NIC5_NNIC5_AUX_PWR_EN_RRST_NIC5_PERST1_R_NRST_NIC5_PERST2_R_NRST_NIC5_PERST3_R_NNIC5_RBT_ARB_INNIC5_RBT_ARB_OUT
NCSI_NIC5_CRS_DVNCSI_NIC5_RXD0NCSI_NIC5_RXD1NCSI_NIC5_TXD0NCSI_NIC5_TXD1CLK_50M_NIC5_RBT_REFNCSI_NIC5_TX_ENPWRGD_NIC5_PWR_GOODNIC5_MAIN_PWR_ENNIC5_AUX_PWR_ENNIC5_LD_NNIC5_DATA_INNIC5_DATA_OUTNIC5_PWRBRK_R_N
PWRGD_NIC5_PWR_GOOD_RPWRGD_NIC5_PWR_GOODNIC5_CLKP5E_PEX2_STN0_TX_C_DN<0>P5E_PEX2_STN0_RX_DN<0>P5E_PEX2_STN0_TX_C_DP<0>P5E_PEX2_STN0_RX_DP<0>P5E_PEX2_STN0_TX_C_DN<1>P5E_PEX2_STN0_RX_DN<1>P5E_PEX2_STN0_TX_C_DP<1>P5E_PEX2_STN0_RX_DP<1>P5E_PEX2_STN0_TX_C_DN<2>P5E_PEX2_STN0_RX_DN<2>P5E_PEX2_STN0_TX_C_DP<2>P5E_PEX2_STN0_RX_DP<2>P5E_PEX2_STN0_TX_C_DN<3>P5E_PEX2_STN0_RX_DN<3>P5E_PEX2_STN0_TX_C_DP<3>P5E_PEX2_STN0_RX_DP<3>P5E_PEX2_STN0_TX_C_DN<4>P5E_PEX2_STN0_RX_DN<4>P5E_PEX2_STN0_TX_C_DP<4>P5E_PEX2_STN0_RX_DP<4>P5E_PEX2_STN0_TX_C_DN<5>P5E_PEX2_STN0_RX_DN<5>P5E_PEX2_STN0_TX_C_DP<5>P5E_PEX2_STN0_RX_DP<5>P5E_PEX2_STN0_TX_C_DN<6>P5E_PEX2_STN0_RX_DN<6>P5E_PEX2_STN0_TX_C_DP<6>P5E_PEX2_STN0_RX_DP<6>P5E_PEX2_STN0_TX_C_DN<7>P5E_PEX2_STN0_RX_DN<7>P5E_PEX2_STN0_TX_C_DP<7>P5E_PEX2_STN0_RX_DP<7>P5E_PEX2_STN0_TX_C_DN<8>P5E_PEX2_STN0_RX_DN<8>P5E_PEX2_STN0_TX_C_DP<8>P5E_PEX2_STN0_RX_DP<8>P5E_PEX2_STN0_TX_C_DN<9>P5E_PEX2_STN0_RX_DN<9>P5E_PEX2_STN0_TX_C_DP<9>P5E_PEX2_STN0_RX_DP<9>P5E_PEX2_STN0_TX_C_DN<10>P5E_PEX2_STN0_RX_DN<10>P5E_PEX2_STN0_TX_C_DP<10>P5E_PEX2_STN0_RX_DP<10>P5E_PEX2_STN0_TX_C_DN<11>P5E_PEX2_STN0_RX_DN<11>P5E_PEX2_STN0_TX_C_DP<11>P5E_PEX2_STN0_RX_DP<11>P5E_PEX2_STN0_TX_C_DP<12>P5E_PEX2_STN0_RX_DN<12>P5E_PEX2_STN0_TX_C_DN<12>P5E_PEX2_STN0_RX_DP<12>P5E_PEX2_STN0_TX_C_DN<13>P5E_PEX2_STN0_RX_DN<13>P5E_PEX2_STN0_TX_C_DP<13>P5E_PEX2_STN0_RX_DP<13>P5E_PEX2_STN0_TX_C_DP<14>P5E_PEX2_STN0_RX_DN<14>P5E_PEX2_STN0_TX_C_DN<14>P5E_PEX2_STN0_RX_DP<14>P5E_PEX2_STN0_TX_C_DN<15>P5E_PEX2_STN0_RX_DN<15>P5E_PEX2_STN0_TX_C_DP<15>P5E_PEX2_STN0_RX_DP<15>SMB_NIC5_LS_SCLSMB_NIC5_LS_SDARST_SMB_NIC5_MUX_ISO_R_NCLK_100M_DB2000QL_NIC5_R_DNSMB_NIC5_LS_SCLCLK_100M_DB2000QL_NIC5_R_DPSMB_NIC5_LS_SDA



5
5
4
4
3
3
2
2
1
1
D D
C C
B B
A A
NIC_5_J25(2/3)
RST_SMB_NIC_MUX_R_N[87,169,172,175,178,181,187,190]NIC5_AUX_PWR_EN_R[183]RST_SMB_NIC5_MUX_ISO_R_N [183]
NIC5_BIF0_N [183]NIC5_BIF1_N [183]NIC5_BIF2_N [183]NIC5_SLOT_ID0 [183]NIC5_SLOT_ID1 [183]
P3V3_AUXP3V3_AUXP3V3_AUXP3V3_AUXP3V3_NIC5P3V3_NIC5
P3V3_NIC5SizeDoc NumberRevDate: SheetofReviewerDesignerDepartmentProject
Page TitleCCBU D184 257Tuesday, August 29, 2023<project_name><Designer> GRANDTETON_SWB_20230829184 NIC_5_J25(2/3)<Reviewer>SizeDoc NumberRevDate: SheetofReviewerDesignerDepartmentProject
Page TitleCCBU D184 257Tuesday, August 29, 2023<project_name><Designer> GRANDTETON_SWB_20230829184 NIC_5_J25(2/3)<Reviewer>SizeDoc NumberRevDate: SheetofReviewerDesignerDepartmentProject
Page TitleCCBU D184 257Tuesday, August 29, 2023<project_name><Designer> GRANDTETON_SWB_20230829184 NIC_5_J25(2/3)<Reviewer>R291 33 R0402-02011%3 state outputU3374HC1G126GW<Part Number>24513
R284100K1% R0402-0201<Part Number>NIR28705% R0402-0201<Part Number>R293100K1%R0402-0201<Part Number>
R28505% R0402-0201<Part Number>R2824.7K1% R0402-0201<Part Number>NI
C9310.1UFX6SC0402-020110%25V<Part Number>R286100K1% R0402-0201<Part Number>NIR2904.75KR0402-02011%NI
R2804.7K1% R0402-0201<Part Number>NIR288100K1% R0402-0201<Part Number>NIR2831001% R0402-0201<Part Number>R28905% R0402-0201<Part Number>R2811001% R0402-0201<Part Number>
R29205% R0402-0201<Part Number>RST_SMB_NIC5_MUX_ISO_R_NRST_SMB_NIC5_MUX_ISO_NRST_SMB_NIC5_MUX_NNIC5_AUX_PWR_EN_RNIC5_BIF0_NNIC5_BIF1_NNIC5_BIF2_NNIC5_SLOT_ID0NIC5_SLOT_ID1



5
5
4
4
3
3
2
2
1
1
D D
C C
B B
A A
NIC_5_J25(3/3)
PRSNT_NIC5_R_N [86,116,185]HP_NIC5_EN [235,238,243,249]PRSNT_NIC5_R_N[86,116,185]RST_NIC5_PERST0_R_N [183]RST_NIC5_PERST1_R_N [183]RST_HP_NIC5_N[185]HP_NIC5_PWRGD_R [185]HP_NIC5_PWRGD_R[185]RST_HP_NIC5_N [185]RST_NIC5_PERST_R_N[116]
PRSNTB0_NIC5_N[183]PRSNTB1_NIC5_N[183]PRSNTB2_NIC5_N[183]PRSNTB3_NIC5_N[183]RST_NIC5_PERST2_R_N [183]RST_NIC5_PERST3_R_N [183]PWRGD_P12V_NIC5_R[116,235,243]
P3V3_AUXP3V3_AUXP3V3_NIC5P3V3_AUXP3V3_NIC5P3V3_AUXSizeDoc NumberRevDate: SheetofReviewerDesignerDepartmentProject
Page TitleCCBU D185 257Tuesday, August 29, 2023<project_name><Designer> GRANDTETON_SWB_20230829185 NIC_5_J25(3/3)<Reviewer>SizeDoc NumberRevDate: SheetofReviewerDesignerDepartmentProject
Page TitleCCBU D185 257Tuesday, August 29, 2023<project_name><Designer> GRANDTETON_SWB_20230829185 NIC_5_J25(3/3)<Reviewer>SizeDoc NumberRevDate: SheetofReviewerDesignerDepartmentProject
Page TitleCCBU D185 257Tuesday, August 29, 2023<project_name><Designer> GRANDTETON_SWB_20230829185 NIC_5_J25(3/3)<Reviewer>
R29505% R0402-0201<Part Number>R29833.21% R0402-0201<Part Number>R30033.21% R0402-0201<Part Number>U35SN74LVC1G17DCKR<Part Number>24531R30233.21% R0402-0201<Part Number>Q6ADMN53D0LDW-7<Part Number>S11G12D16R30333.21% R0402-0201<Part Number>C9330.1UFX6SC0402-020110%25V<Part Number>U3674LVC1G08GV12453C9320.1UFX6SC0402-020110%25V<Part Number>C9340.1UFX6SC0402-020110%25V<Part Number>
U34BSS138K<Part Number>GDS
Q6BDMN53D0LDW-7<Part Number>D23G25S24R30133.21% R0402-0201<Part Number>C40030.1UF25V10%C0402-0201X7RR29705% R0402-0201<Part Number>R2991K1%R0402-0201<Part Number>
U37DS1818-5<Part Number>RST#1VCC2GND3
R29405% R0402-0201<Part Number>R29605% R0402-0201<Part Number>
R30633.21% R0402-0201<Part Number>R3041K1%R0402-0201<Part Number>R30510K1%R0402-0201<Part Number>
PRSNT_NIC5_R_NHP_NIC5_ENPRSNT_NIC5_R_NRST_NIC5_PERST0_R_NRST_HP_NIC5_BUF_NRST_NIC5_PERST1_R_NRST_HP_NIC5_NHP_NIC5_PWRGDHP_NIC5_PWRGD_RHP_NIC5_PWRGD_RRST_HP_NIC5_NRST_NIC5_PERST_R_N
PRSNTB0_NIC5_NPRSNTB1_NIC5_NPRSNTB2_NIC5_NPRSNTB3_NIC5_NRST_NIC5_PERST2_R_NRST_NIC5_PERST3_R_NPRSNT_NIC5_N
HP_NIC5_HSC_PWRGD_N



5
5
4
4
3
3
2
2
1
1
D D
C C
B B
A A
PRIMARY CONNECTOR
NIC_6_J26(1/3)
LANE REVERSAL
PVT_CHANGENIC6_DATA_IN[186]NIC6_DATA_OUT[186]NIC6_CLK[186]PWRGD_NIC6_PWR_GOOD[186]NIC6_MAIN_PWR_EN_R[186]NIC6_LD_N[186]NIC6_SLOT_ID0[187]NCSI_NIC6_RXD1[186]NCSI_NIC6_RXD0[186]NCSI_NIC6_CRS_DV[186]CLK_50M_NIC6_RBT_REF [186]NIC6_RBT_ARB_OUT [186]NIC6_SLOT_ID1 [187]NCSI_NIC6_TX_EN [186]NCSI_NIC6_TXD1 [186]NCSI_NIC6_TXD0 [186]NIC6_MAIN_PWR_EN[116,186]NIC6_MAIN_PWR_EN_R [186]NIC6_AUX_PWR_EN[116,186]NIC6_AUX_PWR_EN_R [186,187]NIC6_BIF0_N[187]NIC6_BIF1_N[187]NIC6_BIF2_N[187]RST_NIC6_PERST0_R_N[188]PRSNTB0_NIC6_N [186,188]PRSNTB0_NIC6_N[186,188]PRSNTB3_NIC6_N[186,188]PRSNTB1_NIC6_N [186,188]PRSNTB2_NIC6_N [186,188]PRSNTB1_NIC6_N [186,188]PRSNTB2_NIC6_N [186,188]PRSNTB3_NIC6_N [186,188]NIC6_AUX_PWR_EN_R[186,187]NIC6_RBT_ARB_IN [186]RST_SMB_NIC6_MUX_ISO_R_N [187]RST_NIC6_PERST1_R_N [188]RST_NIC6_PERST2_R_N [188]RST_NIC6_PERST3_R_N [188]NIC6_RBT_ARB_IN[186]NIC6_RBT_ARB_OUT [186]
NCSI_NIC6_CRS_DV [186]NCSI_NIC6_RXD0 [186]NCSI_NIC6_RXD1 [186]NCSI_NIC6_TXD0 [186]NCSI_NIC6_TXD1 [186]CLK_50M_NIC6_RBT_REF [186]NCSI_NIC6_TX_EN [186]PWRGD_NIC6_PWR_GOOD [186]NIC6_MAIN_PWR_EN [116,186]NIC6_AUX_PWR_EN [116,186]NIC6_LD_N [186]NIC6_DATA_IN [186]NIC6_DATA_OUT [186]PWRGD_NIC6_PWR_GOOD_R[116]PWRGD_NIC6_PWR_GOOD [186]
NIC6_PWRBRK_R_N [192]NIC6_CLK [186]P5E_PEX3_STN1_TX_C_DP<31>[49]P5E_PEX3_STN1_RX_DN<31> [49]P5E_PEX3_STN1_TX_C_DN<31>[49]P5E_PEX3_STN1_RX_DP<31> [49]P5E_PEX3_STN1_TX_C_DN<30>[49]P5E_PEX3_STN1_RX_DN<30> [49]P5E_PEX3_STN1_TX_C_DP<30>[49]P5E_PEX3_STN1_RX_DP<30> [49]P5E_PEX3_STN1_TX_C_DP<29>[49]P5E_PEX3_STN1_RX_DN<29> [49]P5E_PEX3_STN1_TX_C_DN<29>[49]P5E_PEX3_STN1_RX_DP<29> [49]P5E_PEX3_STN1_TX_C_DN<28>[49]P5E_PEX3_STN1_RX_DN<28> [49]P5E_PEX3_STN1_TX_C_DP<28>[49]P5E_PEX3_STN1_RX_DP<28> [49]P5E_PEX3_STN1_TX_C_DP<27>[49]P5E_PEX3_STN1_RX_DN<27> [49]P5E_PEX3_STN1_TX_C_DN<27>[49]P5E_PEX3_STN1_RX_DP<27> [49]P5E_PEX3_STN1_TX_C_DN<26>[49]P5E_PEX3_STN1_RX_DN<26> [49]P5E_PEX3_STN1_TX_C_DP<26>[49]P5E_PEX3_STN1_RX_DP<26> [49]P5E_PEX3_STN1_TX_C_DP<25>[49]P5E_PEX3_STN1_RX_DN<25> [49]P5E_PEX3_STN1_TX_C_DN<25>[49]P5E_PEX3_STN1_RX_DP<25> [49]P5E_PEX3_STN1_TX_C_DN<24>[49]P5E_PEX3_STN1_RX_DN<24> [49]P5E_PEX3_STN1_TX_C_DP<24>[49]P5E_PEX3_STN1_RX_DP<24> [49]P5E_PEX3_STN1_TX_C_DP<23>[49]P5E_PEX3_STN1_RX_DN<23> [49]P5E_PEX3_STN1_TX_C_DN<23>[49]P5E_PEX3_STN1_RX_DP<23> [49]P5E_PEX3_STN1_TX_C_DN<22>[49]P5E_PEX3_STN1_RX_DN<22> [49]P5E_PEX3_STN1_TX_C_DP<22>[49]P5E_PEX3_STN1_RX_DP<22> [49]P5E_PEX3_STN1_TX_C_DP<21>[49]P5E_PEX3_STN1_RX_DN<21> [49]P5E_PEX3_STN1_TX_C_DN<21>[49]P5E_PEX3_STN1_RX_DP<21> [49]P5E_PEX3_STN1_TX_C_DN<20>[49]P5E_PEX3_STN1_RX_DN<20> [49]P5E_PEX3_STN1_TX_C_DP<20>[49]P5E_PEX3_STN1_RX_DP<20> [49]P5E_PEX3_STN1_TX_C_DP<19>[49]P5E_PEX3_STN1_RX_DN<19> [49]P5E_PEX3_STN1_TX_C_DN<19>[49]P5E_PEX3_STN1_RX_DP<19> [49]P5E_PEX3_STN1_TX_C_DN<18>[49]P5E_PEX3_STN1_RX_DN<18> [49]P5E_PEX3_STN1_TX_C_DP<18>[49]P5E_PEX3_STN1_RX_DP<18> [49]P5E_PEX3_STN1_TX_C_DP<17>[49]P5E_PEX3_STN1_RX_DN<17> [49]P5E_PEX3_STN1_TX_C_DN<17>[49]P5E_PEX3_STN1_RX_DP<17> [49]P5E_PEX3_STN1_TX_C_DN<16>[49]P5E_PEX3_STN1_RX_DN<16> [49]P5E_PEX3_STN1_TX_C_DP<16>[49]P5E_PEX3_STN1_RX_DP<16> [49]SMB_NIC6_LS_SCL [94,186]SMB_NIC6_LS_SDA [94,186]SMB_NIC6_LS_SCL [94,186]SMB_NIC6_LS_SDA [94,186]CLK_100M_DB2000QL_NIC6_R_DN[79]CLK_100M_DB2000QL_NIC6_R_DP[79]
P12V_NIC6P3V3_NIC6P12V_NIC6P3V3_NIC6P3V3_AUXP3V3_NIC6
SizeDoc NumberRevDate: SheetofReviewerDesignerDepartmentProject
Page TitleCCBU D186 257Tuesday, August 29, 2023<project_name><Designer> GRANDTETON_SWB_20230829186 NIC_6_J26(1/3)<Reviewer>SizeDoc NumberRevDate: SheetofReviewerDesignerDepartmentProject
Page TitleCCBU D186 257Tuesday, August 29, 2023<project_name><Designer> GRANDTETON_SWB_20230829186 NIC_6_J26(1/3)<Reviewer>SizeDoc NumberRevDate: SheetofReviewerDesignerDepartmentProject
Page TitleCCBU D186 257Tuesday, August 29, 2023<project_name><Designer> GRANDTETON_SWB_20230829186 NIC_6_J26(1/3)<Reviewer>
C9400.1UFX6SC020110%16V<Part Number>
R31810K1% R0402-0201<Part Number>R324100K1% R0402-0201<Part Number>R3171K1% R0402-0201<Part Number>
C9370.1UFX6SC020110%16V<Part Number>C9380.1UFX6SC020110%16V<Part Number>
R32910K1% R0402-0201<Part Number>KEYKEYKEYSCONN168_G64V35313HR
J26
<Part Number>
NIC_PWR_GOODOB1MAIN_PWR_ENOB2LD#OB3DATA_INOB4DATA_OUTOB5CLKOB6SLOT_ID0OB7RBT_RXD1OB8RBT_RXD0OB9GND_OB10OB10REFCLKn2OB11REFCLKp2OB12GND_OB13OB13RBT_CRS_DVOB14+12V_EDGE_B1B1+12V_EDGE_B2B2+12V_EDGE_B3B3+12V_EDGE_B4B4+12V_EDGE_B5B5+12V_EDGE_B6B6BIF0#B7BIF1#B8BIF2#B9PERST0#B10+3.3V_EDGEB11AUX_PWR_ENB12GND_B13B13REFCLKn0B14REFCLKp0B15GND_B16B16PETn0B17PETp0B18GND_B19B19PETn1B20PETp1B21GND_B22B22PETn2B23PETp2B24GND_B25B25PETn3B26PETp3B27GND_B28B28GND_B29B29PETn4B30PETp4B31GND_B32B32PETn5B33PETp5B34GND_B35B35PETn6B36PETp6B37GND_B38B38PETn7B39PETp7B40GND_B41B41PRSNTB0#B42GND_B43B43PETn8B44PETp8B45GND_B46B46PETn9B47PETp9B48GND_B49B49PETn10B50PETp10B51GND_B52B52PETn11B53PETp11B54GND_B55B55PETn12B56
PERST2#OA1PERST3#OA2WAKE#OA3RBT_ARB_INOA4RBT_ARB_OUTOA5SLOT_ID1OA6RBT_TX_ENOA7RBT_TXD1OA8RBT_TXD0OA9GND_OA10OA10REFCLKn3OA11REFCLKp3OA12GND_OA13OA13RBT_CLK_INOA14GND_A1A1GND_A2A2GND_A3A3GND_A4A4GND_A5A5GND_A6A6SMCLKA7SMDATA8SMRST#A9PRSNTA#A10PERST1#A11PRSNTB2#A12GND_A13A13REFCLKn1A14REFCLKp1A15GND_A16A16PERn0A17PERp0A18GND_A19A19PERn1A20PERp1A21GND_A22A22PERn2A23PERp2A24GND_A25A25PERn3A26PERp3A27GND_A28A28GND_A29A29PERn4A30PERp4A31GND_A32A32PERn5A33PERp5A34GND_A35A35PERn6A36PERp6A37GND_A38A38PERn7A39PERp7A40GND_A41A41PRSNTB1#A42GND_A43A43PERn8A44PERp8A45GND_A46A46PERn9A47PERp9A48GND_A49A49PERn10A50PERp10A51GND_A52A52PERn11A53PERp11A54GND_A55A55PERn12A56PERp12A57GND_A58A58PERn13A59PERp13A60GND_A61A61PERn14A62PERp14A63GND_A64A64PERn15A65PERp15A66GND_A67A67USB_DATnA68USB_DATpA69PWRBRK0#A70PETp12B57GND_B58B58PETn13B59PETp13B60GND_B61B61PETn14B62PETp14B63GND_B64B64PETn15B65PETp15B66GND_B67B67RFU1_NCB68RFU2_NCB69PRSNTB3#B70G1G1G2G2G3G3G4G4G5G5G6G6G7G7G8G8G9G9R3191K1% R0402-0201<Part Number>R3111K1% R0402-0201<Part Number>C9440.1UFX6SC0402-020110%25V<Part Number>R30905% R0402-0201<Part Number>
R323100K1% R0402-0201<Part Number>
C9420.1UFX6SC0402-020110%25V<Part Number>C9430.1UFX6SC0402-020110%25V<Part Number>R3121K1% R0402-0201<Part Number>C9450.1UFX6SC0402-020110%25V<Part Number>
R328100K1% R0402-0201<Part Number>
C9410.1UFX6SC020110%16V<Part Number>C93522UFX6SC0805_H5720%16V<Part Number>
R326100K1% R0402-0201<Part Number>R3131K1% R0402-0201<Part Number>R31005% R0402-0201<Part Number>R30705% R0402-0201<Part Number>
R327100K1% R0402-0201<Part Number>
C93622UFX6SC0805_H5720%16V<Part Number>
R320100K1% R0402-0201<Part Number>R33010K1% R0402-0201<Part Number>
R30805% R0402-0201<Part Number>
R322100K1% R0402-0201<Part Number>R325100K1% R0402-0201<Part Number>R3153.3K1%R0402-0201R3141K1% R0402-0201<Part Number>R321100K1% R0402-0201<Part Number>
C9390.1UFX6SC020110%16V<Part Number>R3163.3K1%R0402-0201PWRGD_NIC6_PWR_GOODNIC6_MAIN_PWR_EN_RNIC6_LD_NNIC6_DATA_INNIC6_DATA_OUTNIC6_CLKNIC6_SLOT_ID0NCSI_NIC6_RXD1NCSI_NIC6_RXD0NCSI_NIC6_CRS_DVCLK_50M_NIC6_RBT_REFNIC6_RBT_ARB_OUTNIC6_SLOT_ID1NCSI_NIC6_TX_ENNCSI_NIC6_TXD1NCSI_NIC6_TXD0NIC6_RBT_ARB_INNIC6_MAIN_PWR_ENNIC6_MAIN_PWR_EN_RNIC6_AUX_PWR_ENNIC6_AUX_PWR_EN_RNIC6_BIF0_NNIC6_BIF1_NNIC6_BIF2_NPRSNTB3_NIC6_NPRSNTB0_NIC6_NPRSNTB1_NIC6_NPRSNTB2_NIC6_NRST_NIC6_PERST0_R_NPRSNTB0_NIC6_NPRSNTB1_NIC6_NPRSNTB2_NIC6_NPRSNTB3_NIC6_NNIC6_AUX_PWR_EN_RRST_NIC6_PERST1_R_NRST_NIC6_PERST2_R_NRST_NIC6_PERST3_R_NNIC6_RBT_ARB_INNIC6_RBT_ARB_OUT
NCSI_NIC6_CRS_DVNCSI_NIC6_RXD0NCSI_NIC6_RXD1NCSI_NIC6_TXD0NCSI_NIC6_TXD1CLK_50M_NIC6_RBT_REFNCSI_NIC6_TX_ENPWRGD_NIC6_PWR_GOODNIC6_MAIN_PWR_ENNIC6_AUX_PWR_ENNIC6_LD_NNIC6_DATA_INNIC6_DATA_OUTNIC6_PWRBRK_R_N
PWRGD_NIC6_PWR_GOOD_RPWRGD_NIC6_PWR_GOODNIC6_CLKP5E_PEX3_STN1_TX_C_DP<31>P5E_PEX3_STN1_RX_DN<31>P5E_PEX3_STN1_TX_C_DN<31>P5E_PEX3_STN1_RX_DP<31>P5E_PEX3_STN1_TX_C_DN<30>P5E_PEX3_STN1_RX_DN<30>P5E_PEX3_STN1_TX_C_DP<30>P5E_PEX3_STN1_RX_DP<30>P5E_PEX3_STN1_TX_C_DP<29>P5E_PEX3_STN1_RX_DN<29>P5E_PEX3_STN1_TX_C_DN<29>P5E_PEX3_STN1_RX_DP<29>P5E_PEX3_STN1_TX_C_DN<28>P5E_PEX3_STN1_RX_DN<28>P5E_PEX3_STN1_TX_C_DP<28>P5E_PEX3_STN1_RX_DP<28>P5E_PEX3_STN1_TX_C_DP<27>P5E_PEX3_STN1_RX_DN<27>P5E_PEX3_STN1_TX_C_DN<27>P5E_PEX3_STN1_RX_DP<27>P5E_PEX3_STN1_TX_C_DN<26>P5E_PEX3_STN1_RX_DN<26>P5E_PEX3_STN1_TX_C_DP<26>P5E_PEX3_STN1_RX_DP<26>P5E_PEX3_STN1_TX_C_DP<25>P5E_PEX3_STN1_RX_DN<25>P5E_PEX3_STN1_TX_C_DN<25>P5E_PEX3_STN1_RX_DP<25>P5E_PEX3_STN1_TX_C_DN<24>P5E_PEX3_STN1_RX_DN<24>P5E_PEX3_STN1_TX_C_DP<24>P5E_PEX3_STN1_RX_DP<24>P5E_PEX3_STN1_TX_C_DP<23>P5E_PEX3_STN1_RX_DN<23>P5E_PEX3_STN1_TX_C_DN<23>P5E_PEX3_STN1_RX_DP<23>P5E_PEX3_STN1_TX_C_DN<22>P5E_PEX3_STN1_RX_DN<22>P5E_PEX3_STN1_TX_C_DP<22>P5E_PEX3_STN1_RX_DP<22>P5E_PEX3_STN1_TX_C_DP<21>P5E_PEX3_STN1_RX_DN<21>P5E_PEX3_STN1_TX_C_DN<21>P5E_PEX3_STN1_RX_DP<21>P5E_PEX3_STN1_TX_C_DN<20>P5E_PEX3_STN1_RX_DN<20>P5E_PEX3_STN1_TX_C_DP<20>P5E_PEX3_STN1_RX_DP<20>P5E_PEX3_STN1_TX_C_DP<19>P5E_PEX3_STN1_RX_DN<19>P5E_PEX3_STN1_TX_C_DN<19>P5E_PEX3_STN1_RX_DP<19>P5E_PEX3_STN1_TX_C_DN<18>P5E_PEX3_STN1_RX_DN<18>P5E_PEX3_STN1_TX_C_DP<18>P5E_PEX3_STN1_RX_DP<18>P5E_PEX3_STN1_TX_C_DP<17>P5E_PEX3_STN1_RX_DN<17>P5E_PEX3_STN1_TX_C_DN<17>P5E_PEX3_STN1_RX_DP<17>P5E_PEX3_STN1_TX_C_DN<16>P5E_PEX3_STN1_RX_DN<16>P5E_PEX3_STN1_TX_C_DP<16>P5E_PEX3_STN1_RX_DP<16>SMB_NIC6_LS_SCLSMB_NIC6_LS_SDARST_SMB_NIC6_MUX_ISO_R_NCLK_100M_DB2000QL_NIC6_R_DNSMB_NIC6_LS_SCLCLK_100M_DB2000QL_NIC6_R_DPSMB_NIC6_LS_SDA



5
5
4
4
3
3
2
2
1
1
D D
C C
B B
A A
NIC_6_J26(2/3)
RST_SMB_NIC_MUX_R_N[87,169,172,175,178,181,184,190]NIC6_AUX_PWR_EN_R[186]RST_SMB_NIC6_MUX_ISO_R_N [186]
NIC6_BIF0_N [186]NIC6_BIF1_N [186]NIC6_BIF2_N [186]NIC6_SLOT_ID0 [186]NIC6_SLOT_ID1 [186]
P3V3_AUXP3V3_AUXP3V3_AUXP3V3_AUXP3V3_NIC6P3V3_NIC6
P3V3_NIC6SizeDoc NumberRevDate: SheetofReviewerDesignerDepartmentProject
Page TitleCCBU D187 257Tuesday, August 29, 2023<project_name><Designer> GRANDTETON_SWB_20230829187 NIC_6_J26(2/3)<Reviewer>SizeDoc NumberRevDate: SheetofReviewerDesignerDepartmentProject
Page TitleCCBU D187 257Tuesday, August 29, 2023<project_name><Designer> GRANDTETON_SWB_20230829187 NIC_6_J26(2/3)<Reviewer>SizeDoc NumberRevDate: SheetofReviewerDesignerDepartmentProject
Page TitleCCBU D187 257Tuesday, August 29, 2023<project_name><Designer> GRANDTETON_SWB_20230829187 NIC_6_J26(2/3)<Reviewer>
R337100K1% R0402-0201<Part Number>NIR339100K1% R0402-0201<Part Number>NIR3414.75KR0402-02011%NI
R3314.7K1% R0402-0201<Part Number>NIR34005% R0402-0201<Part Number>R3341001% R0402-0201<Part Number>
R34305% R0402-0201<Part Number>
R3321001% R0402-0201<Part Number>
3 state outputU3874HC1G126GW<Part Number>24513R342 33 R0402-02011%R33805% R0402-0201<Part Number>R335100K1% R0402-0201<Part Number>NIR3334.7K1% R0402-0201<Part Number>NI
R344100K1%R0402-0201<Part Number>
R33605% R0402-0201<Part Number>C9460.1UFX6SC0402-020110%25V<Part Number>RST_SMB_NIC6_MUX_ISO_R_NRST_SMB_NIC6_MUX_ISO_NRST_SMB_NIC6_MUX_NNIC6_AUX_PWR_EN_RNIC6_BIF0_NNIC6_BIF1_NNIC6_BIF2_NNIC6_SLOT_ID0NIC6_SLOT_ID1



5
5
4
4
3
3
2
2
1
1
D D
C C
B B
A A
NIC_6_J26(3/3)
PRSNT_NIC6_R_N [86,116,188]HP_NIC6_EN [235,238,243,249]PRSNT_NIC6_R_N[86,116,188]RST_NIC6_PERST0_R_N [186]RST_NIC6_PERST1_R_N [186]RST_HP_NIC6_N[188]HP_NIC6_PWRGD_R [188]HP_NIC6_PWRGD_R[188]RST_HP_NIC6_N [188]RST_NIC6_PERST_R_N[116]
PRSNTB0_NIC6_N[186]PRSNTB1_NIC6_N[186]PRSNTB2_NIC6_N[186]PRSNTB3_NIC6_N[186]RST_NIC6_PERST2_R_N [186]RST_NIC6_PERST3_R_N [186]PWRGD_P12V_NIC6_R[116,235,243]
P3V3_AUXP3V3_AUXP3V3_NIC6P3V3_AUXP3V3_NIC6P3V3_AUXSizeDoc NumberRevDate: SheetofReviewerDesignerDepartmentProject
Page TitleCCBU D188 257Tuesday, August 29, 2023<project_name><Designer> GRANDTETON_SWB_20230829188 NIC_6_J26(3/3)<Reviewer>SizeDoc NumberRevDate: SheetofReviewerDesignerDepartmentProject
Page TitleCCBU D188 257Tuesday, August 29, 2023<project_name><Designer> GRANDTETON_SWB_20230829188 NIC_6_J26(3/3)<Reviewer>SizeDoc NumberRevDate: SheetofReviewerDesignerDepartmentProject
Page TitleCCBU D188 257Tuesday, August 29, 2023<project_name><Designer> GRANDTETON_SWB_20230829188 NIC_6_J26(3/3)<Reviewer>Q7ADMN53D0LDW-7<Part Number>S11G12D16R35433.21% R0402-0201<Part Number>C9480.1UFX6SC0402-020110%25V<Part Number>U4174LVC1G08GV12453C9470.1UFX6SC0402-020110%25V<Part Number>C9490.1UFX6SC0402-020110%25V<Part Number>
U39BSS138K<Part Number>GDS
Q7BDMN53D0LDW-7<Part Number>D23G25S24R35233.21% R0402-0201<Part Number>R34805% R0402-0201<Part Number>R3501K1%R0402-0201<Part Number>
U42DS1818-5<Part Number>RST#1VCC2GND3
R34505% R0402-0201<Part Number>R34705% R0402-0201<Part Number>
R35733.21% R0402-0201<Part Number>R3551K1%R0402-0201<Part Number>R35610K1%R0402-0201<Part Number>
R34605% R0402-0201<Part Number>C40040.1UF25V10%C0402-0201X7RR34933.21% R0402-0201<Part Number>R35133.21% R0402-0201<Part Number>U40SN74LVC1G17DCKR<Part Number>24531R35333.21% R0402-0201<Part Number>PRSNT_NIC6_R_NHP_NIC6_ENPRSNT_NIC6_R_NRST_NIC6_PERST0_R_NRST_HP_NIC6_BUF_NRST_NIC6_PERST1_R_NRST_HP_NIC6_NHP_NIC6_PWRGDHP_NIC6_PWRGD_RHP_NIC6_PWRGD_RRST_HP_NIC6_NRST_NIC6_PERST_R_N
PRSNTB0_NIC6_NPRSNTB1_NIC6_NPRSNTB2_NIC6_NPRSNTB3_NIC6_NRST_NIC6_PERST2_R_NRST_NIC6_PERST3_R_NPRSNT_NIC6_N
HP_NIC6_HSC_PWRGD_N



5
5
4
4
3
3
2
2
1
1
D D
C C
B B
A A
PRIMARY CONNECTOR
NIC_7_J27(1/3)
DVT_CHANGENIC7_DATA_IN[189]NIC7_DATA_OUT[189]NIC7_CLK[189]PWRGD_NIC7_PWR_GOOD[189]NIC7_MAIN_PWR_EN_R[189]NIC7_LD_N[189]NIC7_SLOT_ID0[190]NCSI_NIC7_RXD1[189]NCSI_NIC7_RXD0[189]NCSI_NIC7_CRS_DV[189]CLK_50M_NIC7_RBT_REF [189]NIC7_RBT_ARB_OUT [189]NIC7_SLOT_ID1 [190]NCSI_NIC7_TX_EN [189]NCSI_NIC7_TXD1 [189]NCSI_NIC7_TXD0 [189]NIC7_MAIN_PWR_EN[116,189]NIC7_MAIN_PWR_EN_R [189]NIC7_AUX_PWR_EN[116,189]NIC7_AUX_PWR_EN_R [189,190]NIC7_BIF0_N[190]NIC7_BIF1_N[190]NIC7_BIF2_N[190]RST_NIC7_PERST0_R_N[191]PRSNTB0_NIC7_N [189,191]PRSNTB0_NIC7_N[189,191]PRSNTB3_NIC7_N[189,191]PRSNTB1_NIC7_N [189,191]PRSNTB2_NIC7_N [189,191]PRSNTB1_NIC7_N [189,191]PRSNTB2_NIC7_N [189,191]PRSNTB3_NIC7_N [189,191]NIC7_AUX_PWR_EN_R[189,190]NIC7_RBT_ARB_IN [189]RST_SMB_NIC7_MUX_ISO_R_N [190]RST_NIC7_PERST1_R_N [191]RST_NIC7_PERST2_R_N [191]RST_NIC7_PERST3_R_N [191]NIC7_RBT_ARB_IN[189]NIC7_RBT_ARB_OUT [189]
NCSI_NIC7_CRS_DV [189]NCSI_NIC7_RXD0 [189]NCSI_NIC7_RXD1 [189]NCSI_NIC7_TXD0 [189]NCSI_NIC7_TXD1 [189]CLK_50M_NIC7_RBT_REF [189]NCSI_NIC7_TX_EN [189]PWRGD_NIC7_PWR_GOOD [189]NIC7_MAIN_PWR_EN [116,189]NIC7_AUX_PWR_EN [116,189]NIC7_LD_N [189]NIC7_DATA_IN [189]NIC7_DATA_OUT [189]PWRGD_NIC7_PWR_GOOD_R[116]PWRGD_NIC7_PWR_GOOD [189]
NIC7_PWRBRK_R_N [192]NIC7_CLK [189]P5E_PEX3_STN0_TX_C_DN<0>[49]P5E_PEX3_STN0_RX_DN<0> [49]P5E_PEX3_STN0_TX_C_DP<0>[49]P5E_PEX3_STN0_RX_DP<0> [49]P5E_PEX3_STN0_TX_C_DN<1>[49]P5E_PEX3_STN0_RX_DN<1> [49]P5E_PEX3_STN0_TX_C_DP<1>[49]P5E_PEX3_STN0_RX_DP<1> [49]P5E_PEX3_STN0_TX_C_DN<2>[49]P5E_PEX3_STN0_RX_DN<2> [49]P5E_PEX3_STN0_TX_C_DP<2>[49]P5E_PEX3_STN0_RX_DP<2> [49]P5E_PEX3_STN0_TX_C_DN<3>[49]P5E_PEX3_STN0_RX_DN<3> [49]P5E_PEX3_STN0_TX_C_DP<3>[49]P5E_PEX3_STN0_RX_DP<3> [49]P5E_PEX3_STN0_TX_C_DN<4>[49]P5E_PEX3_STN0_RX_DN<4> [49]P5E_PEX3_STN0_TX_C_DP<4>[49]P5E_PEX3_STN0_RX_DP<4> [49]P5E_PEX3_STN0_TX_C_DN<5>[49]P5E_PEX3_STN0_RX_DN<5> [49]P5E_PEX3_STN0_TX_C_DP<5>[49]P5E_PEX3_STN0_RX_DP<5> [49]P5E_PEX3_STN0_TX_C_DN<6>[49]P5E_PEX3_STN0_RX_DN<6> [49]P5E_PEX3_STN0_TX_C_DP<6>[49]P5E_PEX3_STN0_RX_DP<6> [49]P5E_PEX3_STN0_TX_C_DN<7>[49]P5E_PEX3_STN0_RX_DN<7> [49]P5E_PEX3_STN0_TX_C_DP<7>[49]P5E_PEX3_STN0_RX_DP<7> [49]P5E_PEX3_STN0_TX_C_DN<8>[49]P5E_PEX3_STN0_RX_DN<8> [49]P5E_PEX3_STN0_TX_C_DP<8>[49]P5E_PEX3_STN0_RX_DP<8> [49]P5E_PEX3_STN0_TX_C_DN<9>[49]P5E_PEX3_STN0_RX_DN<9> [49]P5E_PEX3_STN0_TX_C_DP<9>[49]P5E_PEX3_STN0_RX_DP<9> [49]P5E_PEX3_STN0_TX_C_DN<10>[49]P5E_PEX3_STN0_RX_DN<10> [49]P5E_PEX3_STN0_TX_C_DP<10>[49]P5E_PEX3_STN0_RX_DP<10> [49]P5E_PEX3_STN0_TX_C_DN<11>[49]P5E_PEX3_STN0_RX_DN<11> [49]P5E_PEX3_STN0_TX_C_DP<11>[49]P5E_PEX3_STN0_RX_DP<11> [49]P5E_PEX3_STN0_TX_C_DP<12>[49]P5E_PEX3_STN0_RX_DN<12> [49]P5E_PEX3_STN0_TX_C_DN<12>[49]P5E_PEX3_STN0_RX_DP<12> [49]P5E_PEX3_STN0_TX_C_DN<13>[49]P5E_PEX3_STN0_RX_DN<13> [49]P5E_PEX3_STN0_TX_C_DP<13>[49]P5E_PEX3_STN0_RX_DP<13> [49]P5E_PEX3_STN0_TX_C_DP<14>[49]P5E_PEX3_STN0_RX_DN<14> [49]P5E_PEX3_STN0_TX_C_DN<14>[49]P5E_PEX3_STN0_RX_DP<14> [49]P5E_PEX3_STN0_TX_C_DN<15>[49]P5E_PEX3_STN0_RX_DN<15> [49]P5E_PEX3_STN0_TX_C_DP<15>[49]P5E_PEX3_STN0_RX_DP<15> [49]SMB_NIC7_LS_SCL [94,189]SMB_NIC7_LS_SDA [94,189]SMB_NIC7_LS_SCL [94,189]SMB_NIC7_LS_SDA [94,189]CLK_100M_DB2000QL_NIC7_R_DN[79]CLK_100M_DB2000QL_NIC7_R_DP[79]
P12V_NIC7P3V3_NIC7P12V_NIC7P3V3_NIC7P3V3_AUXP3V3_NIC7
SizeDoc NumberRevDate: SheetofReviewerDesignerDepartmentProject
Page TitleCCBU D189 257Tuesday, August 29, 2023<project_name><Designer> GRANDTETON_SWB_20230829189 NIC_7_J27(1/3)<Reviewer>SizeDoc NumberRevDate: SheetofReviewerDesignerDepartmentProject
Page TitleCCBU D189 257Tuesday, August 29, 2023<project_name><Designer> GRANDTETON_SWB_20230829189 NIC_7_J27(1/3)<Reviewer>SizeDoc NumberRevDate: SheetofReviewerDesignerDepartmentProject
Page TitleCCBU D189 257Tuesday, August 29, 2023<project_name><Designer> GRANDTETON_SWB_20230829189 NIC_7_J27(1/3)<Reviewer>R372100K1% R0402-0201<Part Number>R36910K1% R0402-0201<Part Number>
R35805% R0402-0201<Part Number>
R377100K1% R0402-0201<Part Number>
R36105% R0402-0201<Part Number>C9520.1UFX6SC020110%16V<Part Number>R3641K1% R0402-0201<Part Number>C9580.1UFX6SC0402-020110%25V<Part Number>C9550.1UFX6SC020110%16V<Part Number>
R378100K1% R0402-0201<Part Number>
C9540.1UFX6SC020110%16V<Part Number>R3631K1% R0402-0201<Part Number>R379100K1% R0402-0201<Part Number>R3621K1% R0402-0201<Part Number>C9600.1UFX6SC0402-020110%25V<Part Number>C95122UFX6SC0805_H5720%16V<Part Number>
R373100K1% R0402-0201<Part Number>R3681K1% R0402-0201<Part Number>R38010K1% R0402-0201<Part Number>R3651K1% R0402-0201<Part Number>C9570.1UFX6SC0402-020110%25V<Part Number>R371100K1% R0402-0201<Part Number>R35905% R0402-0201<Part Number>R3663.3K1%R0402-0201R374100K1% R0402-0201<Part Number>
C9560.1UFX6SC020110%16V<Part Number>
R3701K1% R0402-0201<Part Number>R3673.3K1%R0402-0201R36005% R0402-0201<Part Number>C9530.1UFX6SC020110%16V<Part Number>C9590.1UFX6SC0402-020110%25V<Part Number>KEYKEYKEYSCONN168_G64V35313HR
J27
<Part Number>
NIC_PWR_GOODOB1MAIN_PWR_ENOB2LD#OB3DATA_INOB4DATA_OUTOB5CLKOB6SLOT_ID0OB7RBT_RXD1OB8RBT_RXD0OB9GND_OB10OB10REFCLKn2OB11REFCLKp2OB12GND_OB13OB13RBT_CRS_DVOB14+12V_EDGE_B1B1+12V_EDGE_B2B2+12V_EDGE_B3B3+12V_EDGE_B4B4+12V_EDGE_B5B5+12V_EDGE_B6B6BIF0#B7BIF1#B8BIF2#B9PERST0#B10+3.3V_EDGEB11AUX_PWR_ENB12GND_B13B13REFCLKn0B14REFCLKp0B15GND_B16B16PETn0B17PETp0B18GND_B19B19PETn1B20PETp1B21GND_B22B22PETn2B23PETp2B24GND_B25B25PETn3B26PETp3B27GND_B28B28GND_B29B29PETn4B30PETp4B31GND_B32B32PETn5B33PETp5B34GND_B35B35PETn6B36PETp6B37GND_B38B38PETn7B39PETp7B40GND_B41B41PRSNTB0#B42GND_B43B43PETn8B44PETp8B45GND_B46B46PETn9B47PETp9B48GND_B49B49PETn10B50PETp10B51GND_B52B52PETn11B53PETp11B54GND_B55B55PETn12B56
PERST2#OA1PERST3#OA2WAKE#OA3RBT_ARB_INOA4RBT_ARB_OUTOA5SLOT_ID1OA6RBT_TX_ENOA7RBT_TXD1OA8RBT_TXD0OA9GND_OA10OA10REFCLKn3OA11REFCLKp3OA12GND_OA13OA13RBT_CLK_INOA14GND_A1A1GND_A2A2GND_A3A3GND_A4A4GND_A5A5GND_A6A6SMCLKA7SMDATA8SMRST#A9PRSNTA#A10PERST1#A11PRSNTB2#A12GND_A13A13REFCLKn1A14REFCLKp1A15GND_A16A16PERn0A17PERp0A18GND_A19A19PERn1A20PERp1A21GND_A22A22PERn2A23PERp2A24GND_A25A25PERn3A26PERp3A27GND_A28A28GND_A29A29PERn4A30PERp4A31GND_A32A32PERn5A33PERp5A34GND_A35A35PERn6A36PERp6A37GND_A38A38PERn7A39PERp7A40GND_A41A41PRSNTB1#A42GND_A43A43PERn8A44PERp8A45GND_A46A46PERn9A47PERp9A48GND_A49A49PERn10A50PERp10A51GND_A52A52PERn11A53PERp11A54GND_A55A55PERn12A56PERp12A57GND_A58A58PERn13A59PERp13A60GND_A61A61PERn14A62PERp14A63GND_A64A64PERn15A65PERp15A66GND_A67A67USB_DATnA68USB_DATpA69PWRBRK0#A70PETp12B57GND_B58B58PETn13B59PETp13B60GND_B61B61PETn14B62PETp14B63GND_B64B64PETn15B65PETp15B66GND_B67B67RFU1_NCB68RFU2_NCB69PRSNTB3#B70G1G1G2G2G3G3G4G4G5G5G6G6G7G7G8G8G9G9R376100K1% R0402-0201<Part Number>R38110K1% R0402-0201<Part Number>R375100K1% R0402-0201<Part Number>
C95022UFX6SC0805_H5720%16V<Part Number>PWRGD_NIC7_PWR_GOODNIC7_MAIN_PWR_EN_RNIC7_LD_NNIC7_DATA_INNIC7_DATA_OUTNIC7_CLKNIC7_SLOT_ID0NCSI_NIC7_RXD1NCSI_NIC7_RXD0NCSI_NIC7_CRS_DVCLK_50M_NIC7_RBT_REFNIC7_RBT_ARB_OUTNIC7_SLOT_ID1NCSI_NIC7_TX_ENNCSI_NIC7_TXD1NCSI_NIC7_TXD0NIC7_RBT_ARB_INNIC7_MAIN_PWR_ENNIC7_MAIN_PWR_EN_RNIC7_AUX_PWR_ENNIC7_AUX_PWR_EN_RNIC7_BIF0_NNIC7_BIF1_NNIC7_BIF2_NPRSNTB3_NIC7_NPRSNTB0_NIC7_NPRSNTB1_NIC7_NPRSNTB2_NIC7_NRST_NIC7_PERST0_R_NPRSNTB0_NIC7_NPRSNTB1_NIC7_NPRSNTB2_NIC7_NPRSNTB3_NIC7_NNIC7_AUX_PWR_EN_RRST_NIC7_PERST1_R_NRST_NIC7_PERST2_R_NRST_NIC7_PERST3_R_NNIC7_RBT_ARB_INNIC7_RBT_ARB_OUT
NCSI_NIC7_CRS_DVNCSI_NIC7_RXD0NCSI_NIC7_RXD1NCSI_NIC7_TXD0NCSI_NIC7_TXD1CLK_50M_NIC7_RBT_REFNCSI_NIC7_TX_ENPWRGD_NIC7_PWR_GOODNIC7_MAIN_PWR_ENNIC7_AUX_PWR_ENNIC7_LD_NNIC7_DATA_INNIC7_DATA_OUTNIC7_PWRBRK_R_N
PWRGD_NIC7_PWR_GOOD_RPWRGD_NIC7_PWR_GOODNIC7_CLKP5E_PEX3_STN0_TX_C_DN<0>P5E_PEX3_STN0_RX_DN<0>P5E_PEX3_STN0_TX_C_DP<0>P5E_PEX3_STN0_RX_DP<0>P5E_PEX3_STN0_TX_C_DN<1>P5E_PEX3_STN0_RX_DN<1>P5E_PEX3_STN0_TX_C_DP<1>P5E_PEX3_STN0_RX_DP<1>P5E_PEX3_STN0_TX_C_DN<2>P5E_PEX3_STN0_RX_DN<2>P5E_PEX3_STN0_TX_C_DP<2>P5E_PEX3_STN0_RX_DP<2>P5E_PEX3_STN0_TX_C_DN<3>P5E_PEX3_STN0_RX_DN<3>P5E_PEX3_STN0_TX_C_DP<3>P5E_PEX3_STN0_RX_DP<3>P5E_PEX3_STN0_TX_C_DN<4>P5E_PEX3_STN0_RX_DN<4>P5E_PEX3_STN0_TX_C_DP<4>P5E_PEX3_STN0_RX_DP<4>P5E_PEX3_STN0_TX_C_DN<5>P5E_PEX3_STN0_RX_DN<5>P5E_PEX3_STN0_TX_C_DP<5>P5E_PEX3_STN0_RX_DP<5>P5E_PEX3_STN0_TX_C_DN<6>P5E_PEX3_STN0_RX_DN<6>P5E_PEX3_STN0_TX_C_DP<6>P5E_PEX3_STN0_RX_DP<6>P5E_PEX3_STN0_TX_C_DN<7>P5E_PEX3_STN0_RX_DN<7>P5E_PEX3_STN0_TX_C_DP<7>P5E_PEX3_STN0_RX_DP<7>P5E_PEX3_STN0_TX_C_DN<8>P5E_PEX3_STN0_RX_DN<8>P5E_PEX3_STN0_TX_C_DP<8>P5E_PEX3_STN0_RX_DP<8>P5E_PEX3_STN0_TX_C_DN<9>P5E_PEX3_STN0_RX_DN<9>P5E_PEX3_STN0_TX_C_DP<9>P5E_PEX3_STN0_RX_DP<9>P5E_PEX3_STN0_TX_C_DN<10>P5E_PEX3_STN0_RX_DN<10>P5E_PEX3_STN0_TX_C_DP<10>P5E_PEX3_STN0_RX_DP<10>P5E_PEX3_STN0_TX_C_DN<11>P5E_PEX3_STN0_RX_DN<11>P5E_PEX3_STN0_TX_C_DP<11>P5E_PEX3_STN0_RX_DP<11>P5E_PEX3_STN0_TX_C_DP<12>P5E_PEX3_STN0_RX_DN<12>P5E_PEX3_STN0_TX_C_DN<12>P5E_PEX3_STN0_RX_DP<12>P5E_PEX3_STN0_TX_C_DN<13>P5E_PEX3_STN0_RX_DN<13>P5E_PEX3_STN0_TX_C_DP<13>P5E_PEX3_STN0_RX_DP<13>P5E_PEX3_STN0_TX_C_DP<14>P5E_PEX3_STN0_RX_DN<14>P5E_PEX3_STN0_TX_C_DN<14>P5E_PEX3_STN0_RX_DP<14>P5E_PEX3_STN0_TX_C_DN<15>P5E_PEX3_STN0_RX_DN<15>P5E_PEX3_STN0_TX_C_DP<15>P5E_PEX3_STN0_RX_DP<15>SMB_NIC7_LS_SCLSMB_NIC7_LS_SDARST_SMB_NIC7_MUX_ISO_R_NCLK_100M_DB2000QL_NIC7_R_DNSMB_NIC7_LS_SCLCLK_100M_DB2000QL_NIC7_R_DPSMB_NIC7_LS_SDA



5
5
4
4
3
3
2
2
1
1
D D
C C
B B
A A
NIC_7_J27(2/3)
RST_SMB_NIC_MUX_R_N[87,169,172,175,178,181,184,187]NIC7_AUX_PWR_EN_R[189]RST_SMB_NIC7_MUX_ISO_R_N [189]
NIC7_BIF0_N [189]NIC7_BIF1_N [189]NIC7_BIF2_N [189]NIC7_SLOT_ID0 [189]NIC7_SLOT_ID1 [189]
P3V3_AUXP3V3_AUXP3V3_AUXP3V3_AUXP3V3_NIC7P3V3_NIC7
P3V3_NIC7SizeDoc NumberRevDate: SheetofReviewerDesignerDepartmentProject
Page TitleCCBU D190 257Tuesday, August 29, 2023<project_name><Designer> GRANDTETON_SWB_20230829190 NIC_7_J27(2/3)<Reviewer>SizeDoc NumberRevDate: SheetofReviewerDesignerDepartmentProject
Page TitleCCBU D190 257Tuesday, August 29, 2023<project_name><Designer> GRANDTETON_SWB_20230829190 NIC_7_J27(2/3)<Reviewer>SizeDoc NumberRevDate: SheetofReviewerDesignerDepartmentProject
Page TitleCCBU D190 257Tuesday, August 29, 2023<project_name><Designer> GRANDTETON_SWB_20230829190 NIC_7_J27(2/3)<Reviewer>
R39105% R0402-0201<Part Number>R390100K1% R0402-0201<Part Number>NI3 state outputU4374HC1G126GW<Part Number>24513R39405% R0402-0201<Part Number>
R3844.7K1% R0402-0201<Part Number>NIR38905% R0402-0201<Part Number>R388100K1% R0402-0201<Part Number>NIR38705% R0402-0201<Part Number>R3831001% R0402-0201<Part Number>R3824.7K1% R0402-0201<Part Number>NIR3851001% R0402-0201<Part Number>
R395100K1%R0402-0201<Part Number>
R386100K1% R0402-0201<Part Number>NI
R393 33 R0402-02011%R3924.75KR0402-02011%NIC9610.1UFX6SC0402-020110%25V<Part Number>RST_SMB_NIC7_MUX_ISO_R_NRST_SMB_NIC7_MUX_ISO_NRST_SMB_NIC7_MUX_NNIC7_AUX_PWR_EN_RNIC7_BIF0_NNIC7_BIF1_NNIC7_BIF2_NNIC7_SLOT_ID0NIC7_SLOT_ID1



5
5
4
4
3
3
2
2
1
1
D D
C C
B B
A A
NIC_7_J27(3/3)
PRSNT_NIC7_R_N [86,116,191]HP_NIC7_EN [235,238,243,249]PRSNT_NIC7_R_N[86,116,191]RST_NIC7_PERST0_R_N [189]RST_NIC7_PERST1_R_N [189]RST_HP_NIC7_N[191]HP_NIC7_PWRGD_R [191]HP_NIC7_PWRGD_R[191]RST_HP_NIC7_N [191]RST_NIC7_PERST_R_N[116]
PRSNTB0_NIC7_N[189]PRSNTB1_NIC7_N[189]PRSNTB2_NIC7_N[189]PRSNTB3_NIC7_N[189]RST_NIC7_PERST2_R_N [189]RST_NIC7_PERST3_R_N [189]PWRGD_P12V_NIC7_R[116,235,243]
P3V3_AUXP3V3_AUXP3V3_NIC7P3V3_AUXP3V3_NIC7P3V3_AUXSizeDoc NumberRevDate: SheetofReviewerDesignerDepartmentProject
Page TitleCCBU D191 257Tuesday, August 29, 2023<project_name><Designer> GRANDTETON_SWB_20230829191 NIC_7_J27(3/3)<Reviewer>SizeDoc NumberRevDate: SheetofReviewerDesignerDepartmentProject
Page TitleCCBU D191 257Tuesday, August 29, 2023<project_name><Designer> GRANDTETON_SWB_20230829191 NIC_7_J27(3/3)<Reviewer>SizeDoc NumberRevDate: SheetofReviewerDesignerDepartmentProject
Page TitleCCBU D191 257Tuesday, August 29, 2023<project_name><Designer> GRANDTETON_SWB_20230829191 NIC_7_J27(3/3)<Reviewer>
R40033.21% R0402-0201<Part Number>
C9640.1UFX6SC0402-020110%25V<Part Number>R40433.21% R0402-0201<Part Number>R40333.21% R0402-0201<Part Number>U45SN74LVC1G17DCKR<Part Number>24531U47DS1818-5<Part Number>RST#1VCC2GND3R40833.21% R0402-0201<Part Number>
R39705% R0402-0201<Part Number>
Q8BDMN53D0LDW-7<Part Number>D23G25S24R40533.21% R0402-0201<Part Number>C9620.1UFX6SC0402-020110%25V<Part Number>R40710K1%R0402-0201<Part Number>
R4011K1%R0402-0201<Part Number>R39805% R0402-0201<Part Number>
U4674LVC1G08GV12453R40233.21% R0402-0201<Part Number>Q8ADMN53D0LDW-7<Part Number>S11G12D16
R39605% R0402-0201<Part Number>U44BSS138K<Part Number>GDSC40050.1UF25V10%C0402-0201X7RR39905% R0402-0201<Part Number>C9630.1UFX6SC0402-020110%25V<Part Number>R4061K1%R0402-0201<Part Number>
PRSNT_NIC7_R_NHP_NIC7_ENPRSNT_NIC7_R_NRST_NIC7_PERST0_R_NRST_HP_NIC7_BUF_NRST_NIC7_PERST1_R_NRST_HP_NIC7_NHP_NIC7_PWRGDHP_NIC7_PWRGD_RHP_NIC7_PWRGD_RRST_HP_NIC7_NRST_NIC7_PERST_R_N
PRSNTB0_NIC7_NPRSNTB1_NIC7_NPRSNTB2_NIC7_NPRSNTB3_NIC7_NRST_NIC7_PERST2_R_NRST_NIC7_PERST3_R_NPRSNT_NIC7_N
HP_NIC7_HSC_PWRGD_N



5
5
4
4
3
3
2
2
1
1
D D
C C
B B
A A
NIC_PWRBRK_N
NIC0_PWRBRK_R_N [168]FM_SYS_THROTTLE_R[87,118]NIC1_PWRBRK_R_N [171]NIC2_PWRBRK_R_N [174]NIC3_PWRBRK_R_N [177]NIC4_PWRBRK_R_N [180]NIC5_PWRBRK_R_N [183]NIC6_PWRBRK_R_N [186]NIC7_PWRBRK_R_N [189]
P3V3_NIC0P3V3_NIC1P3V3_NIC2P3V3_NIC3P3V3_NIC4P3V3_NIC5P3V3_NIC6P3V3_NIC7SizeDoc NumberRevDate: SheetofReviewerDesignerDepartmentProject
Page TitleCCBU D192 257Tuesday, August 29, 2023<project_name><Designer> GRANDTETON_SWB_20230829192 NIC_PWRBRK_N<Reviewer>SizeDoc NumberRevDate: SheetofReviewerDesignerDepartmentProject
Page TitleCCBU D192 257Tuesday, August 29, 2023<project_name><Designer> GRANDTETON_SWB_20230829192 NIC_PWRBRK_N<Reviewer>SizeDoc NumberRevDate: SheetofReviewerDesignerDepartmentProject
Page TitleCCBU D192 257Tuesday, August 29, 2023<project_name><Designer> GRANDTETON_SWB_20230829192 NIC_PWRBRK_N<Reviewer>Q122BBSS138BKSD23G25S24
R3305 33 R0402-02011%R247405%R0402-0201R3308 33 R0402-02011%R3311 33 R0402-02011%R247005%R0402-0201
Q119ABSS138BKSS11G12D16R24654.7K1%R0402-0201R24754.7K1%R0402-0201Q120BBSS138BKSD23G25S24Q122ABSS138BKSS11G12D16
R3304 33 R0402-02011%R246605%R0402-0201R3307 33 R0402-02011%R247605%R0402-0201R3310 33 R0402-02011%
R24714.7K1%R0402-0201R24674.7K1%R0402-0201Q120ABSS138BKSS11G12D16R24774.7K1%R0402-0201Q121BBSS138BKSD23G25S24R247205%R0402-0201R3306 33 R0402-02011%R246805%R0402-0201R3309 33 R0402-02011%R247805%R0402-0201
R24634.7K1%R0402-0201R24734.7K1%R0402-0201Q119BBSS138BKSD23G25S24R24694.7K1%R0402-0201
R246405%R0402-0201Q121ABSS138BKSS11G12D16NIC0_PWRBRK_NFM_SYS_THROTTLE_NIC0NIC1_PWRBRK_NFM_SYS_THROTTLE_NIC1NIC2_PWRBRK_NFM_SYS_THROTTLE_NIC2NIC3_PWRBRK_NFM_SYS_THROTTLE_NIC3NIC4_PWRBRK_NFM_SYS_THROTTLE_NIC4NIC5_PWRBRK_NFM_SYS_THROTTLE_NIC5NIC6_PWRBRK_NFM_SYS_THROTTLE_NIC6NIC7_PWRBRK_NFM_SYS_THROTTLE_NIC7



5
5
4
4
3
3
2
2
1
1
D D
C C
B B
A A
BLANK SizeDoc NumberRevDate: SheetofReviewerDesignerDepartmentProject
Page TitleCCBU D193 257Tuesday, August 29, 2023<project_name><Designer> GRANDTETON_SWB_20230829193 BLANK<Reviewer>SizeDoc NumberRevDate: SheetofReviewerDesignerDepartmentProject
Page TitleCCBU D193 257Tuesday, August 29, 2023<project_name><Designer> GRANDTETON_SWB_20230829193 BLANK<Reviewer>SizeDoc NumberRevDate: SheetofReviewerDesignerDepartmentProject
Page TitleCCBU D193 257Tuesday, August 29, 2023<project_name><Designer> GRANDTETON_SWB_20230829193 BLANK<Reviewer>



5
5
4
4
3
3
2
2
1
1
D D
C C
B B
A A
SSD_0/1
SSD0
SSD1
P5E_PEX0_STN2_TX_C_DN<44>[11]P5E_PEX0_STN2_TX_C_DP<44>[11]P5E_PEX0_STN2_RX_DN<44> [11]P5E_PEX0_STN2_RX_DP<44> [11]P5E_PEX0_STN2_TX_C_DN<45>[11]P5E_PEX0_STN2_TX_C_DP<45>[11]P5E_PEX0_STN2_TX_C_DN<46>[11]P5E_PEX0_STN2_TX_C_DP<46>[11]P5E_PEX0_STN2_TX_C_DN<47>[11]P5E_PEX0_STN2_TX_C_DP<47>[11]P5E_PEX0_STN2_RX_DN<45> [11]P5E_PEX0_STN2_RX_DP<45> [11]P5E_PEX0_STN2_RX_DN<46> [11]P5E_PEX0_STN2_RX_DP<46> [11]P5E_PEX0_STN2_RX_DN<47> [11]P5E_PEX0_STN2_RX_DP<47> [11]P5E_PEX0_STN2_TX_C_DN<40>[11]P5E_PEX0_STN2_RX_DN<40> [11]P5E_PEX0_STN2_TX_C_DP<40>[11]P5E_PEX0_STN2_RX_DP<40> [11]P5E_PEX0_STN2_TX_C_DN<41>[11]P5E_PEX0_STN2_RX_DN<41> [11]P5E_PEX0_STN2_TX_C_DP<41>[11]P5E_PEX0_STN2_RX_DP<41> [11]P5E_PEX0_STN2_TX_C_DN<42>[11]P5E_PEX0_STN2_RX_DN<42> [11]P5E_PEX0_STN2_TX_C_DP<42>[11]P5E_PEX0_STN2_RX_DP<42> [11]P5E_PEX0_STN2_TX_C_DN<43>[11]P5E_PEX0_STN2_RX_DN<43> [11]P5E_PEX0_STN2_TX_C_DP<43>[11]P5E_PEX0_STN2_RX_DP<43> [11]
RST_SSD0_PERST_R_N[115]SSD0_PWRDIS_R[115,194]SMB_ISO_SSD0_R_SCL [97]SMB_ISO_SSD0_R_SDA [97]RST_SMB_SSD0_ISO_R_N [101]SSD0_LED_ISO_R_N [194]
RST_SMB_SSD1_ISO_R_N [101]RST_SSD1_PERST_R_N[115]SSD1_LED_ISO_R_N [194]SSD1_PWRDIS_R[115,194]
CLK_100M_DB800ZL_SSD0_R_DN[80]CLK_100M_DB800ZL_SSD0_R_DP[80]SMB_ISO_SSD1_R_SCL [97]SMB_ISO_SSD1_R_SDA [97]CLK_100M_DB800ZL_SSD1_R_DN[80]CLK_100M_DB800ZL_SSD1_R_DP[80]PRSNT_SSD1_R_N [86,115,202]
PRSNT_SSD0_R_N [86,115,202]SSD0_LED_ISO_R_N [194]SSD0_LED_R[90]SSD1_LED_ISO_R_N [194]SSD1_LED_R[90]
SSD0_PWRDIS_R [115,194]
SSD1_PWRDIS_R [115,194]
P12V_SSD0
P12V_SSD1
P3V3_SSD0P3V3_SSD0P3V3_SSD0
P3V3_SSD1P3V3_SSD1P3V3_SSD1P3V3_AUX
P3V3_AUXP3V3_SSD0
P3V3_SSD1
P12V_SSD0
P12V_SSD1
SizeDoc NumberRevDate: SheetofReviewerDesignerDepartmentProject
Page TitleCCBU D194 257Tuesday, August 29, 2023<project_name><Designer> GRANDTETON_SWB_20230829194 SSD_0/1<Reviewer>SizeDoc NumberRevDate: SheetofReviewerDesignerDepartmentProject
Page TitleCCBU D194 257Tuesday, August 29, 2023<project_name><Designer> GRANDTETON_SWB_20230829194 SSD_0/1<Reviewer>SizeDoc NumberRevDate: SheetofReviewerDesignerDepartmentProject
Page TitleCCBU D194 257Tuesday, August 29, 2023<project_name><Designer> GRANDTETON_SWB_20230829194 SSD_0/1<Reviewer>C38840.1UF25V10%X6SJ31_OTH<Part Number>1R412 4.7K 1/16W1%R4051 0 5% R0402-0201C965 0.1UF25V 10% C0402-0201X6SU398BSS138K<Part Number>GDSC38850.1UF25V10%X6S<Part Number>R41310KR0402-02015%1/16WC27640.1UF25V10%C0402-0201X7RJ31SCONN56_1-2327679-3P12V_B1B1P12V_B2B2P12V_B3B3P12V_B4B4P12V_B5B5P12V_B6B6GND_A1A1GND_A2A2GND_A3A3GND_A4A4GND_A5A5GND_A6A6MFGB7RFUB8DUALPORTEN#B9P3V3_AUXB11PWRDISB12GND_B13B13GND_B16B16GND_B19B19GND_B22B22GND_B25B25GND_B28B28REFCLK_n0B14REFCLK_p0B15PET_n0B17PET_p0B18PET_n1B20PET_p1B21PET_n2B23PET_p2B24PET_n3B26PET_p3B27SMBCLKA7SMBDATA8SMBRST#A9LED#_ACTIVITYA10PERST0#B10PERST1#_CLKREQ#A11PRSNT0#A12GND_A13A13GND_A16A16GND_A19A19GND_A22A22GND_A25A25GND_A28A28REFCLK_n1A14REFCLK_p1A15PER_n0A17PER_p0A18PER_n1A20PER_p1A21PER_n2A23PER_p2A24PER_n3A26PER_p3A27G2G2G1G1
C38750.1UF25V10%X6S
R414 4.7K 1/16W1%NI
R409 4.7K 1/16W1%
R40544.7KR0402-02011%1/16W
C38760.1UF25V10%X6SJ30SCONN56_1-2327679-3P12V_B1B1P12V_B2B2P12V_B3B3P12V_B4B4P12V_B5B5P12V_B6B6GND_A1A1GND_A2A2GND_A3A3GND_A4A4GND_A5A5GND_A6A6MFGB7RFUB8DUALPORTEN#B9P3V3_AUXB11PWRDISB12GND_B13B13GND_B16B16GND_B19B19GND_B22B22GND_B25B25GND_B28B28REFCLK_n0B14REFCLK_p0B15PET_n0B17PET_p0B18PET_n1B20PET_p1B21PET_n2B23PET_p2B24PET_n3B26PET_p3B27SMBCLKA7SMBDATA8SMBRST#A9LED#_ACTIVITYA10PERST0#B10PERST1#_CLKREQ#A11PRSNT0#A12GND_A13A13GND_A16A16GND_A19A19GND_A22A22GND_A25A25GND_A28A28REFCLK_n1A14REFCLK_p1A15PER_n0A17PER_p0A18PER_n1A20PER_p1A21PER_n2A23PER_p2A24PER_n3A26PER_p3A27G2G2G1G1C38791UFX6SC0402-020110%25V<Part Number>R4052 0 5% R0402-0201R57331K1%R0402-0201<Part Number>
C38770.1UF25V10%X6S<Part Number>R411 4.7K 1/16W1%NI R41010KR0402-02015%1/16WC38720.1UF25V10%X6SSCREW_SSD0_1<Part Number>1C38800.1UF25V10%X6SR5734 33C38810.1UF25V10%X6SSCREW_SSD0_2<Part Number>1C38781UFX6SC0402-020110%25V<Part Number>
C27630.1UF25V10%C0402-0201X7RR57311K1%R0402-0201<Part Number>C38730.1UF25V10%X6SR6198 4.7K 5% R0402-0201C38820.1UF25V10%X6SR6199 4.7K 5% R0402-0201U399BSS138K<Part Number>GDS
R5732 33SCREW_SSD1_1<Part Number>1J30_OTH<Part Number>1C38830.1UF25V10%X6S
R40554.7KR0402-02011%1/16WC38740.1UF25V10%X6S
C966 0.1UF25V 10% C0402-0201X6SSCREW_SSD1_2<Part Number>1
P5E_PEX0_STN2_TX_C_DN<44>P5E_PEX0_STN2_TX_C_DP<44>P5E_PEX0_STN2_RX_DN<44>P5E_PEX0_STN2_RX_DP<44>P5E_PEX0_STN2_TX_C_DN<45>P5E_PEX0_STN2_TX_C_DP<45>P5E_PEX0_STN2_TX_C_DN<46>P5E_PEX0_STN2_TX_C_DP<46>P5E_PEX0_STN2_TX_C_DN<47>P5E_PEX0_STN2_TX_C_DP<47>P5E_PEX0_STN2_RX_DN<45>P5E_PEX0_STN2_RX_DP<45>P5E_PEX0_STN2_RX_DN<46>P5E_PEX0_STN2_RX_DP<46>P5E_PEX0_STN2_RX_DN<47>P5E_PEX0_STN2_RX_DP<47>P5E_PEX0_STN2_TX_C_DN<40>P5E_PEX0_STN2_RX_DN<40>P5E_PEX0_STN2_TX_C_DP<40>P5E_PEX0_STN2_RX_DP<40>P5E_PEX0_STN2_TX_C_DN<41>P5E_PEX0_STN2_RX_DN<41>P5E_PEX0_STN2_TX_C_DP<41>P5E_PEX0_STN2_RX_DP<41>P5E_PEX0_STN2_TX_C_DN<42>P5E_PEX0_STN2_RX_DN<42>P5E_PEX0_STN2_TX_C_DP<42>P5E_PEX0_STN2_RX_DP<42>P5E_PEX0_STN2_TX_C_DN<43>P5E_PEX0_STN2_RX_DN<43>P5E_PEX0_STN2_TX_C_DP<43>P5E_PEX0_STN2_RX_DP<43>
DUALPORT_N_SSD0RST_SSD0_PERST_R_NSSD0_PWRDIS_RSMB_ISO_SSD0_R_SCLSMB_ISO_SSD0_R_SDARST_SMB_SSD0_ISO_R_NPU_CLKREQ0PRSNT_SSD0_N
DUALPORT_N_SSD1RST_SMB_SSD1_ISO_R_NRST_SSD1_PERST_R_NPU_CLKREQ1SSD1_PWRDIS_R
CLK_100M_DB800ZL_SSD0_R_DNCLK_100M_DB800ZL_SSD0_R_DPSMB_ISO_SSD1_R_SCLSMB_ISO_SSD1_R_SDACLK_100M_DB800ZL_SSD1_R_DNCLK_100M_DB800ZL_SSD1_R_DPPRSNT_SSD1_NSSD0_LED_ISO_N
SSD1_LED_ISO_N



5
5
4
4
3
3
2
2
1
1
D D
C C
B B
A A
SSD_2/3
SSD2
SSD3
P5E_PEX0_STN2_TX_C_DN<36>[11]P5E_PEX0_STN2_RX_DN<36> [11]P5E_PEX0_STN2_TX_C_DP<36>[11]P5E_PEX0_STN2_RX_DP<36> [11]P5E_PEX0_STN2_TX_C_DN<37>[11]P5E_PEX0_STN2_RX_DN<37> [11]P5E_PEX0_STN2_TX_C_DP<37>[11]P5E_PEX0_STN2_RX_DP<37> [11]P5E_PEX0_STN2_TX_C_DN<38>[11]P5E_PEX0_STN2_RX_DN<38> [11]P5E_PEX0_STN2_TX_C_DP<38>[11]P5E_PEX0_STN2_RX_DP<38> [11]P5E_PEX0_STN2_TX_C_DN<39>[11]P5E_PEX0_STN2_RX_DN<39> [11]P5E_PEX0_STN2_TX_C_DP<39>[11]P5E_PEX0_STN2_RX_DP<39> [11]P5E_PEX0_STN2_TX_C_DN<32>[11]P5E_PEX0_STN2_RX_DN<32> [11]P5E_PEX0_STN2_TX_C_DP<32>[11]P5E_PEX0_STN2_RX_DP<32> [11]P5E_PEX0_STN2_TX_C_DN<33>[11]P5E_PEX0_STN2_RX_DN<33> [11]P5E_PEX0_STN2_TX_C_DP<33>[11]P5E_PEX0_STN2_RX_DP<33> [11]P5E_PEX0_STN2_TX_C_DN<34>[11]P5E_PEX0_STN2_RX_DN<34> [11]P5E_PEX0_STN2_TX_C_DP<34>[11]P5E_PEX0_STN2_RX_DP<34> [11]P5E_PEX0_STN2_TX_C_DN<35>[11]P5E_PEX0_STN2_RX_DN<35> [11]P5E_PEX0_STN2_TX_C_DP<35>[11]P5E_PEX0_STN2_RX_DP<35> [11]
RST_SMB_SSD2_ISO_R_N [101]RST_SSD2_PERST_R_N[115]SSD2_LED_ISO_R_N [195]SSD2_PWRDIS_R[115,195]
RST_SMB_SSD3_ISO_R_N [101]RST_SSD3_PERST_R_N[115]SSD3_LED_ISO_R_N [195]SSD3_PWRDIS_R[115,195]
SMB_ISO_SSD2_R_SCL [97]SMB_ISO_SSD2_R_SDA [97]
SMB_ISO_SSD3_R_SCL [97]SMB_ISO_SSD3_R_SDA [97]
CLK_100M_DB800ZL_SSD2_R_DN[80]CLK_100M_DB800ZL_SSD2_R_DP[80]
CLK_100M_DB800ZL_SSD3_R_DN[80]CLK_100M_DB800ZL_SSD3_R_DP[80]
PRSNT_SSD2_R_N [86,115,202]
PRSNT_SSD3_R_N [86,115,202]SSD2_LED_ISO_R_N [195]SSD2_LED_R[90]SSD3_LED_ISO_R_N [195]SSD3_LED_R[90]
SSD2_PWRDIS_R [115,195]
SSD3_PWRDIS_R [115,195]
P12V_SSD2
P12V_SSD3
P3V3_SSD2P3V3_SSD2P3V3_SSD2P3V3_SSD3P3V3_SSD3P3V3_SSD3
P3V3_AUX
P3V3_AUXP3V3_SSD2
P3V3_SSD3
P12V_SSD2
P12V_SSD3SizeDoc NumberRevDate: SheetofReviewerDesignerDepartmentProject
Page TitleCCBU D195 257Tuesday, August 29, 2023<project_name><Designer> GRANDTETON_SWB_20230829195 SSD_2/3<Reviewer>SizeDoc NumberRevDate: SheetofReviewerDesignerDepartmentProject
Page TitleCCBU D195 257Tuesday, August 29, 2023<project_name><Designer> GRANDTETON_SWB_20230829195 SSD_2/3<Reviewer>SizeDoc NumberRevDate: SheetofReviewerDesignerDepartmentProject
Page TitleCCBU D195 257Tuesday, August 29, 2023<project_name><Designer> GRANDTETON_SWB_20230829195 SSD_2/3<Reviewer>
R6200 4.7K 5% R0402-0201
R57371K1%R0402-0201<Part Number>R6201 4.7K 5% R0402-0201
SCREW_SSD2_1<Part Number>1R416 4.7K 1/16W1%NI
R40584.7KR0402-02011%1/16WR4057 0 5% R0402-0201
SCREW_SSD3_1<Part Number>1C38931UFX6SC0402-020110%25V<Part Number>R5738 33
J32_OTH<Part Number>1SCREW_SSD2_2<Part Number>1C38861UFX6SC0402-020110%25V<Part Number>
R4059 0 5% R0402-0201SCREW_SSD3_2<Part Number>1J33_OTH<Part Number>1 J33SCONN56_1-2327679-3P12V_B1B1P12V_B2B2P12V_B3B3P12V_B4B4P12V_B5B5P12V_B6B6GND_A1A1GND_A2A2GND_A3A3GND_A4A4GND_A5A5GND_A6A6MFGB7RFUB8DUALPORTEN#B9P3V3_AUXB11PWRDISB12GND_B13B13GND_B16B16GND_B19B19GND_B22B22GND_B25B25GND_B28B28REFCLK_n0B14REFCLK_p0B15PET_n0B17PET_p0B18PET_n1B20PET_p1B21PET_n2B23PET_p2B24PET_n3B26PET_p3B27SMBCLKA7SMBDATA8SMBRST#A9LED#_ACTIVITYA10PERST0#B10PERST1#_CLKREQ#A11PRSNT0#A12GND_A13A13GND_A16A16GND_A19A19GND_A22A22GND_A25A25GND_A28A28REFCLK_n1A14REFCLK_p1A15PER_n0A17PER_p0A18PER_n1A20PER_p1A21PER_n2A23PER_p2A24PER_n3A26PER_p3A27G2G2G1G1C38940.1UF25V10%X6SC27650.1UF25V10%C0402-0201X7R
C968 0.1UF25V 10% C0402-0201X6S
C38870.1UF25V10%X6SR57351K1%R0402-0201<Part Number>C38950.1UF25V10%X6SU401BSS138K<Part Number>GDS
C38880.1UF25V10%X6S
R418 4.7K 1/16W1%C27660.1UF25V10%C0402-0201X7R
J32SCONN56_1-2327679-3P12V_B1B1P12V_B2B2P12V_B3B3P12V_B4B4P12V_B5B5P12V_B6B6GND_A1A1GND_A2A2GND_A3A3GND_A4A4GND_A5A5GND_A6A6MFGB7RFUB8DUALPORTEN#B9P3V3_AUXB11PWRDISB12GND_B13B13GND_B16B16GND_B19B19GND_B22B22GND_B25B25GND_B28B28REFCLK_n0B14REFCLK_p0B15PET_n0B17PET_p0B18PET_n1B20PET_p1B21PET_n2B23PET_p2B24PET_n3B26PET_p3B27SMBCLKA7SMBDATA8SMBRST#A9LED#_ACTIVITYA10PERST0#B10PERST1#_CLKREQ#A11PRSNT0#A12GND_A13A13GND_A16A16GND_A19A19GND_A22A22GND_A25A25GND_A28A28REFCLK_n1A14REFCLK_p1A15PER_n0A17PER_p0A18PER_n1A20PER_p1A21PER_n2A23PER_p2A24PER_n3A26PER_p3A27G2G2G1G1C38960.1UF25V10%X6SR5736 33R41910KR0402-02015%1/16W
C38890.1UF25V10%X6S
C38970.1UF25V10%X6S
C38900.1UF25V10%X6S
R420 4.7K 1/16W1%NIC967 0.1UF25V 10% C0402-0201X6SC38980.1UF25V10%X6S
C38910.1UF25V10%X6SU400BSS138K<Part Number>GDSC38990.1UF25V10%X6S<Part Number>
R415 4.7K 1/16W1%C38920.1UF25V10%X6S<Part Number>R41710KR0402-02015%1/16WR40564.7KR0402-02011%1/16WP5E_PEX0_STN2_TX_C_DN<36>P5E_PEX0_STN2_RX_DN<36>P5E_PEX0_STN2_TX_C_DP<36>P5E_PEX0_STN2_RX_DP<36>P5E_PEX0_STN2_TX_C_DN<37>P5E_PEX0_STN2_RX_DN<37>P5E_PEX0_STN2_TX_C_DP<37>P5E_PEX0_STN2_RX_DP<37>P5E_PEX0_STN2_TX_C_DN<38>P5E_PEX0_STN2_RX_DN<38>P5E_PEX0_STN2_TX_C_DP<38>P5E_PEX0_STN2_RX_DP<38>P5E_PEX0_STN2_TX_C_DN<39>P5E_PEX0_STN2_RX_DN<39>P5E_PEX0_STN2_TX_C_DP<39>P5E_PEX0_STN2_RX_DP<39>P5E_PEX0_STN2_TX_C_DN<32>P5E_PEX0_STN2_RX_DN<32>P5E_PEX0_STN2_TX_C_DP<32>P5E_PEX0_STN2_RX_DP<32>P5E_PEX0_STN2_TX_C_DN<33>P5E_PEX0_STN2_RX_DN<33>P5E_PEX0_STN2_TX_C_DP<33>P5E_PEX0_STN2_RX_DP<33>P5E_PEX0_STN2_TX_C_DN<34>P5E_PEX0_STN2_RX_DN<34>P5E_PEX0_STN2_TX_C_DP<34>P5E_PEX0_STN2_RX_DP<34>P5E_PEX0_STN2_TX_C_DN<35>P5E_PEX0_STN2_RX_DN<35>P5E_PEX0_STN2_TX_C_DP<35>P5E_PEX0_STN2_RX_DP<35>
DUALPORT_N_SSD2RST_SMB_SSD2_ISO_R_NRST_SSD2_PERST_R_NPU_CLKREQ2SSD2_PWRDIS_R
DUALPORT_N_SSD3RST_SMB_SSD3_ISO_R_NRST_SSD3_PERST_R_NPU_CLKREQ3SSD3_PWRDIS_R
SMB_ISO_SSD2_R_SCLSMB_ISO_SSD2_R_SDA
SMB_ISO_SSD3_R_SCLSMB_ISO_SSD3_R_SDA
CLK_100M_DB800ZL_SSD2_R_DNCLK_100M_DB800ZL_SSD2_R_DP
CLK_100M_DB800ZL_SSD3_R_DNCLK_100M_DB800ZL_SSD3_R_DP
PRSNT_SSD2_N
PRSNT_SSD3_NSSD2_LED_ISO_N
SSD3_LED_ISO_N



5
5
4
4
3
3
2
2
1
1
D D
C C
B B
A A
SSD_4/5
SSD4
SSD5
P5E_PEX1_STN2_TX_C_DN<44>[24]P5E_PEX1_STN2_RX_DN<44> [24]P5E_PEX1_STN2_TX_C_DP<44>[24]P5E_PEX1_STN2_RX_DP<44> [24]P5E_PEX1_STN2_TX_C_DN<45>[24]P5E_PEX1_STN2_RX_DN<45> [24]P5E_PEX1_STN2_TX_C_DP<45>[24]P5E_PEX1_STN2_RX_DP<45> [24]P5E_PEX1_STN2_TX_C_DN<46>[24]P5E_PEX1_STN2_RX_DN<46> [24]P5E_PEX1_STN2_TX_C_DP<46>[24]P5E_PEX1_STN2_RX_DP<46> [24]P5E_PEX1_STN2_TX_C_DN<47>[24]P5E_PEX1_STN2_RX_DN<47> [24]P5E_PEX1_STN2_TX_C_DP<47>[24]P5E_PEX1_STN2_RX_DP<47> [24]P5E_PEX1_STN2_TX_C_DN<40>[24]P5E_PEX1_STN2_RX_DN<40> [24]P5E_PEX1_STN2_TX_C_DP<40>[24]P5E_PEX1_STN2_RX_DP<40> [24]P5E_PEX1_STN2_TX_C_DN<41>[24]P5E_PEX1_STN2_RX_DN<41> [24]P5E_PEX1_STN2_TX_C_DP<41>[24]P5E_PEX1_STN2_RX_DP<41> [24]P5E_PEX1_STN2_TX_C_DN<42>[24]P5E_PEX1_STN2_RX_DN<42> [24]P5E_PEX1_STN2_TX_C_DP<42>[24]P5E_PEX1_STN2_RX_DP<42> [24]P5E_PEX1_STN2_TX_C_DN<43>[24]P5E_PEX1_STN2_RX_DN<43> [24]P5E_PEX1_STN2_TX_C_DP<43>[24]P5E_PEX1_STN2_RX_DP<43> [24]
RST_SMB_SSD4_ISO_R_N [101]RST_SSD4_PERST_R_N[115]SSD4_LED_ISO_R_N [196]SSD4_PWRDIS_R[115,196]
RST_SMB_SSD5_ISO_R_N [101]RST_SSD5_PERST_R_N[115]SSD5_LED_ISO_R_N [196]SSD5_PWRDIS_R[115,196]
SMB_ISO_SSD4_R_SCL [97]SMB_ISO_SSD4_R_SDA [97]
SMB_ISO_SSD5_R_SCL [97]SMB_ISO_SSD5_R_SDA [97]
CLK_100M_DB800ZL_SSD4_R_DN[80]CLK_100M_DB800ZL_SSD4_R_DP[80]
CLK_100M_DB800ZL_SSD5_R_DN[80]CLK_100M_DB800ZL_SSD5_R_DP[80]
PRSNT_SSD4_R_N [86,115,202]
PRSNT_SSD5_R_N [86,115,202]SSD4_LED_ISO_R_N [196]SSD4_LED_R[90]SSD5_LED_ISO_R_N [196]SSD5_LED_R[90]
SSD4_PWRDIS_R [115,196]
SSD5_PWRDIS_R [115,196]
P12V_SSD4
P12V_SSD5
P3V3_SSD4P3V3_SSD4P3V3_SSD4P3V3_SSD5P3V3_SSD5P3V3_SSD5
P3V3_AUX
P3V3_AUXP3V3_SSD4
P3V3_SSD5
P12V_SSD4
P12V_SSD5
SizeDoc NumberRevDate: SheetofReviewerDesignerDepartmentProject
Page TitleCCBU D196 257Tuesday, August 29, 2023<project_name><Designer> GRANDTETON_SWB_20230829196 SSD_4/5<Reviewer>SizeDoc NumberRevDate: SheetofReviewerDesignerDepartmentProject
Page TitleCCBU D196 257Tuesday, August 29, 2023<project_name><Designer> GRANDTETON_SWB_20230829196 SSD_4/5<Reviewer>SizeDoc NumberRevDate: SheetofReviewerDesignerDepartmentProject
Page TitleCCBU D196 257Tuesday, August 29, 2023<project_name><Designer> GRANDTETON_SWB_20230829196 SSD_4/5<Reviewer>
C27670.1UF25V10%C0402-0201X7RC39080.1UF25V10%X6S
R423 4.7K 1/16W1%NI U402BSS138K<Part Number>GDSR6202 4.7K 5% R0402-0201C39090.1UF25V10%X6SR40624.7KR0402-02011%1/16W
C39001UFX6SC0402-020110%25V<Part Number>
R6203 4.7K 5% R0402-0201C39100.1UF25V10%X6SC970 0.1UF25V 10% C0402-0201X6SJ35SCONN56_1-2327679-3P12V_B1B1P12V_B2B2P12V_B3B3P12V_B4B4P12V_B5B5P12V_B6B6GND_A1A1GND_A2A2GND_A3A3GND_A4A4GND_A5A5GND_A6A6MFGB7RFUB8DUALPORTEN#B9P3V3_AUXB11PWRDISB12GND_B13B13GND_B16B16GND_B19B19GND_B22B22GND_B25B25GND_B28B28REFCLK_n0B14REFCLK_p0B15PET_n0B17PET_p0B18PET_n1B20PET_p1B21PET_n2B23PET_p2B24PET_n3B26PET_p3B27SMBCLKA7SMBDATA8SMBRST#A9LED#_ACTIVITYA10PERST0#B10PERST1#_CLKREQ#A11PRSNT0#A12GND_A13A13GND_A16A16GND_A19A19GND_A22A22GND_A25A25GND_A28A28REFCLK_n1A14REFCLK_p1A15PER_n0A17PER_p0A18PER_n1A20PER_p1A21PER_n2A23PER_p2A24PER_n3A26PER_p3A27G2G2G1G1R4063 0 5% R0402-0201
C39010.1UF25V10%X6S
R57411K1%R0402-0201<Part Number>C39110.1UF25V10%X6SSCREW_SSD4_1<Part Number>1
R424 4.7K 1/16W1%J34_OTH<Part Number>1C39020.1UF25V10%X6S
SCREW_SSD5_1<Part Number>1
SCREW_SSD4_2<Part Number>1C39120.1UF25V10%X6SJ35_OTH<Part Number>1 R5742 33R42610KR0402-02015%1/16W
J34SCONN56_1-2327679-3P12V_B1B1P12V_B2B2P12V_B3B3P12V_B4B4P12V_B5B5P12V_B6B6GND_A1A1GND_A2A2GND_A3A3GND_A4A4GND_A5A5GND_A6A6MFGB7RFUB8DUALPORTEN#B9P3V3_AUXB11PWRDISB12GND_B13B13GND_B16B16GND_B19B19GND_B22B22GND_B25B25GND_B28B28REFCLK_n0B14REFCLK_p0B15PET_n0B17PET_p0B18PET_n1B20PET_p1B21PET_n2B23PET_p2B24PET_n3B26PET_p3B27SMBCLKA7SMBDATA8SMBRST#A9LED#_ACTIVITYA10PERST0#B10PERST1#_CLKREQ#A11PRSNT0#A12GND_A13A13GND_A16A16GND_A19A19GND_A22A22GND_A25A25GND_A28A28REFCLK_n1A14REFCLK_p1A15PER_n0A17PER_p0A18PER_n1A20PER_p1A21PER_n2A23PER_p2A24PER_n3A26PER_p3A27G2G2G1G1SCREW_SSD5_2<Part Number>1 C27680.1UF25V10%C0402-0201X7R
C39030.1UF25V10%X6S
C39130.1UF25V10%X6S<Part Number>
R40604.7KR0402-02011%1/16WC39040.1UF25V10%X6S
R425 4.7K 1/16W1%NIC969 0.1UF25V 10% C0402-0201X6SR57391K1%R0402-0201<Part Number>
U403BSS138K<Part Number>GDS
C39050.1UF25V10%X6SR4061 0 5% R0402-0201R421 4.7K 1/16W1%R5740 33C39060.1UF25V10%X6S<Part Number>R42210KR0402-02015%1/16WC39071UFX6SC0402-020110%25V<Part Number>P5E_PEX1_STN2_TX_C_DN<44>P5E_PEX1_STN2_RX_DN<44>P5E_PEX1_STN2_TX_C_DP<44>P5E_PEX1_STN2_RX_DP<44>P5E_PEX1_STN2_TX_C_DN<45>P5E_PEX1_STN2_RX_DN<45>P5E_PEX1_STN2_TX_C_DP<45>P5E_PEX1_STN2_RX_DP<45>P5E_PEX1_STN2_TX_C_DN<46>P5E_PEX1_STN2_RX_DN<46>P5E_PEX1_STN2_TX_C_DP<46>P5E_PEX1_STN2_RX_DP<46>P5E_PEX1_STN2_TX_C_DN<47>P5E_PEX1_STN2_RX_DN<47>P5E_PEX1_STN2_TX_C_DP<47>P5E_PEX1_STN2_RX_DP<47>P5E_PEX1_STN2_TX_C_DN<40>P5E_PEX1_STN2_RX_DN<40>P5E_PEX1_STN2_TX_C_DP<40>P5E_PEX1_STN2_RX_DP<40>P5E_PEX1_STN2_TX_C_DN<41>P5E_PEX1_STN2_RX_DN<41>P5E_PEX1_STN2_TX_C_DP<41>P5E_PEX1_STN2_RX_DP<41>P5E_PEX1_STN2_TX_C_DN<42>P5E_PEX1_STN2_RX_DN<42>P5E_PEX1_STN2_TX_C_DP<42>P5E_PEX1_STN2_RX_DP<42>P5E_PEX1_STN2_TX_C_DN<43>P5E_PEX1_STN2_RX_DN<43>P5E_PEX1_STN2_TX_C_DP<43>P5E_PEX1_STN2_RX_DP<43>
DUALPORT_N_SSD4RST_SMB_SSD4_ISO_R_NRST_SSD4_PERST_R_NPU_CLKREQ4SSD4_PWRDIS_R
DUALPORT_N_SSD5RST_SMB_SSD5_ISO_R_NRST_SSD5_PERST_R_NPU_CLKREQ5SSD5_PWRDIS_R
SMB_ISO_SSD4_R_SCLSMB_ISO_SSD4_R_SDA
SMB_ISO_SSD5_R_SCLSMB_ISO_SSD5_R_SDA
CLK_100M_DB800ZL_SSD4_R_DNCLK_100M_DB800ZL_SSD4_R_DP
CLK_100M_DB800ZL_SSD5_R_DNCLK_100M_DB800ZL_SSD5_R_DP
PRSNT_SSD4_N
PRSNT_SSD5_NSSD4_LED_ISO_N
SSD5_LED_ISO_N



5
5
4
4
3
3
2
2
1
1
D D
C C
B B
A A
SSD_6/7
SSD6
SSD7
P5E_PEX1_STN2_TX_C_DN<36>[24]P5E_PEX1_STN2_RX_DN<36> [24]P5E_PEX1_STN2_TX_C_DP<36>[24]P5E_PEX1_STN2_RX_DP<36> [24]P5E_PEX1_STN2_TX_C_DN<37>[24]P5E_PEX1_STN2_RX_DN<37> [24]P5E_PEX1_STN2_TX_C_DP<37>[24]P5E_PEX1_STN2_RX_DP<37> [24]P5E_PEX1_STN2_TX_C_DN<38>[24]P5E_PEX1_STN2_RX_DN<38> [24]P5E_PEX1_STN2_TX_C_DP<38>[24]P5E_PEX1_STN2_RX_DP<38> [24]P5E_PEX1_STN2_TX_C_DN<39>[24]P5E_PEX1_STN2_RX_DN<39> [24]P5E_PEX1_STN2_TX_C_DP<39>[24]P5E_PEX1_STN2_RX_DP<39> [24]P5E_PEX1_STN2_TX_C_DN<32>[24]P5E_PEX1_STN2_RX_DN<32> [24]P5E_PEX1_STN2_TX_C_DP<32>[24]P5E_PEX1_STN2_RX_DP<32> [24]P5E_PEX1_STN2_TX_C_DN<33>[24]P5E_PEX1_STN2_RX_DN<33> [24]P5E_PEX1_STN2_TX_C_DP<33>[24]P5E_PEX1_STN2_RX_DP<33> [24]P5E_PEX1_STN2_TX_C_DN<34>[24]P5E_PEX1_STN2_RX_DN<34> [24]P5E_PEX1_STN2_TX_C_DP<34>[24]P5E_PEX1_STN2_RX_DP<34> [24]P5E_PEX1_STN2_TX_C_DN<35>[24]P5E_PEX1_STN2_RX_DN<35> [24]P5E_PEX1_STN2_TX_C_DP<35>[24]P5E_PEX1_STN2_RX_DP<35> [24]
RST_SMB_SSD6_ISO_R_N [101]RST_SSD6_PERST_R_N[115]SSD6_LED_ISO_R_N [197]SSD6_PWRDIS_R[115,197]
RST_SMB_SSD7_ISO_R_N [101]RST_SSD7_PERST_R_N[115]SSD7_LED_ISO_R_N [197]SSD7_PWRDIS_R[115,197]
SMB_ISO_SSD6_R_SCL [97]SMB_ISO_SSD6_R_SDA [97]
SMB_ISO_SSD7_R_SCL [97]SMB_ISO_SSD7_R_SDA [97]
CLK_100M_DB800ZL_SSD6_R_DN[80]CLK_100M_DB800ZL_SSD6_R_DP[80]
CLK_100M_DB800ZL_SSD7_R_DN[80]CLK_100M_DB800ZL_SSD7_R_DP[80]
PRSNT_SSD6_R_N [86,115,202]
PRSNT_SSD7_R_N [86,115,202]SSD6_LED_ISO_R_N [197]SSD6_LED_R[90]SSD7_LED_ISO_R_N [197]SSD7_LED_R[90]
SSD6_PWRDIS_R [115,197]
SSD7_PWRDIS_R [115,197]
P12V_SSD6
P12V_SSD7
P3V3_SSD6P3V3_SSD6P3V3_SSD6P3V3_SSD7P3V3_SSD7P3V3_SSD7
P3V3_AUX
P3V3_AUXP3V3_SSD6
P3V3_SSD7
P12V_SSD6
P12V_SSD7
SizeDoc NumberRevDate: SheetofReviewerDesignerDepartmentProject
Page TitleCCBU D197 257Tuesday, August 29, 2023<project_name><Designer> GRANDTETON_SWB_20230829197 SSD_6/7<Reviewer>SizeDoc NumberRevDate: SheetofReviewerDesignerDepartmentProject
Page TitleCCBU D197 257Tuesday, August 29, 2023<project_name><Designer> GRANDTETON_SWB_20230829197 SSD_6/7<Reviewer>SizeDoc NumberRevDate: SheetofReviewerDesignerDepartmentProject
Page TitleCCBU D197 257Tuesday, August 29, 2023<project_name><Designer> GRANDTETON_SWB_20230829197 SSD_6/7<Reviewer>
C39160.1UF25V10%X6S
C39240.1UF25V10%X6SR432 4.7K 1/16W1%NIC971 0.1UF25V 10% C0402-0201X6SC39170.1UF25V10%X6S
C39250.1UF25V10%X6SC27700.1UF25V10%C0402-0201X7R
R427 4.7K 1/16W1%C27690.1UF25V10%C0402-0201X7RR57431K1%R0402-0201<Part Number>
U405BSS138K<Part Number>GDS
C39180.1UF25V10%X6S
C39260.1UF25V10%X6S
R42910KR0402-02015%1/16WR5744 33C39190.1UF25V10%X6SR6204 4.7K 5% R0402-0201C39270.1UF25V10%X6S<Part Number>J37SCONN56_1-2327679-3P12V_B1B1P12V_B2B2P12V_B3B3P12V_B4B4P12V_B5B5P12V_B6B6GND_A1A1GND_A2A2GND_A3A3GND_A4A4GND_A5A5GND_A6A6MFGB7RFUB8DUALPORTEN#B9P3V3_AUXB11PWRDISB12GND_B13B13GND_B16B16GND_B19B19GND_B22B22GND_B25B25GND_B28B28REFCLK_n0B14REFCLK_p0B15PET_n0B17PET_p0B18PET_n1B20PET_p1B21PET_n2B23PET_p2B24PET_n3B26PET_p3B27SMBCLKA7SMBDATA8SMBRST#A9LED#_ACTIVITYA10PERST0#B10PERST1#_CLKREQ#A11PRSNT0#A12GND_A13A13GND_A16A16GND_A19A19GND_A22A22GND_A25A25GND_A28A28REFCLK_n1A14REFCLK_p1A15PER_n0A17PER_p0A18PER_n1A20PER_p1A21PER_n2A23PER_p2A24PER_n3A26PER_p3A27G2G2G1G1SCREW_SSD7_1<Part Number>1
R428 4.7K 1/16W1%NIC39200.1UF25V10%X6S<Part Number>
R6205 4.7K 5% R0402-0201
SCREW_SSD6_1<Part Number>1
SCREW_SSD7_2<Part Number>1
SCREW_SSD6_2<Part Number>1 U404BSS138K<Part Number>GDSJ36SCONN56_1-2327679-3P12V_B1B1P12V_B2B2P12V_B3B3P12V_B4B4P12V_B5B5P12V_B6B6GND_A1A1GND_A2A2GND_A3A3GND_A4A4GND_A5A5GND_A6A6MFGB7RFUB8DUALPORTEN#B9P3V3_AUXB11PWRDISB12GND_B13B13GND_B16B16GND_B19B19GND_B22B22GND_B25B25GND_B28B28REFCLK_n0B14REFCLK_p0B15PET_n0B17PET_p0B18PET_n1B20PET_p1B21PET_n2B23PET_p2B24PET_n3B26PET_p3B27SMBCLKA7SMBDATA8SMBRST#A9LED#_ACTIVITYA10PERST0#B10PERST1#_CLKREQ#A11PRSNT0#A12GND_A13A13GND_A16A16GND_A19A19GND_A22A22GND_A25A25GND_A28A28REFCLK_n1A14REFCLK_p1A15PER_n0A17PER_p0A18PER_n1A20PER_p1A21PER_n2A23PER_p2A24PER_n3A26PER_p3A27G2G2G1G1C972 0.1UF25V 10% C0402-0201X6S
J36_OTH<Part Number>1C39211UFX6SC0402-020110%25V<Part Number>J37_OTH<Part Number>1R430 4.7K 1/16W1%
C39141UFX6SC0402-020110%25V<Part Number>
R40664.7KR0402-02011%1/16W
R40644.7KR0402-02011%1/16WC39220.1UF25V10%X6SR57451K1%R0402-0201<Part Number>R43110KR0402-02015%1/16W
C39150.1UF25V10%X6S
R4067 0 5% R0402-0201C39230.1UF25V10%X6SR4065 0 5% R0402-0201
R5746 33
P5E_PEX1_STN2_TX_C_DN<36>P5E_PEX1_STN2_RX_DN<36>P5E_PEX1_STN2_TX_C_DP<36>P5E_PEX1_STN2_RX_DP<36>P5E_PEX1_STN2_TX_C_DN<37>P5E_PEX1_STN2_RX_DN<37>P5E_PEX1_STN2_TX_C_DP<37>P5E_PEX1_STN2_RX_DP<37>P5E_PEX1_STN2_TX_C_DN<38>P5E_PEX1_STN2_RX_DN<38>P5E_PEX1_STN2_TX_C_DP<38>P5E_PEX1_STN2_RX_DP<38>P5E_PEX1_STN2_TX_C_DN<39>P5E_PEX1_STN2_RX_DN<39>P5E_PEX1_STN2_TX_C_DP<39>P5E_PEX1_STN2_RX_DP<39>P5E_PEX1_STN2_TX_C_DN<32>P5E_PEX1_STN2_RX_DN<32>P5E_PEX1_STN2_TX_C_DP<32>P5E_PEX1_STN2_RX_DP<32>P5E_PEX1_STN2_TX_C_DN<33>P5E_PEX1_STN2_RX_DN<33>P5E_PEX1_STN2_TX_C_DP<33>P5E_PEX1_STN2_RX_DP<33>P5E_PEX1_STN2_TX_C_DN<34>P5E_PEX1_STN2_RX_DN<34>P5E_PEX1_STN2_TX_C_DP<34>P5E_PEX1_STN2_RX_DP<34>P5E_PEX1_STN2_TX_C_DN<35>P5E_PEX1_STN2_RX_DN<35>P5E_PEX1_STN2_TX_C_DP<35>P5E_PEX1_STN2_RX_DP<35>
DUALPORT_N_SSD6RST_SMB_SSD6_ISO_R_NRST_SSD6_PERST_R_NPU_CLKREQ6SSD6_PWRDIS_R
DUALPORT_N_SSD7RST_SMB_SSD7_ISO_R_NRST_SSD7_PERST_R_NPU_CLKREQ7SSD7_PWRDIS_R
SMB_ISO_SSD6_R_SCLSMB_ISO_SSD6_R_SDA
SMB_ISO_SSD7_R_SCLSMB_ISO_SSD7_R_SDA
CLK_100M_DB800ZL_SSD6_R_DNCLK_100M_DB800ZL_SSD6_R_DP
CLK_100M_DB800ZL_SSD7_R_DNCLK_100M_DB800ZL_SSD7_R_DP
PRSNT_SSD6_N
PRSNT_SSD7_NSSD6_LED_ISO_N
SSD7_LED_ISO_N



5
5
4
4
3
3
2
2
1
1
D D
C C
B B
A A
SSD_8/9
SSD8
SSD9
P5E_PEX2_STN2_TX_C_DN<44>[37]P5E_PEX2_STN2_RX_DN<44> [37]P5E_PEX2_STN2_TX_C_DP<44>[37]P5E_PEX2_STN2_RX_DP<44> [37]P5E_PEX2_STN2_TX_C_DN<45>[37]P5E_PEX2_STN2_RX_DN<45> [37]P5E_PEX2_STN2_TX_C_DP<45>[37]P5E_PEX2_STN2_RX_DP<45> [37]P5E_PEX2_STN2_TX_C_DN<46>[37]P5E_PEX2_STN2_RX_DN<46> [37]P5E_PEX2_STN2_TX_C_DP<46>[37]P5E_PEX2_STN2_RX_DP<46> [37]P5E_PEX2_STN2_TX_C_DN<47>[37]P5E_PEX2_STN2_RX_DN<47> [37]P5E_PEX2_STN2_TX_C_DP<47>[37]P5E_PEX2_STN2_RX_DP<47> [37]P5E_PEX2_STN2_TX_C_DN<40>[37]P5E_PEX2_STN2_RX_DN<40> [37]P5E_PEX2_STN2_TX_C_DP<40>[37]P5E_PEX2_STN2_RX_DP<40> [37]P5E_PEX2_STN2_TX_C_DN<41>[37]P5E_PEX2_STN2_RX_DN<41> [37]P5E_PEX2_STN2_TX_C_DP<41>[37]P5E_PEX2_STN2_RX_DP<41> [37]P5E_PEX2_STN2_TX_C_DN<42>[37]P5E_PEX2_STN2_RX_DN<42> [37]P5E_PEX2_STN2_TX_C_DP<42>[37]P5E_PEX2_STN2_RX_DP<42> [37]P5E_PEX2_STN2_TX_C_DN<43>[37]P5E_PEX2_STN2_RX_DN<43> [37]P5E_PEX2_STN2_TX_C_DP<43>[37]P5E_PEX2_STN2_RX_DP<43> [37]
RST_SMB_SSD8_ISO_R_N [102]RST_SSD8_PERST_R_N[117]SSD8_LED_ISO_R_N [198]SSD8_PWRDIS_R[117,198]
RST_SMB_SSD9_ISO_R_N [102]RST_SSD9_PERST_R_N[117]SSD9_LED_ISO_R_N [198]SSD9_PWRDIS_R[117,198]
SMB_ISO_SSD8_R_SCL [98]SMB_ISO_SSD8_R_SDA [98]
SMB_ISO_SSD9_R_SCL [98]SMB_ISO_SSD9_R_SDA [98]
CLK_100M_DB800ZL_SSD8_R_DN[81]CLK_100M_DB800ZL_SSD8_R_DP[81]
CLK_100M_DB800ZL_SSD9_R_DN[81]CLK_100M_DB800ZL_SSD9_R_DP[81]
PRSNT_SSD8_R_N [86,117,203]
PRSNT_SSD9_R_N [86,117,203]SSD8_LED_ISO_R_N [198]SSD8_LED_R[90]SSD9_LED_ISO_R_N [198]SSD9_LED_R[90]
SSD8_PWRDIS_R [117,198]
SSD9_PWRDIS_R [117,198]
P12V_SSD8
P12V_SSD9
P3V3_SSD8P3V3_SSD8P3V3_SSD8P3V3_SSD9P3V3_SSD9P3V3_SSD9
P3V3_AUX
P3V3_AUXP3V3_SSD8
P3V3_SSD9
P12V_SSD8
P12V_SSD9SizeDoc NumberRevDate: SheetofReviewerDesignerDepartmentProject
Page TitleCCBU D198 257Tuesday, August 29, 2023<project_name><Designer> GRANDTETON_SWB_20230829198 SSD_8/9<Reviewer>SizeDoc NumberRevDate: SheetofReviewerDesignerDepartmentProject
Page TitleCCBU D198 257Tuesday, August 29, 2023<project_name><Designer> GRANDTETON_SWB_20230829198 SSD_8/9<Reviewer>SizeDoc NumberRevDate: SheetofReviewerDesignerDepartmentProject
Page TitleCCBU D198 257Tuesday, August 29, 2023<project_name><Designer> GRANDTETON_SWB_20230829198 SSD_8/9<Reviewer>U413BSS138K<Part Number>GDSJ39_OTH<Part Number>1
R434 4.7K 1/16W1%NIC39330.1UF25V10%X6S
C39410.1UF25V10%X6S<Part Number>R4071 0 5% R0402-0201R5760 33C39340.1UF25V10%X6S<Part Number>
C974 0.1UF25V 10% C0402-0201X6SSCREW_SSD9_1<Part Number>1 C27720.1UF25V10%C0402-0201X7RU412BSS138K<Part Number>GDSJ39SCONN56_1-2327679-3P12V_B1B1P12V_B2B2P12V_B3B3P12V_B4B4P12V_B5B5P12V_B6B6GND_A1A1GND_A2A2GND_A3A3GND_A4A4GND_A5A5GND_A6A6MFGB7RFUB8DUALPORTEN#B9P3V3_AUXB11PWRDISB12GND_B13B13GND_B16B16GND_B19B19GND_B22B22GND_B25B25GND_B28B28REFCLK_n0B14REFCLK_p0B15PET_n0B17PET_p0B18PET_n1B20PET_p1B21PET_n2B23PET_p2B24PET_n3B26PET_p3B27SMBCLKA7SMBDATA8SMBRST#A9LED#_ACTIVITYA10PERST0#B10PERST1#_CLKREQ#A11PRSNT0#A12GND_A13A13GND_A16A16GND_A19A19GND_A22A22GND_A25A25GND_A28A28REFCLK_n1A14REFCLK_p1A15PER_n0A17PER_p0A18PER_n1A20PER_p1A21PER_n2A23PER_p2A24PER_n3A26PER_p3A27G2G2G1G1R436 4.7K 1/16W1%
R40684.7KR0402-02011%1/16W
C39351UFX6SC0402-020110%25V<Part Number>SCREW_SSD9_2<Part Number>1
SCREW_SSD8_1<Part Number>1 R43810KR0402-02015%1/16WSCREW_SSD8_2<Part Number>1C39281UFX6SC0402-020110%25V<Part Number>R4069 0 5% R0402-0201C39360.1UF25V10%X6S
J38SCONN56_1-2327679-3P12V_B1B1P12V_B2B2P12V_B3B3P12V_B4B4P12V_B5B5P12V_B6B6GND_A1A1GND_A2A2GND_A3A3GND_A4A4GND_A5A5GND_A6A6MFGB7RFUB8DUALPORTEN#B9P3V3_AUXB11PWRDISB12GND_B13B13GND_B16B16GND_B19B19GND_B22B22GND_B25B25GND_B28B28REFCLK_n0B14REFCLK_p0B15PET_n0B17PET_p0B18PET_n1B20PET_p1B21PET_n2B23PET_p2B24PET_n3B26PET_p3B27SMBCLKA7SMBDATA8SMBRST#A9LED#_ACTIVITYA10PERST0#B10PERST1#_CLKREQ#A11PRSNT0#A12GND_A13A13GND_A16A16GND_A19A19GND_A22A22GND_A25A25GND_A28A28REFCLK_n1A14REFCLK_p1A15PER_n0A17PER_p0A18PER_n1A20PER_p1A21PER_n2A23PER_p2A24PER_n3A26PER_p3A27G2G2G1G1R6206 4.7K 5% R0402-0201
R57611K1%R0402-0201<Part Number>
C39290.1UF25V10%X6S
C39370.1UF25V10%X6SR437 4.7K 1/16W1%NIR6207 4.7K 5% R0402-0201
C973 0.1UF25V 10% C0402-0201X6SC39300.1UF25V10%X6S
C39380.1UF25V10%X6SR5762 33
C27710.1UF25V10%C0402-0201X7RR433 4.7K 1/16W1%C39310.1UF25V10%X6S
C39390.1UF25V10%X6S
R43510KR0402-02015%1/16WJ38_OTH<Part Number>1C39320.1UF25V10%X6S
C39400.1UF25V10%X6SR40704.7KR0402-02011%1/16WR57591K1%R0402-0201<Part Number>P5E_PEX2_STN2_TX_C_DN<44>P5E_PEX2_STN2_RX_DN<44>P5E_PEX2_STN2_TX_C_DP<44>P5E_PEX2_STN2_RX_DP<44>P5E_PEX2_STN2_TX_C_DN<45>P5E_PEX2_STN2_RX_DN<45>P5E_PEX2_STN2_TX_C_DP<45>P5E_PEX2_STN2_RX_DP<45>P5E_PEX2_STN2_TX_C_DN<46>P5E_PEX2_STN2_RX_DN<46>P5E_PEX2_STN2_TX_C_DP<46>P5E_PEX2_STN2_RX_DP<46>P5E_PEX2_STN2_TX_C_DN<47>P5E_PEX2_STN2_RX_DN<47>P5E_PEX2_STN2_TX_C_DP<47>P5E_PEX2_STN2_RX_DP<47>P5E_PEX2_STN2_TX_C_DN<40>P5E_PEX2_STN2_RX_DN<40>P5E_PEX2_STN2_TX_C_DP<40>P5E_PEX2_STN2_RX_DP<40>P5E_PEX2_STN2_TX_C_DN<41>P5E_PEX2_STN2_RX_DN<41>P5E_PEX2_STN2_TX_C_DP<41>P5E_PEX2_STN2_RX_DP<41>P5E_PEX2_STN2_TX_C_DN<42>P5E_PEX2_STN2_RX_DN<42>P5E_PEX2_STN2_TX_C_DP<42>P5E_PEX2_STN2_RX_DP<42>P5E_PEX2_STN2_TX_C_DN<43>P5E_PEX2_STN2_RX_DN<43>P5E_PEX2_STN2_TX_C_DP<43>P5E_PEX2_STN2_RX_DP<43>
DUALPORT_N_SSD8RST_SMB_SSD8_ISO_R_NRST_SSD8_PERST_R_NPU_CLKREQ8SSD8_PWRDIS_R
DUALPORT_N_SSD9RST_SMB_SSD9_ISO_R_NRST_SSD9_PERST_R_NPU_CLKREQ9SSD9_PWRDIS_R
SMB_ISO_SSD8_R_SCLSMB_ISO_SSD8_R_SDA
SMB_ISO_SSD9_R_SCLSMB_ISO_SSD9_R_SDA
CLK_100M_DB800ZL_SSD8_R_DNCLK_100M_DB800ZL_SSD8_R_DP
CLK_100M_DB800ZL_SSD9_R_DNCLK_100M_DB800ZL_SSD9_R_DP
PRSNT_SSD8_N
PRSNT_SSD9_NSSD8_LED_ISO_N
SSD9_LED_ISO_N



5
5
4
4
3
3
2
2
1
1
D D
C C
B B
A A
SSD_10/11
SSD10
SSD11
P5E_PEX2_STN2_TX_C_DN<36>[37]P5E_PEX2_STN2_RX_DN<36> [37]P5E_PEX2_STN2_TX_C_DP<36>[37]P5E_PEX2_STN2_RX_DP<36> [37]P5E_PEX2_STN2_TX_C_DN<37>[37]P5E_PEX2_STN2_RX_DN<37> [37]P5E_PEX2_STN2_TX_C_DP<37>[37]P5E_PEX2_STN2_RX_DP<37> [37]P5E_PEX2_STN2_TX_C_DN<38>[37]P5E_PEX2_STN2_RX_DN<38> [37]P5E_PEX2_STN2_TX_C_DP<38>[37]P5E_PEX2_STN2_RX_DP<38> [37]P5E_PEX2_STN2_TX_C_DN<39>[37]P5E_PEX2_STN2_RX_DN<39> [37]P5E_PEX2_STN2_TX_C_DP<39>[37]P5E_PEX2_STN2_RX_DP<39> [37]P5E_PEX2_STN2_TX_C_DN<32>[37]P5E_PEX2_STN2_RX_DN<32> [37]P5E_PEX2_STN2_TX_C_DP<32>[37]P5E_PEX2_STN2_RX_DP<32> [37]P5E_PEX2_STN2_TX_C_DN<33>[37]P5E_PEX2_STN2_RX_DN<33> [37]P5E_PEX2_STN2_TX_C_DP<33>[37]P5E_PEX2_STN2_RX_DP<33> [37]P5E_PEX2_STN2_TX_C_DN<34>[37]P5E_PEX2_STN2_RX_DN<34> [37]P5E_PEX2_STN2_TX_C_DP<34>[37]P5E_PEX2_STN2_RX_DP<34> [37]P5E_PEX2_STN2_TX_C_DN<35>[37]P5E_PEX2_STN2_RX_DN<35> [37]P5E_PEX2_STN2_TX_C_DP<35>[37]P5E_PEX2_STN2_RX_DP<35> [37]
RST_SMB_SSD10_ISO_R_N [102]RST_SSD10_PERST_R_N[117]SSD10_LED_ISO_R_N [199]SSD10_PWRDIS_R[117,199]
RST_SMB_SSD11_ISO_R_N [102]RST_SSD11_PERST_R_N[117]SSD11_LED_ISO_R_N [199]SSD11_PWRDIS_R[117,199]
SMB_ISO_SSD10_R_SCL [98]SMB_ISO_SSD10_R_SDA [98]
SMB_ISO_SSD11_R_SCL [98]SMB_ISO_SSD11_R_SDA [98]
CLK_100M_DB800ZL_SSD10_R_DN[81]CLK_100M_DB800ZL_SSD10_R_DP[81]
CLK_100M_DB800ZL_SSD11_R_DN[81]CLK_100M_DB800ZL_SSD11_R_DP[81]
PRSNT_SSD10_R_N [86,117,203]
PRSNT_SSD11_R_N [86,117,203]SSD10_LED_ISO_R_N [199]SSD10_LED_R[90]SSD11_LED_ISO_R_N [199]SSD11_LED_R[90]
SSD10_PWRDIS_R [117,199]
SSD11_PWRDIS_R [117,199]
P12V_SSD10
P12V_SSD11
P3V3_SSD10P3V3_SSD10P3V3_SSD10P3V3_SSD11P3V3_SSD11P3V3_SSD11
P3V3_AUX
P3V3_AUXP3V3_SSD10
P3V3_SSD11
P12V_SSD10
P12V_SSD11SizeDoc NumberRevDate: SheetofReviewerDesignerDepartmentProject
Page TitleCCBU D199 257Tuesday, August 29, 2023<project_name><Designer> GRANDTETON_SWB_20230829199 SSD_10/11<Reviewer>SizeDoc NumberRevDate: SheetofReviewerDesignerDepartmentProject
Page TitleCCBU D199 257Tuesday, August 29, 2023<project_name><Designer> GRANDTETON_SWB_20230829199 SSD_10/11<Reviewer>SizeDoc NumberRevDate: SheetofReviewerDesignerDepartmentProject
Page TitleCCBU D199 257Tuesday, August 29, 2023<project_name><Designer> GRANDTETON_SWB_20230829199 SSD_10/11<Reviewer>J41SCONN56_1-2327679-3P12V_B1B1P12V_B2B2P12V_B3B3P12V_B4B4P12V_B5B5P12V_B6B6GND_A1A1GND_A2A2GND_A3A3GND_A4A4GND_A5A5GND_A6A6MFGB7RFUB8DUALPORTEN#B9P3V3_AUXB11PWRDISB12GND_B13B13GND_B16B16GND_B19B19GND_B22B22GND_B25B25GND_B28B28REFCLK_n0B14REFCLK_p0B15PET_n0B17PET_p0B18PET_n1B20PET_p1B21PET_n2B23PET_p2B24PET_n3B26PET_p3B27SMBCLKA7SMBDATA8SMBRST#A9LED#_ACTIVITYA10PERST0#B10PERST1#_CLKREQ#A11PRSNT0#A12GND_A13A13GND_A16A16GND_A19A19GND_A22A22GND_A25A25GND_A28A28REFCLK_n1A14REFCLK_p1A15PER_n0A17PER_p0A18PER_n1A20PER_p1A21PER_n2A23PER_p2A24PER_n3A26PER_p3A27G2G2G1G1R442 4.7K 1/16W1%R57551K1%R0402-0201<Part Number>C39491UFX6SC0402-020110%25V<Part Number>R40744.7KR0402-02011%1/16WU411BSS138K<Part Number>GDSR44410KR0402-02015%1/16W
J40SCONN56_1-2327679-3P12V_B1B1P12V_B2B2P12V_B3B3P12V_B4B4P12V_B5B5P12V_B6B6GND_A1A1GND_A2A2GND_A3A3GND_A4A4GND_A5A5GND_A6A6MFGB7RFUB8DUALPORTEN#B9P3V3_AUXB11PWRDISB12GND_B13B13GND_B16B16GND_B19B19GND_B22B22GND_B25B25GND_B28B28REFCLK_n0B14REFCLK_p0B15PET_n0B17PET_p0B18PET_n1B20PET_p1B21PET_n2B23PET_p2B24PET_n3B26PET_p3B27SMBCLKA7SMBDATA8SMBRST#A9LED#_ACTIVITYA10PERST0#B10PERST1#_CLKREQ#A11PRSNT0#A12GND_A13A13GND_A16A16GND_A19A19GND_A22A22GND_A25A25GND_A28A28REFCLK_n1A14REFCLK_p1A15PER_n0A17PER_p0A18PER_n1A20PER_p1A21PER_n2A23PER_p2A24PER_n3A26PER_p3A27G2G2G1G1J40_OTH<Part Number>1C39500.1UF25V10%X6SR5756 33C39421UFX6SC0402-020110%25V<Part Number>
R4075 0 5% R0402-0201SCREW_SSD11_1<Part Number>1
SCREW_SSD10_1<Part Number>1
J41_OTH<Part Number>1SCREW_SSD11_2<Part Number>1R443 4.7K 1/16W1%NIC39510.1UF25V10%X6SC975 0.1UF25V 10% C0402-0201X6SC39430.1UF25V10%X6SSCREW_SSD10_2<Part Number>1C39520.1UF25V10%X6S
R439 4.7K 1/16W1%C39440.1UF25V10%X6S
C27740.1UF25V10%C0402-0201X7RU410BSS138K<Part Number>GDSR40724.7KR0402-02011%1/16WR44110KR0402-02015%1/16W
C39530.1UF25V10%X6S
C39450.1UF25V10%X6SR4073 0 5% R0402-0201C39540.1UF25V10%X6S
C39460.1UF25V10%X6SR440 4.7K 1/16W1%NI
R57571K1%R0402-0201<Part Number>
R6208 4.7K 5% R0402-0201C39550.1UF25V10%X6S<Part Number>
C39470.1UF25V10%X6S
R6209 4.7K 5% R0402-0201R5758 33
C27730.1UF25V10%C0402-0201X7RC39480.1UF25V10%X6S<Part Number>
C976 0.1UF25V 10% C0402-0201X6SP5E_PEX2_STN2_TX_C_DN<36>P5E_PEX2_STN2_RX_DN<36>P5E_PEX2_STN2_TX_C_DP<36>P5E_PEX2_STN2_RX_DP<36>P5E_PEX2_STN2_TX_C_DN<37>P5E_PEX2_STN2_RX_DN<37>P5E_PEX2_STN2_TX_C_DP<37>P5E_PEX2_STN2_RX_DP<37>P5E_PEX2_STN2_TX_C_DN<38>P5E_PEX2_STN2_RX_DN<38>P5E_PEX2_STN2_TX_C_DP<38>P5E_PEX2_STN2_RX_DP<38>P5E_PEX2_STN2_TX_C_DN<39>P5E_PEX2_STN2_RX_DN<39>P5E_PEX2_STN2_TX_C_DP<39>P5E_PEX2_STN2_RX_DP<39>P5E_PEX2_STN2_TX_C_DN<32>P5E_PEX2_STN2_RX_DN<32>P5E_PEX2_STN2_TX_C_DP<32>P5E_PEX2_STN2_RX_DP<32>P5E_PEX2_STN2_TX_C_DN<33>P5E_PEX2_STN2_RX_DN<33>P5E_PEX2_STN2_TX_C_DP<33>P5E_PEX2_STN2_RX_DP<33>P5E_PEX2_STN2_TX_C_DN<34>P5E_PEX2_STN2_RX_DN<34>P5E_PEX2_STN2_TX_C_DP<34>P5E_PEX2_STN2_RX_DP<34>P5E_PEX2_STN2_TX_C_DN<35>P5E_PEX2_STN2_RX_DN<35>P5E_PEX2_STN2_TX_C_DP<35>P5E_PEX2_STN2_RX_DP<35>
DUALPORT_N_SSD10RST_SMB_SSD10_ISO_R_NRST_SSD10_PERST_R_NPU_CLKREQ10SSD10_PWRDIS_R
DUALPORT_N_SSD11RST_SMB_SSD11_ISO_R_NRST_SSD11_PERST_R_NPU_CLKREQ11SSD11_PWRDIS_R
SMB_ISO_SSD10_R_SCLSMB_ISO_SSD10_R_SDA
SMB_ISO_SSD11_R_SCLSMB_ISO_SSD11_R_SDA
CLK_100M_DB800ZL_SSD10_R_DNCLK_100M_DB800ZL_SSD10_R_DP
CLK_100M_DB800ZL_SSD11_R_DNCLK_100M_DB800ZL_SSD11_R_DP
PRSNT_SSD10_N
PRSNT_SSD11_NSSD10_LED_ISO_N
SSD11_LED_ISO_N



5
5
4
4
3
3
2
2
1
1
D D
C C
B B
A A
SSD_12/13
SSD12
SSD13
P5E_PEX3_STN2_TX_C_DN<44>[50]P5E_PEX3_STN2_RX_DN<44> [50]P5E_PEX3_STN2_TX_C_DP<44>[50]P5E_PEX3_STN2_RX_DP<44> [50]P5E_PEX3_STN2_TX_C_DN<45>[50]P5E_PEX3_STN2_RX_DN<45> [50]P5E_PEX3_STN2_TX_C_DP<45>[50]P5E_PEX3_STN2_RX_DP<45> [50]P5E_PEX3_STN2_TX_C_DN<46>[50]P5E_PEX3_STN2_RX_DN<46> [50]P5E_PEX3_STN2_TX_C_DP<46>[50]P5E_PEX3_STN2_RX_DP<46> [50]P5E_PEX3_STN2_TX_C_DN<47>[50]P5E_PEX3_STN2_RX_DN<47> [50]P5E_PEX3_STN2_TX_C_DP<47>[50]P5E_PEX3_STN2_RX_DP<47> [50]P5E_PEX3_STN2_TX_C_DN<40>[50]P5E_PEX3_STN2_RX_DN<40> [50]P5E_PEX3_STN2_TX_C_DP<40>[50]P5E_PEX3_STN2_RX_DP<40> [50]P5E_PEX3_STN2_TX_C_DN<41>[50]P5E_PEX3_STN2_RX_DN<41> [50]P5E_PEX3_STN2_TX_C_DP<41>[50]P5E_PEX3_STN2_RX_DP<41> [50]P5E_PEX3_STN2_TX_C_DN<42>[50]P5E_PEX3_STN2_RX_DN<42> [50]P5E_PEX3_STN2_TX_C_DP<42>[50]P5E_PEX3_STN2_RX_DP<42> [50]P5E_PEX3_STN2_TX_C_DN<43>[50]P5E_PEX3_STN2_RX_DN<43> [50]P5E_PEX3_STN2_TX_C_DP<43>[50]P5E_PEX3_STN2_RX_DP<43> [50]
RST_SMB_SSD12_ISO_R_N [102]RST_SSD12_PERST_R_N[117]SSD12_LED_ISO_R_N [200]SSD12_PWRDIS_R[117,200]
RST_SMB_SSD13_ISO_R_N [102]RST_SSD13_PERST_R_N[117]SSD13_LED_ISO_R_N [200]SSD13_PWRDIS_R[117,200]
SMB_ISO_SSD12_R_SCL [98]SMB_ISO_SSD12_R_SDA [98]
SMB_ISO_SSD13_R_SCL [98]SMB_ISO_SSD13_R_SDA [98]
CLK_100M_DB800ZL_SSD12_R_DN[81]CLK_100M_DB800ZL_SSD12_R_DP[81]
CLK_100M_DB800ZL_SSD13_R_DN[81]CLK_100M_DB800ZL_SSD13_R_DP[81]
PRSNT_SSD12_R_N [86,117,203]
PRSNT_SSD13_R_N [86,117,203]SSD12_LED_ISO_R_N [200]SSD12_LED_R[90]SSD13_LED_ISO_R_N [200]SSD13_LED_R[90]
SSD12_PWRDIS_R [117,200]
SSD13_PWRDIS_R [117,200]
P12V_SSD12
P12V_SSD13
P3V3_SSD12P3V3_SSD12P3V3_SSD12P3V3_SSD13P3V3_SSD13P3V3_SSD13
P3V3_AUX
P3V3_AUXP3V3_SSD12
P3V3_SSD13
P12V_SSD12
P12V_SSD13SizeDoc NumberRevDate: SheetofReviewerDesignerDepartmentProject
Page TitleCCBU D200 257Tuesday, August 29, 2023<project_name><Designer> GRANDTETON_SWB_20230829200 SSD_12/13<Reviewer>SizeDoc NumberRevDate: SheetofReviewerDesignerDepartmentProject
Page TitleCCBU D200 257Tuesday, August 29, 2023<project_name><Designer> GRANDTETON_SWB_20230829200 SSD_12/13<Reviewer>SizeDoc NumberRevDate: SheetofReviewerDesignerDepartmentProject
Page TitleCCBU D200 257Tuesday, August 29, 2023<project_name><Designer> GRANDTETON_SWB_20230829200 SSD_12/13<Reviewer>
R6210 4.7K 5% R0402-0201C27750.1UF25V10%C0402-0201X7RC39650.1UF25V10%X6S
C39570.1UF25V10%X6S
R6211 4.7K 5% R0402-0201J43SCONN56_1-2327679-3P12V_B1B1P12V_B2B2P12V_B3B3P12V_B4B4P12V_B5B5P12V_B6B6GND_A1A1GND_A2A2GND_A3A3GND_A4A4GND_A5A5GND_A6A6MFGB7RFUB8DUALPORTEN#B9P3V3_AUXB11PWRDISB12GND_B13B13GND_B16B16GND_B19B19GND_B22B22GND_B25B25GND_B28B28REFCLK_n0B14REFCLK_p0B15PET_n0B17PET_p0B18PET_n1B20PET_p1B21PET_n2B23PET_p2B24PET_n3B26PET_p3B27SMBCLKA7SMBDATA8SMBRST#A9LED#_ACTIVITYA10PERST0#B10PERST1#_CLKREQ#A11PRSNT0#A12GND_A13A13GND_A16A16GND_A19A19GND_A22A22GND_A25A25GND_A28A28REFCLK_n1A14REFCLK_p1A15PER_n0A17PER_p0A18PER_n1A20PER_p1A21PER_n2A23PER_p2A24PER_n3A26PER_p3A27G2G2G1G1R57511K1%R0402-0201<Part Number>C39660.1UF25V10%X6S
C39580.1UF25V10%X6S
R40784.7KR0402-02011%1/16WU409BSS138K<Part Number>GDSSCREW_SSD13_1<Part Number>1C978 0.1UF25V 10% C0402-0201X6S
SCREW_SSD12_1<Part Number>1 R5752 33SCREW_SSD13_2<Part Number>1
C39590.1UF25V10%X6S
C39670.1UF25V10%X6S
J42SCONN56_1-2327679-3P12V_B1B1P12V_B2B2P12V_B3B3P12V_B4B4P12V_B5B5P12V_B6B6GND_A1A1GND_A2A2GND_A3A3GND_A4A4GND_A5A5GND_A6A6MFGB7RFUB8DUALPORTEN#B9P3V3_AUXB11PWRDISB12GND_B13B13GND_B16B16GND_B19B19GND_B22B22GND_B25B25GND_B28B28REFCLK_n0B14REFCLK_p0B15PET_n0B17PET_p0B18PET_n1B20PET_p1B21PET_n2B23PET_p2B24PET_n3B26PET_p3B27SMBCLKA7SMBDATA8SMBRST#A9LED#_ACTIVITYA10PERST0#B10PERST1#_CLKREQ#A11PRSNT0#A12GND_A13A13GND_A16A16GND_A19A19GND_A22A22GND_A25A25GND_A28A28REFCLK_n1A14REFCLK_p1A15PER_n0A17PER_p0A18PER_n1A20PER_p1A21PER_n2A23PER_p2A24PER_n3A26PER_p3A27G2G2G1G1R4079 0 5% R0402-0201
SCREW_SSD12_2<Part Number>1R448 4.7K 1/16W1%C39680.1UF25V10%X6S
C39600.1UF25V10%X6S
R45010KR0402-02015%1/16WJ42_OTH<Part Number>1C39690.1UF25V10%X6S<Part Number>
C39610.1UF25V10%X6SU408BSS138K<Part Number>GDSJ43_OTH<Part Number>1 C27760.1UF25V10%C0402-0201X7RR449 4.7K 1/16W1%NIC977 0.1UF25V 10% C0402-0201X6SC39620.1UF25V10%X6S<Part Number>R40764.7KR0402-02011%1/16WR445 4.7K 1/16W1%
R57531K1%R0402-0201<Part Number>
R4077 0 5% R0402-0201R44610KR0402-02015%1/16W
C39631UFX6SC0402-020110%25V<Part Number>R5754 33
C39561UFX6SC0402-020110%25V<Part Number>
C39640.1UF25V10%X6S
R447 4.7K 1/16W1%NIP5E_PEX3_STN2_TX_C_DN<44>P5E_PEX3_STN2_RX_DN<44>P5E_PEX3_STN2_TX_C_DP<44>P5E_PEX3_STN2_RX_DP<44>P5E_PEX3_STN2_TX_C_DN<45>P5E_PEX3_STN2_RX_DN<45>P5E_PEX3_STN2_TX_C_DP<45>P5E_PEX3_STN2_RX_DP<45>P5E_PEX3_STN2_TX_C_DN<46>P5E_PEX3_STN2_RX_DN<46>P5E_PEX3_STN2_TX_C_DP<46>P5E_PEX3_STN2_RX_DP<46>P5E_PEX3_STN2_TX_C_DN<47>P5E_PEX3_STN2_RX_DN<47>P5E_PEX3_STN2_TX_C_DP<47>P5E_PEX3_STN2_RX_DP<47>P5E_PEX3_STN2_TX_C_DN<40>P5E_PEX3_STN2_RX_DN<40>P5E_PEX3_STN2_TX_C_DP<40>P5E_PEX3_STN2_RX_DP<40>P5E_PEX3_STN2_TX_C_DN<41>P5E_PEX3_STN2_RX_DN<41>P5E_PEX3_STN2_TX_C_DP<41>P5E_PEX3_STN2_RX_DP<41>P5E_PEX3_STN2_TX_C_DN<42>P5E_PEX3_STN2_RX_DN<42>P5E_PEX3_STN2_TX_C_DP<42>P5E_PEX3_STN2_RX_DP<42>P5E_PEX3_STN2_TX_C_DN<43>P5E_PEX3_STN2_RX_DN<43>P5E_PEX3_STN2_TX_C_DP<43>P5E_PEX3_STN2_RX_DP<43>
DUALPORT_N_SSD12RST_SMB_SSD12_ISO_R_NRST_SSD12_PERST_R_NPU_CLKREQ12SSD12_PWRDIS_R
DUALPORT_N_SSD13RST_SMB_SSD13_ISO_R_NRST_SSD13_PERST_R_NPU_CLKREQ13SSD13_PWRDIS_R
SMB_ISO_SSD12_R_SCLSMB_ISO_SSD12_R_SDA
SMB_ISO_SSD13_R_SCLSMB_ISO_SSD13_R_SDA
CLK_100M_DB800ZL_SSD12_R_DNCLK_100M_DB800ZL_SSD12_R_DP
CLK_100M_DB800ZL_SSD13_R_DNCLK_100M_DB800ZL_SSD13_R_DP
PRSNT_SSD12_N
PRSNT_SSD13_NSSD12_LED_ISO_N
SSD13_LED_ISO_N



5
5
4
4
3
3
2
2
1
1
D D
C C
B B
A A
SSD_14/15
SSD14
SSD15
P5E_PEX3_STN2_TX_C_DN<36>[50]P5E_PEX3_STN2_RX_DN<36> [50]P5E_PEX3_STN2_TX_C_DP<36>[50]P5E_PEX3_STN2_RX_DP<36> [50]P5E_PEX3_STN2_TX_C_DN<37>[50]P5E_PEX3_STN2_RX_DN<37> [50]P5E_PEX3_STN2_TX_C_DP<37>[50]P5E_PEX3_STN2_RX_DP<37> [50]P5E_PEX3_STN2_TX_C_DN<38>[50]P5E_PEX3_STN2_RX_DN<38> [50]P5E_PEX3_STN2_TX_C_DP<38>[50]P5E_PEX3_STN2_RX_DP<38> [50]P5E_PEX3_STN2_TX_C_DN<39>[50]P5E_PEX3_STN2_RX_DN<39> [50]P5E_PEX3_STN2_TX_C_DP<39>[50]P5E_PEX3_STN2_RX_DP<39> [50]P5E_PEX3_STN2_TX_C_DN<32>[50]P5E_PEX3_STN2_RX_DN<32> [50]P5E_PEX3_STN2_TX_C_DP<32>[50]P5E_PEX3_STN2_RX_DP<32> [50]P5E_PEX3_STN2_TX_C_DN<33>[50]P5E_PEX3_STN2_RX_DN<33> [50]P5E_PEX3_STN2_TX_C_DP<33>[50]P5E_PEX3_STN2_RX_DP<33> [50]P5E_PEX3_STN2_TX_C_DN<34>[50]P5E_PEX3_STN2_RX_DN<34> [50]P5E_PEX3_STN2_TX_C_DP<34>[50]P5E_PEX3_STN2_RX_DP<34> [50]P5E_PEX3_STN2_TX_C_DN<35>[50]P5E_PEX3_STN2_RX_DN<35> [50]P5E_PEX3_STN2_TX_C_DP<35>[50]P5E_PEX3_STN2_RX_DP<35> [50]
RST_SMB_SSD14_ISO_R_N [102]RST_SSD14_PERST_R_N[117]SSD14_LED_ISO_R_N [201]SSD14_PWRDIS_R[117,201]
RST_SMB_SSD15_ISO_R_N [102]RST_SSD15_PERST_R_N[117]SSD15_LED_ISO_R_N [201]SSD15_PWRDIS_R[117,201]
SMB_ISO_SSD14_R_SCL [98]SMB_ISO_SSD14_R_SDA [98]
SMB_ISO_SSD15_R_SCL [98]SMB_ISO_SSD15_R_SDA [98]
CLK_100M_DB800ZL_SSD14_R_DN[81]CLK_100M_DB800ZL_SSD14_R_DP[81]
CLK_100M_DB800ZL_SSD15_R_DN[81]CLK_100M_DB800ZL_SSD15_R_DP[81]
PRSNT_SSD14_R_N [86,117,203]
PRSNT_SSD15_R_N [86,117,203]SSD14_LED_ISO_R_N [201]SSD14_LED_R[90]SSD15_LED_ISO_R_N [201]SSD15_LED_R[90]
SSD14_PWRDIS_R [117,201]
SSD15_PWRDIS_R [117,201]
P12V_SSD14
P12V_SSD15
P3V3_SSD14P3V3_SSD14P3V3_SSD14P3V3_SSD15P3V3_SSD15P3V3_SSD15
P3V3_AUX
P3V3_AUXP3V3_SSD14
P3V3_SSD15
P12V_SSD14
P12V_SSD15SizeDoc NumberRevDate: SheetofReviewerDesignerDepartmentProject
Page TitleCCBU D201 257Tuesday, August 29, 2023<project_name><Designer> GRANDTETON_SWB_20230829201 SSD_14/15<Reviewer>SizeDoc NumberRevDate: SheetofReviewerDesignerDepartmentProject
Page TitleCCBU D201 257Tuesday, August 29, 2023<project_name><Designer> GRANDTETON_SWB_20230829201 SSD_14/15<Reviewer>SizeDoc NumberRevDate: SheetofReviewerDesignerDepartmentProject
Page TitleCCBU D201 257Tuesday, August 29, 2023<project_name><Designer> GRANDTETON_SWB_20230829201 SSD_14/15<Reviewer>R5750 33
C39730.1UF25V10%X6S
R454 4.7K 1/16W1%C39810.1UF25V10%X6SC27770.1UF25V10%C0402-0201X7RR45610KR0402-02015%1/16W
C39740.1UF25V10%X6S
SCREW_SSD15_1<Part Number>1
SCREW_SSD14_1<Part Number>1R6212 4.7K 5% R0402-0201C39820.1UF25V10%X6SSCREW_SSD15_2<Part Number>1 R57471K1%R0402-0201<Part Number>R6213 4.7K 5% R0402-0201
C39750.1UF25V10%X6SSCREW_SSD14_2<Part Number>1
U407BSS138K<Part Number>GDSC39830.1UF25V10%X6S<Part Number>R455 4.7K 1/16W1%NI R40824.7KR0402-02011%1/16WC979 0.1UF25V 10% C0402-0201X6SR5748 33C39760.1UF25V10%X6S<Part Number>R451 4.7K 1/16W1%
R4083 0 5% R0402-0201
R45310KR0402-02015%1/16WU406BSS138K<Part Number>GDSC39771UFX6SC0402-020110%25V<Part Number>J45SCONN56_1-2327679-3P12V_B1B1P12V_B2B2P12V_B3B3P12V_B4B4P12V_B5B5P12V_B6B6GND_A1A1GND_A2A2GND_A3A3GND_A4A4GND_A5A5GND_A6A6MFGB7RFUB8DUALPORTEN#B9P3V3_AUXB11PWRDISB12GND_B13B13GND_B16B16GND_B19B19GND_B22B22GND_B25B25GND_B28B28REFCLK_n0B14REFCLK_p0B15PET_n0B17PET_p0B18PET_n1B20PET_p1B21PET_n2B23PET_p2B24PET_n3B26PET_p3B27SMBCLKA7SMBDATA8SMBRST#A9LED#_ACTIVITYA10PERST0#B10PERST1#_CLKREQ#A11PRSNT0#A12GND_A13A13GND_A16A16GND_A19A19GND_A22A22GND_A25A25GND_A28A28REFCLK_n1A14REFCLK_p1A15PER_n0A17PER_p0A18PER_n1A20PER_p1A21PER_n2A23PER_p2A24PER_n3A26PER_p3A27G2G2G1G1C27780.1UF25V10%C0402-0201X7R
C39701UFX6SC0402-020110%25V<Part Number>R452 4.7K 1/16W1%NIJ44_OTH<Part Number>1C39780.1UF25V10%X6S
R40804.7KR0402-02011%1/16W
J45_OTH<Part Number>1
C39710.1UF25V10%X6S
C39790.1UF25V10%X6SR57491K1%R0402-0201<Part Number>
J44SCONN56_1-2327679-3P12V_B1B1P12V_B2B2P12V_B3B3P12V_B4B4P12V_B5B5P12V_B6B6GND_A1A1GND_A2A2GND_A3A3GND_A4A4GND_A5A5GND_A6A6MFGB7RFUB8DUALPORTEN#B9P3V3_AUXB11PWRDISB12GND_B13B13GND_B16B16GND_B19B19GND_B22B22GND_B25B25GND_B28B28REFCLK_n0B14REFCLK_p0B15PET_n0B17PET_p0B18PET_n1B20PET_p1B21PET_n2B23PET_p2B24PET_n3B26PET_p3B27SMBCLKA7SMBDATA8SMBRST#A9LED#_ACTIVITYA10PERST0#B10PERST1#_CLKREQ#A11PRSNT0#A12GND_A13A13GND_A16A16GND_A19A19GND_A22A22GND_A25A25GND_A28A28REFCLK_n1A14REFCLK_p1A15PER_n0A17PER_p0A18PER_n1A20PER_p1A21PER_n2A23PER_p2A24PER_n3A26PER_p3A27G2G2G1G1R4081 0 5% R0402-0201C39720.1UF25V10%X6S
C980 0.1UF25V 10% C0402-0201X6SC39800.1UF25V10%X6SP5E_PEX3_STN2_TX_C_DN<36>P5E_PEX3_STN2_RX_DN<36>P5E_PEX3_STN2_TX_C_DP<36>P5E_PEX3_STN2_RX_DP<36>P5E_PEX3_STN2_TX_C_DN<37>P5E_PEX3_STN2_RX_DN<37>P5E_PEX3_STN2_TX_C_DP<37>P5E_PEX3_STN2_RX_DP<37>P5E_PEX3_STN2_TX_C_DN<38>P5E_PEX3_STN2_RX_DN<38>P5E_PEX3_STN2_TX_C_DP<38>P5E_PEX3_STN2_RX_DP<38>P5E_PEX3_STN2_TX_C_DN<39>P5E_PEX3_STN2_RX_DN<39>P5E_PEX3_STN2_TX_C_DP<39>P5E_PEX3_STN2_RX_DP<39>P5E_PEX3_STN2_TX_C_DN<32>P5E_PEX3_STN2_RX_DN<32>P5E_PEX3_STN2_TX_C_DP<32>P5E_PEX3_STN2_RX_DP<32>P5E_PEX3_STN2_TX_C_DN<33>P5E_PEX3_STN2_RX_DN<33>P5E_PEX3_STN2_TX_C_DP<33>P5E_PEX3_STN2_RX_DP<33>P5E_PEX3_STN2_TX_C_DN<34>P5E_PEX3_STN2_RX_DN<34>P5E_PEX3_STN2_TX_C_DP<34>P5E_PEX3_STN2_RX_DP<34>P5E_PEX3_STN2_TX_C_DN<35>P5E_PEX3_STN2_RX_DN<35>P5E_PEX3_STN2_TX_C_DP<35>P5E_PEX3_STN2_RX_DP<35>
DUALPORT_N_SSD14RST_SMB_SSD14_ISO_R_NRST_SSD14_PERST_R_NPU_CLKREQ14SSD14_PWRDIS_R
DUALPORT_N_SSD15RST_SMB_SSD15_ISO_R_NRST_SSD15_PERST_R_NPU_CLKREQ15SSD15_PWRDIS_R
SMB_ISO_SSD14_R_SCLSMB_ISO_SSD14_R_SDA
SMB_ISO_SSD15_R_SCLSMB_ISO_SSD15_R_SDA
CLK_100M_DB800ZL_SSD14_R_DNCLK_100M_DB800ZL_SSD14_R_DP
CLK_100M_DB800ZL_SSD15_R_DNCLK_100M_DB800ZL_SSD15_R_DP
PRSNT_SSD14_N
PRSNT_SSD15_NSSD14_LED_ISO_N
SSD15_LED_ISO_N



5
5
4
4
3
3
2
2
1
1
D D
C C
B B
A A
SSD_AUX_PWR_EN(1/2)
SSD0_AUX_P3V3_EN_R [239,250]PRSNT_SSD0_R_N[86,115,194]SSD1_AUX_P3V3_EN_R [239,250]PRSNT_SSD1_R_N[86,115,194]SSD2_AUX_P3V3_EN_R [239,250]PRSNT_SSD2_R_N[86,115,195]SSD3_AUX_P3V3_EN_R [239,250]PRSNT_SSD3_R_N[86,115,195]
SSD4_AUX_P3V3_EN_R [239,251]PRSNT_SSD4_R_N[86,115,196]SSD5_AUX_P3V3_EN_R [239,251]PRSNT_SSD5_R_N[86,115,196]SSD6_AUX_P3V3_EN_R [239,251]PRSNT_SSD6_R_N[86,115,197]SSD7_AUX_P3V3_EN_R [239,251]PRSNT_SSD7_R_N[86,115,197]
P3V3_AUXP3V3_AUXP3V3_AUXP3V3_AUX
P3V3_AUXP3V3_AUXP3V3_AUXP3V3_AUXSizeDoc NumberRevDate: SheetofReviewerDesignerDepartmentProject
Page TitleCCBU D202 257Tuesday, August 29, 2023<project_name><Designer> GRANDTETON_SWB_20230829202 SSD_AUX_PWR_EN(1/2)<Reviewer>SizeDoc NumberRevDate: SheetofReviewerDesignerDepartmentProject
Page TitleCCBU D202 257Tuesday, August 29, 2023<project_name><Designer> GRANDTETON_SWB_20230829202 SSD_AUX_PWR_EN(1/2)<Reviewer>SizeDoc NumberRevDate: SheetofReviewerDesignerDepartmentProject
Page TitleCCBU D202 257Tuesday, August 29, 2023<project_name><Designer> GRANDTETON_SWB_20230829202 SSD_AUX_PWR_EN(1/2)<Reviewer>R556105% R0402-0201<Part Number>R554705%<Part Number>R55571K1%R0402-0201<Part Number>U364BSS138K<Part Number>GDSU363BSS138K<Part Number>GDSR554105% R0402-0201<Part Number>
R555805% R0402-0201<Part Number>R55541K1%R0402-0201<Part Number>R554405%<Part Number>U370BSS138K<Part Number>GDSR555505% R0402-0201<Part Number>R55481K1%R0402-0201<Part Number>
R55511K1%R0402-0201<Part Number>
R556205%<Part Number>U369BSS138K<Part Number>GDSR554905% R0402-0201<Part Number>R55451K1%R0402-0201<Part Number>R555205% R0402-0201<Part Number>R555905%<Part Number>R554605% R0402-0201<Part Number>U368BSS138K<Part Number>GDSR553905%<Part Number>R55421K1%R0402-0201<Part Number>R555605%<Part Number>U366BSS138K<Part Number>GDS
U367BSS138K<Part Number>GDSR55401K1%R0402-0201<Part Number>R554305% R0402-0201<Part Number>R55601K1%R0402-0201<Part Number>R555005%<Part Number>U365BSS138K<Part Number>GDSR555305%<Part Number>SSD0_AUX_P3V3_ENPRSNT_SSD0_R1_NSSD1_AUX_P3V3_ENPRSNT_SSD1_R1_NSSD2_AUX_P3V3_ENPRSNT_SSD2_R1_NSSD3_AUX_P3V3_ENPRSNT_SSD3_R1_N
SSD4_AUX_P3V3_ENPRSNT_SSD4_R1_NSSD5_AUX_P3V3_ENPRSNT_SSD5_R1_NSSD6_AUX_P3V3_ENPRSNT_SSD6_R1_NSSD7_AUX_P3V3_ENPRSNT_SSD7_R1_N



5
5
4
4
3
3
2
2
1
1
D D
C C
B B
A A
SSD_AUX_PWR_EN(2/2)
SSD8_AUX_P3V3_EN_R [240,252]PRSNT_SSD8_R_N[86,117,198]SSD12_AUX_P3V3_EN_R [240,253]PRSNT_SSD12_R_N[86,117,200]SSD9_AUX_P3V3_EN_R [240,252]PRSNT_SSD9_R_N[86,117,198]SSD13_AUX_P3V3_EN_R [240,253]PRSNT_SSD13_R_N[86,117,200]SSD10_AUX_P3V3_EN_R [240,252]PRSNT_SSD10_R_N[86,117,199]SSD14_AUX_P3V3_EN_R [240,253]PRSNT_SSD14_R_N[86,117,201]SSD11_AUX_P3V3_EN_R [240,252]PRSNT_SSD11_R_N[86,117,199]SSD15_AUX_P3V3_EN_R [240,253]PRSNT_SSD15_R_N[86,117,201]
P3V3_AUXP3V3_AUXP3V3_AUXP3V3_AUXP3V3_AUXP3V3_AUXP3V3_AUXP3V3_AUXSizeDoc NumberRevDate: SheetofReviewerDesignerDepartmentProject
Page TitleCCBU D203 257Tuesday, August 29, 2023<project_name><Designer> GRANDTETON_SWB_20230829203 SSD_AUX_PWR_EN(2/2)<Reviewer>SizeDoc NumberRevDate: SheetofReviewerDesignerDepartmentProject
Page TitleCCBU D203 257Tuesday, August 29, 2023<project_name><Designer> GRANDTETON_SWB_20230829203 SSD_AUX_PWR_EN(2/2)<Reviewer>SizeDoc NumberRevDate: SheetofReviewerDesignerDepartmentProject
Page TitleCCBU D203 257Tuesday, August 29, 2023<project_name><Designer> GRANDTETON_SWB_20230829203 SSD_AUX_PWR_EN(2/2)<Reviewer>
R55661K1%R0402-0201<Part Number>U375BSS138K<Part Number>GDSR557005% R0402-0201<Part Number>R558505% R0402-0201<Part Number>U374BSS138K<Part Number>GDSR557705%<Part Number>R55811K1%R0402-0201<Part Number>
R556705% R0402-0201<Part Number>R55781K1%R0402-0201<Part Number>
R55631K1%R0402-0201<Part Number>R557405%<Part Number>R558205% R0402-0201<Part Number>U373BSS138K<Part Number>GDSR556405% R0402-0201<Part Number>
U378BSS138K<Part Number>GDSR557905% R0402-0201<Part Number>U372BSS138K<Part Number>GDSR557105%<Part Number>R55751K1%R0402-0201<Part Number>R558605%<Part Number>
R55721K1%R0402-0201<Part Number>R556805%<Part Number>
U377BSS138K<Part Number>GDSR557605% R0402-0201<Part Number>U371BSS138K<Part Number>GDS U376BSS138K<Part Number>GDSR558305%<Part Number>R557305% R0402-0201<Part Number>R556505%<Part Number>R55691K1%R0402-0201<Part Number>R55841K1%R0402-0201<Part Number>R558005%<Part Number>
SSD8_AUX_P3V3_ENPRSNT_SSD8_R1_NSSD12_AUX_P3V3_ENPRSNT_SSD12_R1_NSSD9_AUX_P3V3_ENPRSNT_SSD9_R1_NSSD13_AUX_P3V3_ENPRSNT_SSD13_R1_NSSD10_AUX_P3V3_ENPRSNT_SSD10_R1_NSSD14_AUX_P3V3_ENPRSNT_SSD14_R1_NSSD11_AUX_P3V3_ENPRSNT_SSD11_R1_NSSD15_AUX_P3V3_ENPRSNT_SSD15_R1_N



5
5
4
4
3
3
2
2
1
1
D D
C C
B B
A A
BLANK SizeDoc NumberRevDate: SheetofReviewerDesignerDepartmentProject
Page TitleCCBU D204 257Tuesday, August 29, 2023<project_name><Designer> GRANDTETON_SWB_20230829204 BLANK<Reviewer>SizeDoc NumberRevDate: SheetofReviewerDesignerDepartmentProject
Page TitleCCBU D204 257Tuesday, August 29, 2023<project_name><Designer> GRANDTETON_SWB_20230829204 BLANK<Reviewer>SizeDoc NumberRevDate: SheetofReviewerDesignerDepartmentProject
Page TitleCCBU D204 257Tuesday, August 29, 2023<project_name><Designer> GRANDTETON_SWB_20230829204 BLANK<Reviewer>



5
5
4
4
3
3
2
2
1
1
D D
C C
B B
A A
SizeDoc NumberRevDate: SheetofReviewerDesignerDepartmentProject
Page TitleCCBU D205 257Tuesday, August 29, 2023<project_name><Designer> GRANDTETON_SWB_20230829215 P12V_AUX_MP5990_HSC(2/3)<Reviewer>SizeDoc NumberRevDate: SheetofReviewerDesignerDepartmentProject
Page TitleCCBU D205 257Tuesday, August 29, 2023<project_name><Designer> GRANDTETON_SWB_20230829215 P12V_AUX_MP5990_HSC(2/3)<Reviewer>SizeDoc NumberRevDate: SheetofReviewerDesignerDepartmentProject
Page TitleCCBU D205 257Tuesday, August 29, 2023<project_name><Designer> GRANDTETON_SWB_20230829215 P12V_AUX_MP5990_HSC(2/3)<Reviewer>



5
5
4
4
3
3
2
2
1
1
D D
C C
B B
A A
SizeDoc NumberRevDate: SheetofReviewerDesignerDepartmentProject
Page TitleCCBU D206 257Tuesday, August 29, 2023<project_name><Designer> GRANDTETON_SWB_20230829215 P12V_AUX_MP5990_HSC(2/3)<Reviewer>SizeDoc NumberRevDate: SheetofReviewerDesignerDepartmentProject
Page TitleCCBU D206 257Tuesday, August 29, 2023<project_name><Designer> GRANDTETON_SWB_20230829215 P12V_AUX_MP5990_HSC(2/3)<Reviewer>SizeDoc NumberRevDate: SheetofReviewerDesignerDepartmentProject
Page TitleCCBU D206 257Tuesday, August 29, 2023<project_name><Designer> GRANDTETON_SWB_20230829215 P12V_AUX_MP5990_HSC(2/3)<Reviewer>



5
5
4
4
3
3
2
2
1
1
D D
C C
B B
A A
P12V_AUX_HSC_MOSFET SizeDoc NumberRevDate: SheetofReviewerDesignerDepartmentProject
Page TitleCCBU D207 257Tuesday, August 29, 2023<project_name><Designer> GRANDTETON_SWB_20230829216 P12V_AUX_MP5990_HSC(3/3)<Reviewer>SizeDoc NumberRevDate: SheetofReviewerDesignerDepartmentProject
Page TitleCCBU D207 257Tuesday, August 29, 2023<project_name><Designer> GRANDTETON_SWB_20230829216 P12V_AUX_MP5990_HSC(3/3)<Reviewer>SizeDoc NumberRevDate: SheetofReviewerDesignerDepartmentProject
Page TitleCCBU D207 257Tuesday, August 29, 2023<project_name><Designer> GRANDTETON_SWB_20230829216 P12V_AUX_MP5990_HSC(3/3)<Reviewer>



5
5
4
4
3
3
2
2
1
1
D D
C C
B B
A A
BLANK SizeDoc NumberRevDate: SheetofReviewerDesignerDepartmentProject
Page TitleCCBU D208 257Tuesday, August 29, 2023<project_name><Designer> GRANDTETON_SWB_20230829208 BLANK<Reviewer>SizeDoc NumberRevDate: SheetofReviewerDesignerDepartmentProject
Page TitleCCBU D208 257Tuesday, August 29, 2023<project_name><Designer> GRANDTETON_SWB_20230829208 BLANK<Reviewer>SizeDoc NumberRevDate: SheetofReviewerDesignerDepartmentProject
Page TitleCCBU D208 257Tuesday, August 29, 2023<project_name><Designer> GRANDTETON_SWB_20230829208 BLANK<Reviewer>



5
5
4
4
3
3
2
2
1
1
D D
C C
B B
A A
POWER_CONN
P12V_STBY
SizeDoc NumberRevDate: SheetofReviewerDesignerDepartmentProject
Page TitleCCBU D209 257Tuesday, August 29, 2023<project_name><Designer> GRANDTETON_SWB_20230829209 POWER_CONN<Reviewer>SizeDoc NumberRevDate: SheetofReviewerDesignerDepartmentProject
Page TitleCCBU D209 257Tuesday, August 29, 2023<project_name><Designer> GRANDTETON_SWB_20230829209 POWER_CONN<Reviewer>SizeDoc NumberRevDate: SheetofReviewerDesignerDepartmentProject
Page TitleCCBU D209 257Tuesday, August 29, 2023<project_name><Designer> GRANDTETON_SWB_20230829209 POWER_CONN<Reviewer>
CONN48_10106263-6000001LFJ1<Part Number>P1_1P1_1P1_2P1_2P1_3P1_3P1_4P1_4P1_5P1_5P1_6P1_6P1_7P1_7P1_8P1_8P2_1P2_1P2_2P2_2P2_3P2_3P2_4P2_4P2_5P2_5P2_6P2_6P2_7P2_7P2_8P2_8P4_1P4_1P4_2P4_2P4_3P4_3P4_4P4_4P4_5P4_5P4_6P4_6P4_7P4_7P4_8P4_8P5_1P5_1P5_2P5_2P5_3P5_3P5_4P5_4P5_5P5_5P5_6P5_6P5_7P5_7P5_8P5_8P3_1P3_1P3_2P3_2P3_3P3_3P3_4P3_4P3_5P3_5P3_6P3_6P3_7P3_7P3_8P3_8P6_1P6_1P6_2P6_2P6_3P6_3P6_4P6_4P6_5P6_5P6_6P6_6P6_7P6_7P6_8P6_8



5
5
4
4
3
3
2
2
1
1
D D
C C
B B
A A
HSC_OC
Design for 2nd moudle solution
DVT_CHANGELT6700_olayoutBOM CHANGE
BOM CHANGE
BOM CHANGE
HSC_D_OC_R [210,213,214,215]HSC_CSOUT[210,213]
A_HSC_LOW_GATEHSC_CSOUT[210,213]HSC_CSOUT[210,213]HSC_D_OC_R [210,213,214,215]P3V3_AUXP3V3_AUXP3V3_AUXP12V_AUXP3V3_AUXSizeDoc NumberRevDate: SheetofReviewerDesignerDepartmentProject
Page TitleCCBU D210 257Tuesday, August 29, 2023<project_name><Designer> GRANDTETON_SWB_20230829210 BLANK<Reviewer>SizeDoc NumberRevDate: SheetofReviewerDesignerDepartmentProject
Page TitleCCBU D210 257Tuesday, August 29, 2023<project_name><Designer> GRANDTETON_SWB_20230829210 BLANK<Reviewer>SizeDoc NumberRevDate: SheetofReviewerDesignerDepartmentProject
Page TitleCCBU D210 257Tuesday, August 29, 2023<project_name><Designer> GRANDTETON_SWB_20230829210 BLANK<Reviewer>
R665501/16WR0402-02015%CSOUT_BOM2, CSOUT_BOM3R665110K1/16WR0402-02011%CSOUT_BOM2R665310K1/16WR0402-02011%CSOUT_BOM2, CSOUT_BOM3R6801 01/16W 5% R0402-0201CSOUT_BOM1C4486100NFC0402-020110%CSOUT_BOM3
D
G
S
U4372N7002KCSOUT_BOM2, CSOUT_BOM3DGS
R6797 33CSOUT_BOM31/16W 1% R0402-0201R679310KR0402-02011%1/16WNI
C44470.1UF25V10%C0402-0201CSOUT_BOM2R665401/16WR0402-02015%CSOUT_BOM2R6795 1MCSOUT_BOM31/16W 1% R0402-0201
U436LT6700CS6-1#TRPBFCSOUT_BOM2VS5INB-4GND2OUTA1INA+3OUTB6R665210K1/16WR0402-02011%CSOUT_BOM2, CSOUT_BOM3
U449LM4040AIM3X-2.5/NOPBCSOUT_BOM31+12-233R679010KR0402-02011%1/16WCSOUT_BOM3
R6648160K1/16WR0402-02011%CSOUT_BOM2R6649160K1/16WR0402-02011%CSOUT_BOM2R679117.8KR0402-02011%1/16WCSOUT_BOM3
R68241K1/16W1%R0402-0201CSOUT_BOM2
R67985.11KR04021%1/16WCSOUT_BOM3C4484100NFC0402-020110%CSOUT_BOM3
C44921UFX6S25VC0402-0201<Part Number>CSOUT_BOM2R665010K1/16WR0402-02011%CSOUT_BOM2-+U448AP331AWG-7CSOUT_BOM331452C4485100NFC0402-020110%CSOUT_BOM3
A_HSC_LOW_GATEA_HSC_LOWA_HSC_HIGHHSC_D_OCA_HSC_LOW_DRAINHSC_CSOUT
HSC_OC_VOLHSC_D_OC_R2A_HSC_LOW_GATEOC_P2V5_COMP
HSC_OC_LT6700_VS



5
5
4
4
3
3
2
2
1
1
D D
C C
B B
A A
SMBUS ADDRESS: 0XEE
Front IO SlimSAS Vertical Connecter
SLIMSAS_CONN
Push-Pull I/OOpen-Drain INT_NSMBUS ADDRESS: 0XEC (8bit)
USB2_FIO_DP [70]USB2_FIO_DN [70]FM_PFR_LED_AMBER_R [117]FM_PFR_LED_BLUE_R [117]RST_SMB_FIO_R_N [87]SMB_FIO_R1_SCL [87,212]SMB_FIO_R1_SDA [87,212]UART_FIO_DEBUG_R_TX [211]UART_FIO_DEBUG_R_RX [211]
BIC_UART_SEL2 [211]BIC_UART_SEL1 [211]BIC_UART_SEL2 [211]BIC_UART_SEL1 [211]UART_BIC_DEBUG_R_TX [87]UART_BIC_DEBUG_RX [87]
PRSNT_DBV2_SLIMSAS_R[86,211]PRSNT_DBV2_SLIMSAS_R [86,211]
UART_FIO_DEBUG_R_RX[211]UART_MB_BIC_RX_BUF_R[158]UART_FIO_DEBUG_R_TX[211]UART_MB_BIC_TX[158]BIC_UART_BMC_SEL_R[211]BIC_UART_SW_SEL1_R [211]BIC_UART_BIC_SEL_R[87]BIC_RECOVER_IOEXP_A1[211]BIC_FWSPICK[88,93]BIC_RECOVER_IOEXP_A0 [211]BIC_RECOVER_IOEXP_A1 [211]BIC_RECOVER_IOEXP_A0 [211]SMB_MB_R_SCL [115,138]SMB_MB_R_SDA [115,138]BIC_UART_BMC_SEL_R[211]BIC_UART_HW_SEL1 [211]BIC_UART_SEL1 [211]BIC_UART_SW_SEL1_R [211]BIC_UART_HW_SEL1 [211]
P5V_AUXP3V3_AUXP5V_AUX
P3V3_AUXP3V3_AUXP3V3_AUX
P3V3_AUX
P3V3_AUXP3V3_AUXP3V3_AUXP3V3_AUXP3V3_AUXP3V3_AUXP3V3_AUXSizeDoc NumberRevDate: SheetofReviewerDesignerDepartmentProject
Page TitleCCBU D211 257Tuesday, August 29, 2023<project_name><Designer> GRANDTETON_SWB_20230829211 SLIMSAS_CONN<Reviewer>SizeDoc NumberRevDate: SheetofReviewerDesignerDepartmentProject
Page TitleCCBU D211 257Tuesday, August 29, 2023<project_name><Designer> GRANDTETON_SWB_20230829211 SLIMSAS_CONN<Reviewer>SizeDoc NumberRevDate: SheetofReviewerDesignerDepartmentProject
Page TitleCCBU D211 257Tuesday, August 29, 2023<project_name><Designer> GRANDTETON_SWB_20230829211 SLIMSAS_CONN<Reviewer>
R6241 0 R0402-02015%R6215 0 R0402-0201R622610K<Part Number>5%R0402-0201U88FSA3357K8X<Part Number>A7GND4B23S25VCC8B12B01S16J60_12<Part Number>1 U41874LVC1G08GV12453J60SCONN3_TSM-103-01-S-SV-TR123 R6227 33R3761 33 R0402-02011%R62194.7KR0402-02011%1/16WR623710K<Part Number>5%R0402-0201R6216 33.2R0402-0201 1%R59181KR0402-02011%R623810K<Part Number>5%R0402-0201NI R3762 49.9 R0402-02011%R6244 33R62574.7KR0402-02011%1/16WR59191KR0402-02011%NI R6243 0 R0402-02015%R62204.7KR0402-02011%1/16WR59164.7KR0402-02011%1/16WR5917 1K
J2SCONN38_U10DH3824103TGND_A1A1RX0+A2RX0-A3GND_A4A4RX1+A5RX1-A6GND_A7A7SB0A8SB1A9SB2A10SB3A11SB4A12GND_A13A13RX2+A14RX2-A15GND_A16A16RX3+A17RX3-A18GND_A19A19GND_B1B1TX0+B2TX0-B3GND_B4B4TX1+B5TX1-B6GND_B7B7SB5B8SB6B9SB7B10SB8B11SB9B12GND_B13B13TX2+B14TX2-B15GND_B16B16TX3+B17TX3-B18GND_B19B19G1G1G2G2G3G3G4G4
R621810K5%R0402-0201C25710.1UFX7RC0402-020110%16VJ59_12<Part Number>1 U89FSA3357K8X<Part Number>A7GND4B23S25VCC8B12B01S16
R62144.7K5%R0402-0201NIR6305100K<Part Number>R0402-02011%1/16W
C39880.1UF16VX7R10%C0402-0201J59SCONN3_TSM-103-01-S-SV-TR123R622510K<Part Number>5%R0402-0201NI U419PCA9539RPWINT1A12RESET3IO0_04IO0_15IO0_26IO0_37IO0_48IO0_59IO0_610IO0_711VSS12IO1_013IO1_114IO1_215IO1_316IO1_417IO1_518IO1_619IO1_720A021SCL22SDA23VDD24C25700.1UFX7RC0402-020110%16VC39890.1UF16VX7R10%C0402-0201
PRSNT_DBV2_SLIMSASSMB_FIO_R2_SCLSMB_FIO_R2_SDA
BIC_UART_SEL2BIC_UART_SEL1BIC_UART_SEL2BIC_UART_SEL1
USB2_FIO_DPUSB2_FIO_DN
UART_BIC_DEBUG_R_TXUART_BIC_DEBUG_RXBIC_UART_SEL2UART_FIO_DEBUG_R_RXUART_MB_BIC_RX_BUF_RTP_FSA3357K8X_B2_RXUART_FIO_DEBUG_R_TXUART_MB_BIC_TXTP_FSA3357K8X_B2_TXBIC_UART_BMC_SEL_RBIC_UART_SW_SEL1
BIC_UART_BIC_SEL_RIRQ_BIC_RECOVER_IOEXP_NBIC_FWSPICKBIC_FWSPICK_IOEXPSMB_BIC_RECOVER_IOEXP_SCLSMB_BIC_RECOVER_IOEXP_SDABIC_UART_BMC_SEL_RBIC_UART_BMC_SELRST_BIC_RECOVER_NPD_BIC_UART_SELPU_BIC_UART_SEL



5
5
4
4
3
3
2
2
1
1
D D
C C
B B
A A
SLIMASA_DBV2
GPIO expander for Debug Card V2
I2C address: 0x4E
IO BD Address Setting
0
Fix on IO board
0 1 101 1
(To BIC)
PUSH-PULLINTERNAL WEAK PULL_UP
SMB_FIO_R1_SCL[87,211]SMB_IO_DEBUG_CARD_R_SCL [212]SMB_FIO_R1_SDA[87,211]SMB_IO_DEBUG_CARD_R_SDA [212]LED_POSTCODE_0 [118]LED_POSTCODE_1 [118]LED_POSTCODE_2 [118]LED_POSTCODE_3 [118]LED_POSTCODE_4 [118]LED_POSTCODE_5 [118]LED_POSTCODE_6 [118]LED_POSTCODE_7 [118]USB_DEBUG_RST_BTN_N [212]SMB_IO_DEBUG_CARD_R_SDA[212]SMB_IO_DEBUG_CARD_R_SCL[212]FM_SOL_UART_CH_SEL [115]USB_DEBUG_RST_BTN_N[212]USB_DEBUG_RST_BTN_R_N [88]P3V3_AUXP3V3_AUXP3V3_AUXP3V3_AUX
SizeDoc NumberRevDate: SheetofReviewerDesignerDepartmentProject
Page TitleCCBU D212 257Tuesday, August 29, 2023<project_name><Designer> GRANDTETON_SWB_20230829212 SLIMASA_DBV2<Reviewer>SizeDoc NumberRevDate: SheetofReviewerDesignerDepartmentProject
Page TitleCCBU D212 257Tuesday, August 29, 2023<project_name><Designer> GRANDTETON_SWB_20230829212 SLIMASA_DBV2<Reviewer>SizeDoc NumberRevDate: SheetofReviewerDesignerDepartmentProject
Page TitleCCBU D212 257Tuesday, August 29, 2023<project_name><Designer> GRANDTETON_SWB_20230829212 SLIMASA_DBV2<Reviewer>
R424110K5%R0402-0201R424810K5%R0402-0201R424210K5%R0402-0201C21451UFC0402-020125V10%X6SR42364.7KR0402-02015%R424710K5%R0402-0201R42464.7KR0402-02015%NIR424310K5%R0402-0201U324PCA9555APWVDD24VSS12INT#1SDA23SCL22P0_04P0_15P0_26P0_37P0_48P0_59P0_610P0_711P1_013P1_114P1_215P1_316P1_417P1_518P1_619P1_720A021A12A23R42454.7K5%NIR42444.7K5%NIR4232 33 R0402-02011%R4233 0 R0402-02015%R423710K5%R0402-0201R424010K5%R0402-0201R5478 33.2R0402-0201 1%R4238 4.7KR0402-0201 5%R423910K5%R0402-0201C21460.1UFC0402-020116V10%X7RR42354.7K5%R42344.7K5%LED_POSTCODE_0LED_POSTCODE_1LED_POSTCODE_2USB_DEBUG_RST_BTN_NIRQ_IOEXP_DBV2_NLED_POSTCODE_3LED_POSTCODE_4USB_DEBUG_PWR_BTN_NIOEXP_DBV2_A0LED_POSTCODE_5IOEXP_DBV2_A1LED_POSTCODE_6FM_SOL_UART_CH_SELIOEXP_DBV2_A2LED_POSTCODE_7USB_DEBUG_RST_BTN_NPWRGD_DSW_PWROKUSB_DEBUG_PWR_BTN_NPWRGD_SYS_PWROKPWRGD_SYS_PWROKRST_PLTRST_NPWRGD_DSW_PWROKFM_CPU_CATERR_MSMI_LVT3_NRST_PLTRST_NFM_SLPS3_NFM_SOL_UART_CH_SELFM_CPU_CATERR_MSMI_LVT3_NFM_SLPS3_N
USB_DEBUG_RST_BTN_N USB_DEBUG_RST_BTN_R_N



5
5
4
4
3
3
2
2
1
1
D D
C C
B B
A A
P12V_AUX_HSC_MOSFET
RDS(ON)=0.54m OHM@10V
BOM NOTE
For LTC4282LAYOUT NOTE: PLEASE CLOSE TO MOSFET
PU6601MAIN SOURCE:AL007718001 (NCT7718W(MSOP))2ND SOURCE:AL000788001 (G788P81U(MSOP8))
Ipeak=119AIocp=146AProchot=134A
P12V_HSC_SENSE1_P[213]P12V_HSC_SENSE1_N [213]P12V_HSC_SENSE2_R1_P[213]P12V_HSC_SENSE2_R1_N [213]P12V_HSC_GATE2[213]P12V_HSC_SENSE1_P [213]P12V_HSC_SENSE2_R1_P [213]P12V_HSC_GATE1[213]SMB_BIC_I2C6_MUX_PEX_ADC_R_SCL [99,112,113]SMB_BIC_I2C6_MUX_PEX_ADC_R_SDA [99,112,113]HSC_ALERT1_R_N [213,214,216]
P12V_HSC_SENSE2_R2_N [213]P12V_HSC_SENSE2_R2_P[213]P12V_HSC_SENSE2_R2_P [213]P12V_HSC_ADC_P [213]P12V_HSC_ADC_N [213]P12V_HSC_SENSE1_N [213]P12V_HSC_SENSE2_R1_N [213]P12V_HSC_SENSE2_R2_N [213]P12V_HSC_SENSE2_P [213]P12V_HSC_SENSE2_R1_P [213]P12V_HSC_SENSE2_R2_P [213]P12V_HSC_SENSE2_N [213]P12V_HSC_SENSE2_R1_N [213]P12V_HSC_SENSE2_R2_N [213]HSC_CSOUT[210]HSC_D_OC_R [210,214,215]P12V_HSC_GATE2[213]P12V_HSC_GATE1[213]P12V_HSC_ADC_P[213]P12V_HSC_ADC_N[213]P12V_HSC_SENSE2_N[213]P12V_HSC_SENSE2_P[213]P12V_HSC_SENSE1_N[213]P12V_HSC_SENSE1_P[213]FM_HSC_FAULT_N [214,216]SMB_BIC_I2C6_MUX_VR_R_SDA [99,214,223,226]SMB_BIC_I2C6_MUX_VR_R_SCL [99,214,223,226]HSC_D_OC_BUF_R_N [86,118,215]PWRGD_P12V_AUX_R [121,153,214,220]HSC_P12V_EN [152,214]HSC_ALERT1_R_N [213,214,216]HSC_TYPE_ADC_R [85,86]
P12V_STBYP12V_STBY_R2P12V_AUXP3V3_AUXP3V3_AUXP3V3_AUXP12V_AUXP12V_STBYP3V3_AUXSizeDoc NumberRevDate: SheetofReviewerDesignerDepartmentProject
Page TitleCCBU 11213 257Tuesday, August 29, 2023<project_name><Designer> GRANDTETON_SWB_20230829213 BLANK<Reviewer>SizeDoc NumberRevDate: SheetofReviewerDesignerDepartmentProject
Page TitleCCBU 11213 257Tuesday, August 29, 2023<project_name><Designer> GRANDTETON_SWB_20230829213 BLANK<Reviewer>SizeDoc NumberRevDate: SheetofReviewerDesignerDepartmentProject
Page TitleCCBU 11213 257Tuesday, August 29, 2023<project_name><Designer> GRANDTETON_SWB_20230829213 BLANK<Reviewer>SCREW_9<Part Number>HSC_BOM21PR660910<Part Number>R0402-02011%HSC_BOM20.0003PR66031% 4W<Part Number>HSC_BOM22B1B2A1APC66040.1UF16V10%<Part Number>X7RC0402-0201HSC_BOM2PR7164 0 5% R0402-0201HSC_BOM2PR715910.5K<Part Number>R0402-02011%HSC_BOM2
PR7151 10<Part Number>R0402-02011%HSC_BOM2PR6618 05%<Part Number> R0402-0201 1/16WHSC_BOM2S1 S2 S3G1D1PQ6603PSMNR58-30YLHHSC_BOM235241S1 S2 S3G1D1PQ6605PSMNR58-30YLHHSC_BOM235241R6656 0 R0402-02015%HSC_BOM2PC60021NF<Part Number>C0402-020110%50VNIPR661633R0402-02011%HSC_BOM2
PR7145 1<Part Number>R0402-02011%HSC_BOM2PR660710<Part Number>R0402-02011%HSC_BOM2PU6601NCT7718W<Part Number>HSC_BOM2VDD1D+2D-3T_CRIT#4GND5ALERT#6SDA7SCL8R6715 0 R0402-02015%HSC_BOM2
PR6001 0.0031% 3W<Part Number>HSC_BOM21234
PR661210<Part Number>R0402-02011%NI0.0003PR66021% 4W<Part Number>HSC_BOM22B1B2A1APR661110<Part Number>R0402-02011%HSC_BOM2PR6617 05%<Part Number> R0402-0201 1/16WHSC_BOM2PR7150 10<Part Number>R0402-02011%HSC_BOM2PR7157 5.15% R0402-0201<Part Number>HSC_BOM2PR6614 49.91%<Part Number>R0402-02011/16WHSC_BOM2PQ6606MMBT3904<Part Number>HSC_BOM2BEC
PR7148 1<Part Number>R0402-02011%HSC_BOM2S1 S2 S3G1D1PQ6602PSMNR58-30YLHHSC_BOM235241J69SCONN21_91910-31421LF91910-31421LF<Part Number>HSC_BOM21133445522G1G1G2G266778899101011111212131314141515161617171818191920202121R6716 33 R0402-02011%HSC_BOM2PR660810<Part Number>R0402-02011%HSC_BOM2PR7161 0 5% R0402-0201HSC_BOM2S1 S2 S3G1D1PQ6604PSMNR58-30YLHHSC_BOM235241S1 S2 S3G1D1PQ6601PSMNR58-30YLH<Part Number>HSC_BOM235241PC66061000PF25V10%<Part Number>X7RC0603HSC_BOM2PR715810.5K<Part Number>R0402-02011%HSC_BOM2PR7163 0 5% R0402-0201HSC_BOM2SCREW_8<Part Number>HSC_BOM21 PC600133NF<Part Number>C0402-020110%25VNIPR7153 1<Part Number>R0402-02011%HSC_BOM2PR7154 1<Part Number>R0402-02011%HSC_BOM2R6713 0 R0402-02015%HSC_BOM2PR6615 49.91%<Part Number>R0402-02011/16WHSC_BOM2
PR7144 10<Part Number>R0402-02011%HSC_BOM2PR7156 5.15% R0402-0201<Part Number>HSC_BOM2PC66031000PF25V10%<Part Number>X7RC0603HSC_BOM2PR7162 0 5% R0402-0201HSC_BOM2PR661010<Part Number>R0402-02011%HSC_BOM2PR7149 100<Part Number>R0402-02011%HSC_BOM2
R6647 33 R0402-02011%NI
P12V_HSC_SENSE1_NP12V_STBY_R1P12V_HSC_SENSE2_R1_PP12V_HSC_SENSE2_R1_NHS_GATE2_R_2HS_GATE2_R_3HS_GATE1_R_1
HS_GATE2_R_1P12V_HSC_SENSE1_P
SMB_LTC4282_TEMP_SCLLTC4282_TEMP_R_D+LTC4282_TEMP_D+SMB_LTC4282_TEMP_SDALTC4282_ALERT1_R_NLTC4282_TEMP_R_D-LTC4282_TEMP_D-LTC4282_T_CRIT_NHS_GATE2_R_4P12V_HSC_SENSE2_R2_NP12V_HSC_SENSE2_R2_PP12V_HSC_GATE_RCIRQ_HSC_FAULT_R_NSMB_SML1_PMBUS_HSC_SDASMB_SML1_PMBUS_HSC_SCLHSC_TYPE_ADCHSC_CSOUTMB0_P12V_STBY_PWRGDP12V_HSC_ENIRQ_SML1_PMBUS_ALERT_N



5
5
4
4
3
3
2
2
1
1
D D
C C
B B
A A
P12V_AUX_MP5990_HSC(1/3)
For MP5981: DNI PR28, PR29, PR30Change PU2 to AL005981A00
Controller : MP5990+MP5991 x 2Soft start time=6msADDRESS 0X20VIN_ON=10V, VIN_OFF=8VTON_DELAY=2ms, TOFF_DELAY=0msIpeak=119AIocp=146AProchot=134.4AOCP_DELAY=0,4msLATCH OFF MODEOV FAULT LIMIT =14.25VOV WARN LIMIT=13.875VUV WARN LIMIT =10.75VPG_ON=11V, PG_OFF=8VOT FAULT LIMIT=125OT WARN LIMIT=100
EN>1.2V ONEN<0.95V OFF
Soft start time=6ms. Vout Slew rate: 2V/ms
7BITS ADDRESS 0X20h
Cload = 1620uF 
Soft start time=6ms. Vout Slew rate: 2V/ms
For MP5981: DNI PR37, PR38, PR39Change PU3 to AL005981A00
HSC MP5990 and LTC4282/7 share FS1 and PD1, PD2.DVT_CHANGESMB_BIC_I2C6_MUX_VR_R_SCL[99,213,223,226]SMB_BIC_I2C6_MUX_VR_R_SDA[99,213,223,226]FM_HSC_FAULT_N [213,216]PWRGD_P12V_AUX_R [121,153,213,220]HSC_D_OC_R [210,213,215]HSC_ALERT1_R_N[213,216]HSC_P12V_EN[152,213]AGND_HSCP12V_STBYP12V_AUXHSC_VDDHSC_VDDAGND_HSCAGND_HSCAGND_HSCHSC_VDDAGND_HSCP3V3_AUXP12V_AUXAGND_HSCAGND_HSCAGND_HSCP12V_AUXP12V_STBYHSC_VDDAGND_HSCAGND_HSCAGND_HSCAGND_HSCP12V_STBYP12V_AUXHSC_VDDAGND_HSCAGND_HSCAGND_HSCAGND_HSC
P12V_STBY_FUSEP12V_STBY_FUSE
SizeDoc NumberRevDate: SheetofReviewerDesignerDepartmentProject
Page TitleCCBU 11214 257Tuesday, August 29, 2023<project_name><Designer> GRANDTETON_SWB_20230829214 P12V_AUX_MP5990_HSC(1/3)<Reviewer>SizeDoc NumberRevDate: SheetofReviewerDesignerDepartmentProject
Page TitleCCBU 11214 257Tuesday, August 29, 2023<project_name><Designer> GRANDTETON_SWB_20230829214 P12V_AUX_MP5990_HSC(1/3)<Reviewer>SizeDoc NumberRevDate: SheetofReviewerDesignerDepartmentProject
Page TitleCCBU 11214 257Tuesday, August 29, 2023<project_name><Designer> GRANDTETON_SWB_20230829214 P12V_AUX_MP5990_HSC(1/3)<Reviewer>PR40 0 1/16W5% R0402-0201<Part Number>HSC_BOM1
PR54.99K1/16W1%R0402-0201<Part Number>HSC_BOM1PR2601/16W5%R0402-0201<Part Number>HSC_BOM1PC131UF25V10%C0402-0201<Part Number>HSC_BOM1
PR15 2K 1/16W1% R0402-0201<Part Number>HSC_BOM1PD2SS15P3S-M3/86A<Part Number>1K2PR14 10K1/16W1%R0402-0201<Part Number>HSC_BOM1PR64.99K1/16W1%R0402-0201<Part Number>HSC_BOM1PR16 10K 1/16W1% R0402-0201<Part Number>HSC_BOM1
PR36 120K 1/16W1% R0402-0201<Part Number>HSC_BOM1MP5991GLU-ZPU2<Part Number>HSC_BOM1VIN19VIN210VIN311VIN412VIN513ON4OCREF24CS23IMON22VDD3321GND20SS19GOK5VTEMP18VOUT11VOUT22VOUT325VOUT426D_OC3VIN614VIN715VIN816VIN933VOUT527VOUT628VOUT729VOUT830VOUT931VOUT1032MODE8SCREF_OCWREF17FLT_TYPE6NC17
PR3 75K1/16W 1%R0402-0201<Part Number>HSC_BOM1R6245 22 1/16W1% R0402-0201<Part Number>HSC_BOM1R492 01/16W5% R0402-0201<Part Number>HSC_BOM1PR32100K1/16W1%R0402-0201<Part Number>NI
FS120A/125V12 PC8 0.068UF 16V10% C0402-0201<Part Number>HSC_BOM1PR27 120K 1/16W1% R0402-0201<Part Number>HSC_BOM1R6246 22 1/16W1% R0402-0201<Part Number>HSC_BOM1PR29 0 1/16W5% R0402-0201<Part Number>HSC_BOM1
PC20.01UF50V10%C0402-0201<Part Number>HSC_BOM1PC41UF25V10%C0402-0201<Part Number>HSC_BOM1R49482K<Part Number>R0402-02011%1/16WR62510 R0402-02015% <Part Number>HSC_BOM1PR28 0 1/16W5% R0402-0201<Part Number>HSC_BOM1PR332K1/16W1%R0402-0201<Part Number>HSC_BOM1
PR81K1/16W1%R0402-0201<Part Number>HSC_BOM1PR275K1/16W1%R0402-0201<Part Number>HSC_BOM1PC11UF10%25VC0402-0201<Part Number>HSC_BOM1
PC120.068UF16V10%C0402-0201<Part Number>HSC_BOM1
PR13 2K 1/16W1% R0402-0201<Part Number>HSC_BOM1
PR39 0 1/16W5% R0402-0201<Part Number>HSC_BOM1
R62471K1/16W1%R0402-0201<Part Number>HSC_BOM1PC11220PF50V10%C0402-0201<Part Number>HSC_BOM1PJ1<Part Number>HSC_BOM1321 PR21 0 1/16W5% R0402-0201<Part Number>HSC_BOM1PU1MP5990GMA-2222-Z<Part Number>HSC_BOM1VOUT329VOUT228VOUT127VIN22EN26VIN33VIN44GND118SDA12VIN_UVW#14SCL11D_OC37VOUT531VOUT935ALT#10GOK39VIN77VOUT733MODE41VIN88PG||OCW#13VOUT834ON38VIN55VIN66VTEMP15OCREF22SCREF_OCWREF25SS16VOUT632IMON21CS20VIN94236VOUT10VOSEN24VOUT430VIN11GND244FLT_TYPE40VIN1043VINSEN9VDD33_117VDD33_245VDD1819ADDR23PR342K1/16W1%R0402-0201<Part Number>HSC_BOM1
PR401/16W5%R0402-0201<Part Number>HSC_BOM1PC6 0.047UF 25V10% C0402-0201<Part Number>HSC_BOM1R49531.6K<Part Number>R0402-02011%1/16WPR11 120K 1/16W1% R0402-0201<Part Number>HSC_BOM1R493 01/16W5% R0402-0201<Part Number>HSC_BOM1
PR37 0 1/16W5% R0402-0201<Part Number>HSC_BOM1PR31 0 1/16W5% R0402-0201<Part Number>HSC_BOM1PC51UF25V10%C0402-0201<Part Number>HSC_BOM1
PR41100K1/16W1%R0402-0201<Part Number>NI
PC7 0.001UF 50V20% C0402-0201<Part Number>HSC_BOM1PD15.0SMDJ14A<Part Number>AC
PC101UF25V10%C0402-0201<Part Number>HSC_BOM1PR3501/16W5%R0402-0201<Part Number>HSC_BOM1
PC91UF25V10%C0402-0201<Part Number>HSC_BOM1PR1 0 1/16W5% R0402-0201<Part Number>HSC_BOM1PR710K1/16W1%R0402-0201<Part Number>HSC_BOM1PR17 01/16W5%R0402-0201<Part Number>HSC_BOM1PC30.01UF50V10%C0402-0201<Part Number>HSC_BOM1R6249 16.9KR0402-0201<Part Number> 1%1/16WHSC_BOM1C39901000PFC0402-020150VX7R<Part Number>NIR624822 1/16W1% R0402-0201<Part Number>HSC_BOM1
MP5991GLU-ZPU3<Part Number>HSC_BOM1VIN19VIN210VIN311VIN412VIN513ON4OCREF24CS23IMON22VDD3321GND20SS19GOK5VTEMP18VOUT11VOUT22VOUT325VOUT426D_OC3VIN614VIN715VIN816VIN933VOUT527VOUT628VOUT729VOUT830VOUT931VOUT1032MODE8SCREF_OCWREF17FLT_TYPE6NC17
R6250 6.19K 1/16W1% R0402-0201<Part Number>HSC_BOM1
PC150.068UF16V10%C0402-0201<Part Number>HSC_BOM1PR38 0 1/16W5% R0402-0201<Part Number>HSC_BOM1
R6600 0R0402-0201<Part Number> 5%HSC_BOM1
PR432K1/16W1%R0402-0201<Part Number>HSC_BOM1PC14220PF50V10%C0402-0201<Part Number>NIPR30 0 1/16W5% R0402-0201<Part Number>HSC_BOM1PR422K1/16W1%R0402-0201<Part Number>HSC_BOM1
HSC_VINSENHSC_VOSENHSC_D_OCSMB_HOTSWAP_SCL_RSMB_HOTSWAP_SDA_RHSC_VIN_UVW_NHSC_OCREFHSC_ONHSC_ON_RHSC_SCREFHSC_VDD18HSC_FLT_TYPEHSC_VDD_1HSC_MODE_1HSC_SCREFHSC_SCREF_1HSC_VDD_RHSC_ALERT1_NHSC_FAULT_NHSC_IMONHSC_MODEHSC_CSHSC_VTEMPHSC_SSFM_HSC_PWROKHSC_ONHSC_OCREFHSC_CS_1HSC_IMONHSC_D_OC_1HSC_FLT_TYPE_1HSC_FLT_TYPE_RHSC_VTEMPHSC_SSHSC_FAULT_N_1HSC_VDD_2HSC_MODE_2HSC_SCREFHSC_SCREF_2HSC_D_OC_2HSC_FLT_TYPE_2HSC_FLT_TYPE_RHSC_ONHSC_OCREFHSC_FAULT_N_2HSC_CS_2HSC_VTEMPHSC_IMONHSC_SS
FM_HSC_FAULT_NHSC_FLT_TYPE_RHSC_D_OC_RHSC_P12V_MP5990_EN



5
5
4
4
3
3
2
2
1
1
D D
C C
B B
A A
P12V_AUX_MP5990_HSC(2/3)
D_OC with digital signal don't need to compare
UV Setting:TPS3700 Vthr+: 0.400VTPS3700 Vthf-: 0.393.5VFM_UV_ADR_TRIGGER_N low when P12V_AUX drop to IRQ_UV_DETECT_N low when P12V_AUX drop to 10.92V
Open-Drain Buffer
DVT_CHANGELT6700_layout
BOM CHANGE
BOM CHANGE
DVT_CHANGEHSC_D_OC_BUF_R_N [86,118,213]HSC_UV_R_N [86,118,215]HSC_D_OC_R[210,213,214]
HSC_UV_R_N [86,118,215]
P12V_AUXP12V_AUXP3V3_AUXP3V3_AUXP3V3_AUXP3V3_AUX
P12V_AUXP3V3_AUXP12V_AUXP3V3_AUXSizeDoc NumberRevDate: SheetofReviewerDesignerDepartmentProject
Page TitleCCBU 11215 257Tuesday, August 29, 2023<project_name><Designer> GRANDTETON_SWB_20230829215 P12V_AUX_MP5990_HSC(2/3)<Reviewer>SizeDoc NumberRevDate: SheetofReviewerDesignerDepartmentProject
Page TitleCCBU 11215 257Tuesday, August 29, 2023<project_name><Designer> GRANDTETON_SWB_20230829215 P12V_AUX_MP5990_HSC(2/3)<Reviewer>SizeDoc NumberRevDate: SheetofReviewerDesignerDepartmentProject
Page TitleCCBU 11215 257Tuesday, August 29, 2023<project_name><Designer> GRANDTETON_SWB_20230829215 P12V_AUX_MP5990_HSC(2/3)<Reviewer>C4479100NFC0402-020110%COMP_BOM2U338LT6700CS6-1#TRPBFCOMP_BOM1VS5INB-4GND2OUTA1INA+3OUTB6R4415267K1%R0402-0201<Part Number>COMP_BOM1R5799 1001%R0402-0201
R678110KR0402-02011%1/16WCOMP_BOM2R677733R0402-02011%1/16WCOMP_BOM2
R4414267K1%R0402-0201<Part Number>COMP_BOM1U415SN74LVC1G07VCC5A2GND3Y4NC1 R498 10R0402-02011% <Part Number>COMP_BOM1C44931UFX6S25VC0402-0201<Part Number>COMP_BOM1R441810K1%R0402-0201<Part Number>COMP_BOM1C28440.1UF25V10%COMP_BOM1C0402-0201X6S
-+U443AP331AWG-7COMP_BOM231452R442010K1%R0402-0201<Part Number>COMP_BOM1U444LM4040AIM3X-2.5/NOPBCOMP_BOM21+12-233
R68251K1/16W1%R0402-0201COMP_BOM1
R67805.11KR0402-02011%1/16WCOMP_BOM2R677810KR0402-02011%1/16WCOMP_BOM2R441710K1%R0402-0201<Part Number>COMP_BOM1R677917.8KR0402-02011%1/16WCOMP_BOM2
C38690.1UF25V10%C0402-0201X7RR441910K1%R0402-0201<Part Number>COMP_BOM1R4961K1/16W1%R0402-0201<Part Number>
D
G
S
Q1252N7002KWCOMP_BOM1DGSC4478100NFC0402-020110%COMP_BOM2C4477100NFC0402-020110%COMP_BOM2
R441610K1%R0402-0201<Part Number>COMP_BOM1R67761MR0402-02011%1/16WCOMP_BOM2A_P12V_AUX_ADR_TRIGGERFM_UV_ADR_TRIGGER_NA_P12V_AUX_FP_TRIGGERA_P12V_AUX_FPH_GATEHSC_UV_NHSC_D_OC_BUF_N
HSC_UV_R2_NP12V_AUX_FP_TRIGGERUV_P2V5_COMP
FM_UV_LT6700_VS



5
5
4
4
3
3
2
2
1
1
D D
C C
B B
A A
P12V_AUX_MP5990_HSC(3/3)
FM_HSC_FAULT_N[213,214]HSC_ALERT1_R_N[213,214]SMB_ALERT_HSC_R_N [88,118]P3V3_AUXP3V3_AUX
SizeDoc NumberRevDate: SheetofReviewerDesignerDepartmentProject
Page TitleCCBU 11216 257Tuesday, August 29, 2023<project_name><Designer> GRANDTETON_SWB_20230829216 P12V_AUX_MP5990_HSC(3/3)<Reviewer>SizeDoc NumberRevDate: SheetofReviewerDesignerDepartmentProject
Page TitleCCBU 11216 257Tuesday, August 29, 2023<project_name><Designer> GRANDTETON_SWB_20230829216 P12V_AUX_MP5990_HSC(3/3)<Reviewer>SizeDoc NumberRevDate: SheetofReviewerDesignerDepartmentProject
Page TitleCCBU 11216 257Tuesday, August 29, 2023<project_name><Designer> GRANDTETON_SWB_20230829216 P12V_AUX_MP5990_HSC(3/3)<Reviewer>
U34074LVC1G08GV12453R4994.7K<Part Number>R0402-02015%NIC2846 0.1UFX7R 16V C0402-020110%R500 33R0402-02011%<Part Number>SMB_ALERT_HSC_N



5
5
4
4
3
3
2
2
1
1
D D
C C
B B
A A
RA
RB
Enable:Vth > 1.2V (High)
Vo=0.8(1+RA/RB)=1.8V
RB
RA
Enable:Vth > 1.2V (High)
Vo=0.8(1+RA/RB)=1.8V
P1V8_PEX_PLL_RT9059BGQW_1
OUTPUT VOLTAGE = 1.8V +/-3%OUTPUT RIPPLE = +/-3%TRANSIENT TOLERANCE = +/-3%
TDC = 0.5AMAX CURRENT = 0.5APD = (3.3V - 1.8V) * 0.5A = 0.75W
P1V8_PLL_PEX Design specification
PWR_EN_PEX_R[118,217,218,223,226,229,230,231,232,233]PWRGD_PEX0_P1V8_PLL_R[116]PWR_EN_PEX_R[118,217,218,223,226,229,230,231,232,233]PWRGD_PEX1_P1V8_PLL_R[116]
P5V_AUXP3V3_AUXP3V3_AUXP1V8_PLL0_PEX0P3V3_AUXP5V_AUXP3V3_AUXP3V3_AUXP1V8_PLL0_PEX1P3V3_AUXSizeDoc NumberRevDate: SheetofReviewerDesignerDepartmentProject
Page TitleCCBU 11217 257Tuesday, August 29, 2023<project_name><Designer> GRANDTETON_SWB_20230829217 P1V8_PEX_PLL_RT9059BGQW_1<Reviewer>SizeDoc NumberRevDate: SheetofReviewerDesignerDepartmentProject
Page TitleCCBU 11217 257Tuesday, August 29, 2023<project_name><Designer> GRANDTETON_SWB_20230829217 P1V8_PEX_PLL_RT9059BGQW_1<Reviewer>SizeDoc NumberRevDate: SheetofReviewerDesignerDepartmentProject
Page TitleCCBU 11217 257Tuesday, August 29, 2023<project_name><Designer> GRANDTETON_SWB_20230829217 P1V8_PEX_PLL_RT9059BGQW_1<Reviewer>C442010UFC0805_H6110%16V<Part Number>X7R
C441510UFC0805_H6110%16V<Part Number>X7RR656810K<Part Number>1%R0402-02011/16WR657110KR0402-02015%<Part Number>
NI
R657510K<Part Number>1%R0402-02011/16W
R656510KR0402-02015%<Part Number>
NI
C44170.1UFC0402-020110%25V<Part Number>X7RC441622UFC0805_H5720%16V<Part Number>X6SC44220.1UFC0402-020110%25V<Part Number>X7RR6572 05% R0402-0201<Part Number>R65760<Part Number>5%R0402-02011/16WR657412K<Part Number>1%R0402-02011/16WC44191UFC0402-020110%25V<Part Number>X6S
U430RT9059GQW<Part Number>PGOOD5EN6ADJ4VOUT11VIN17VDD10EPTHVOUT22VOUT33VIN28VIN39
C44231000PFX7R50VC0402-0201<Part Number>
NI
C44141UFC0402-020110%25V<Part Number>X6SR656615K<Part Number>1%R0402-02011/16WR656712K<Part Number>1%R0402-02011/16WR657315K<Part Number>1%R0402-02011/16W
R6570 05% R0402-0201<Part Number>C44181000PFX7R50VC0402-0201<Part Number>
NI
R65690<Part Number>5%R0402-02011/16WU431RT9059GQW<Part Number>PGOOD5EN6ADJ4VOUT11VIN17VDD10EPTHVOUT22VOUT33VIN28VIN39C442122UFC0805_H5720%16V<Part Number>X6S
PEX0_P1V8_PLL_ENP1V8_PLL_PEX0_ADJPWRGD_PEX0_P1V8_PLL_RPWRGD_PEX0_P1V8_PLLPEX1_P1V8_PLL_ENP1V8_PLL_PEX1_ADJPWRGD_PEX1_P1V8_PLL_RPWRGD_PEX1_P1V8_PLL



5
5
4
4
3
3
2
2
1
1
D D
C C
B B
A A
RA
Enable:Vth > 1.2V (High)
RA
Vo=0.8(1+RA/RB)=1.8V
RB
Vo=0.8(1+RA/RB)=1.8V
Enable:Vth > 1.2V (High)
RB
P1V8_PEX_PLL_RT9059BGQW_2
OUTPUT VOLTAGE = 1.8V +/-3%OUTPUT RIPPLE = +/-3%TRANSIENT TOLERANCE = +/-3%
TDC = 0.5AMAX CURRENT = 0.5APD = (3.3V - 1.8V) * 0.5A = 0.75W
P1V8_PLL_PEX Design specification
PWR_EN_PEX_R[118,217,218,223,226,229,230,231,232,233]PWRGD_PEX2_P1V8_PLL_R[116]PWR_EN_PEX_R[118,217,218,223,226,229,230,231,232,233]PWRGD_PEX3_P1V8_PLL_R[116]
P5V_AUXP3V3_AUXP3V3_AUXP1V8_PLL0_PEX2P3V3_AUXP5V_AUXP3V3_AUXP3V3_AUXP1V8_PLL0_PEX3P3V3_AUXSizeDoc NumberRevDate: SheetofReviewerDesignerDepartmentProject
Page TitleCCBU 11218 257Tuesday, August 29, 2023<project_name><Designer> GRANDTETON_SWB_20230829218 P1V8_PEX_PLL_RT9059BGQW_2<Reviewer>SizeDoc NumberRevDate: SheetofReviewerDesignerDepartmentProject
Page TitleCCBU 11218 257Tuesday, August 29, 2023<project_name><Designer> GRANDTETON_SWB_20230829218 P1V8_PEX_PLL_RT9059BGQW_2<Reviewer>SizeDoc NumberRevDate: SheetofReviewerDesignerDepartmentProject
Page TitleCCBU 11218 257Tuesday, August 29, 2023<project_name><Designer> GRANDTETON_SWB_20230829218 P1V8_PEX_PLL_RT9059BGQW_2<Reviewer>
R65820<Part Number>5%R0402-02011/16WR658515K<Part Number>1%R0402-02011/16WR658710K<Part Number>1%R0402-02011/16WC44320.1UFC0402-020110%25V<Part Number>X7RR658012K<Part Number>1%R0402-02011/16W
R65880<Part Number>5%R0402-02011/16WC443010UFC0805_H6110%16V<Part Number>X7RR658110K<Part Number>1%R0402-02011/16WC44270.1UFC0402-020110%25V<Part Number>X7RC442622UFC0805_H5720%16V<Part Number>X6SC44281000PFX7R50VC0402-0201<Part Number>NI
C44331000PFX7R50VC0402-0201<Part Number>NI
U432RT9059GQW<Part Number>PGOOD5EN6ADJ4VOUT11VIN17VDD10EPTHVOUT22VOUT33VIN28VIN39
R658310KR0402-02015%<Part Number>
NI
C44291UFC0402-020110%25V<Part Number>X6SR657710KR0402-02015%<Part Number>
NI
C44241UFC0402-020110%25V<Part Number>X6SR657915K<Part Number>1%R0402-02011/16WC442510UFC0805_H6110%16V<Part Number>X7R
R6584 05% R0402-0201<Part Number>
R6578 05% R0402-0201<Part Number>U433RT9059GQW<Part Number>PGOOD5EN6ADJ4VOUT11VIN17VDD10EPTHVOUT22VOUT33VIN28VIN39C443122UFC0805_H5720%16V<Part Number>X6SR658612K<Part Number>1%R0402-02011/16W
PEX2_P1V8_PLL_ENP1V8_PLL_PEX2_ADJPWRGD_PEX2_P1V8_PLL_RPWRGD_PEX2_P1V8_PLLPEX3_P1V8_PLL_ENP1V8_PLL_PEX3_ADJPWRGD_PEX3_P1V8_PLL_RPWRGD_PEX3_P1V8_PLL



5
5
4
4
3
3
2
2
1
1
D D
C C
B B
A A
BLANK SizeDoc NumberRevDate: SheetofReviewerDesignerDepartmentProject
Page TitleCCBU 11219 257Tuesday, August 29, 2023<project_name><Designer> GRANDTETON_SWB_20230829219 BLANK<Reviewer>SizeDoc NumberRevDate: SheetofReviewerDesignerDepartmentProject
Page TitleCCBU 11219 257Tuesday, August 29, 2023<project_name><Designer> GRANDTETON_SWB_20230829219 BLANK<Reviewer>SizeDoc NumberRevDate: SheetofReviewerDesignerDepartmentProject
Page TitleCCBU 11219 257Tuesday, August 29, 2023<project_name><Designer> GRANDTETON_SWB_20230829219 BLANK<Reviewer>



5
5
4
4
3
3
2
2
1
1
D D
C C
B B
A A
OUTPUT VOLTAGE = 5.0V +/-5%OUTPUT RIPPLE <= 50MVDC TOLERANCE <= 500MV
TDC = 0.9AMAX CURRENT = 0.9AOCP (IC DEFAULT) = 2.1ACURRENT STEP = 0.39ASLEW RATE = 2.5A/USWork frequency = 800KHZEfficiency > 90% @TDC
P5V_AUX Design specification
Enable========VIH(min)=2.7VVIL(max)=0.4V
Vo=0.8(1+Ra/Rb)=5V
Ra
Rb
PGood = 3.33V
DCR=4MOHM
Isat=5A @100℃Isat=4.5A @100℃
P5V_AUX_RT7251B
20220817 Design changePWRGD_P5V_AUX_R [121,221]PWRGD_P12V_AUX_R[121,153,213,214]P5V_AUXP12V_AUXP5V_AUX
SizeDoc NumberRevDate: SheetofReviewerDesignerDepartmentProject
Page TitleCCBU 11220 257Tuesday, August 29, 2023<project_name><Designer> GRANDTETON_SWB_20230829220 P5V_AUX_RT7251B<Reviewer>SizeDoc NumberRevDate: SheetofReviewerDesignerDepartmentProject
Page TitleCCBU 11220 257Tuesday, August 29, 2023<project_name><Designer> GRANDTETON_SWB_20230829220 P5V_AUX_RT7251B<Reviewer>SizeDoc NumberRevDate: SheetofReviewerDesignerDepartmentProject
Page TitleCCBU 11220 257Tuesday, August 29, 2023<project_name><Designer> GRANDTETON_SWB_20230829220 P5V_AUX_RT7251B<Reviewer>
R50110K<Part Number>R0402-02011%1/16WPC1610UFX6S<Part Number>C0805_H6110%25VPR5828K<Part Number>R0402-02011%1/16WR50220K1%<Part Number>R0402-02011/16WPU4RT7251BZQW<Part Number>VIN2PGOOD6GND17SW1EN4BOOT3FB5GND28GND_THTHR503 0 5%R0402-0201<Part Number>1/16WR44290 R0402-02015%<Part Number>PC170.1UFX7R25VC0402-0201<Part Number>10%PR57 147K<Part Number>R0402-02011%1/16WPC2122UFX6S16VC0805_H57<Part Number>20%PC220.1UFX7R25VC0402-0201<Part Number>10%PL1BLM18SN220TN1D<Part Number>8000MA21PC180.1UFX7R25VC0402-0201<Part Number>10%PL210UH<Part Number>INDPCMB063T-100MS4ADCR=68MOHM21PJ2SHORTNI1122PC2022UFX6S16VC0805_H57<Part Number>20%PC190.01UFC0402-0201X7R<Part Number>10% 25VSW_P12V_P5V_AUX_FLTPWRGD_P5V_AUXSW_P5V_AUX_BTSW_P5V_AUX_PHPWRGD_P12V_AUX_RP5V_AUX_ENP5V_AUX_FBSH_P5V_AUX_FB



5
5
4
4
3
3
2
2
1
1
D D
C C
B B
A A
P3V3_AUX Design specification
OUTPUT VOLTAGE = 3.3V +/-5%OUTPUT RIPPLE <=  66MVDC TOLERANCE <=  330MV
TDC = 13.464AMAX CURRENT = 13.464AOCP (IMAX*130%) = 21ACURRENT STEP = 6.426ASLEW RATE = 2.5A/USWork frequency = 600KHZEfficiency > 90% @TDC
Vo=0.6(1+Ra/Rb) = 3.31V
Enable:Vth > 1.27V (High)
FCCM
RaRb
Isat=13A @100℃ Isat=47A@100C
P3V3_AUX_VCC: 3V
P3V3_AUX_RS53319LR
20220817 Design change20220817 Design changePVT changePVT changePWRGD_P5V_AUX_R[121,220]PWRGD_P3V3_AUX_R [70,118,121]P3V3_AUX_VCCP3V3_AUXP12V_AUX
SizeDoc NumberRevDate: SheetofReviewerDesignerDepartmentProject
Page TitleCCBU 11221 257Tuesday, August 29, 2023<project_name><Designer> GRANDTETON_SWB_20230829221 P3V3_AUX_MPQ8633BGLE-C838-Z<Reviewer>SizeDoc NumberRevDate: SheetofReviewerDesignerDepartmentProject
Page TitleCCBU 11221 257Tuesday, August 29, 2023<project_name><Designer> GRANDTETON_SWB_20230829221 P3V3_AUX_MPQ8633BGLE-C838-Z<Reviewer>SizeDoc NumberRevDate: SheetofReviewerDesignerDepartmentProject
Page TitleCCBU 11221 257Tuesday, August 29, 2023<project_name><Designer> GRANDTETON_SWB_20230829221 P3V3_AUX_MPQ8633BGLE-C838-Z<Reviewer>
PC230.1UFX7R25VC0402-0201<Part Number>PC39 56PFC0402-020150VNPO<Part Number>PJ3SHORT<Part Number>
NI
1122+PC37220UF<Part Number>20%6.3VALUM12PL41UH<Part Number>29ADCR=2.5MOHMPCMC135T-1R0MF21PC301UFX6S25VC0402-0201<Part Number>PC3222UFC0805_H5716VX6S<Part Number>PC3522UFC0805_H5716VX6S<Part Number>PR626.19K<Part Number>R0402-02011%PC3322UFC0805_H5716VX6S<Part Number>PC31 0.1UFC0402-020125VX7R<Part Number>PC401UFX6S25VC0402-0201<Part Number>PR6312.4K0.1%R0402-0201<Part Number>+PC25270UF20%16VOSCON<Part Number>12 PC420.1UFX7R25VC0402-0201<Part Number>PC2622UFX6S16VC0805_H57<Part Number>PC360.1UFX7R25VC0402-0201<Part Number>PU5RS53319LR<Part Number>VIN110PGOOD9PGND11_18EN8BST1FB7AGND2VCC19RTN6SW20REF5MODE4CS3VIN221PC2822UFX6S16VC0805_H57<Part Number>PR61 56K0.1% R0402-0201<Part Number>PL3100NH<Part Number>16ADCR=0.12MOHMHCBS4545-10121PC2722UFX6S16VC0805_H57<Part Number>R44300 R0402-02015%<Part Number>+PC24270UFOSCON<Part Number>20%16V12 R82310KR0402-02011%<Part Number>R824 0<Part Number>5% R0402-02011/16WPC3422UFC0805_H5716VX6S<Part Number>+PC38220UF<Part Number>20%6.3VALUM12PC2922UFX6S16VC0805_H57<Part Number>SW_P12V_P3V3_AUX_FLTPWRGD_P3V3_AUXSW_P3V3_AUX_BTPWRGD_P5V_AUX_RP3V3_AUX_ENSW_P3V3_AUX_PHP3V3_AUX_VCCP3V3_AUX_FBP3V3_AUX_REFP3V3_AUX_CSSH_P3V3_AUX_FB



5
5
4
4
3
3
2
2
1
1
D D
C C
B B
A A
P1V2_AUX Design specification
OUTPUT VOLTAGE = 1.2V +/-5%OUTPUT RIPPLE <= 24MVTRANSIENT TOLERANCE <= 120MV
TDC = 0.165AMAX CURRENT = 0.165APD = (3.3V - 1.2V) * 0.165A = 0.3465W
RB
Vo=0.8(1+RA/RB)=1.2V
RA
Enable:Vth > 1.2V (High)
P1V2_AUX_RT9059
PWRGD_P1V2_AUX_R[92,118]PWR_EN_P1V2_AUX_R[118]P5V_AUXP3V3_AUXP1V2_AUXP3V3_AUXP3V3_AUX
SizeDoc NumberRevDate: SheetofReviewerDesignerDepartmentProject
Page TitleCCBU 11222 257Tuesday, August 29, 2023<project_name><Designer> GRANDTETON_SWB_20230829222 P1V2_AUX_RT9059<Reviewer>SizeDoc NumberRevDate: SheetofReviewerDesignerDepartmentProject
Page TitleCCBU 11222 257Tuesday, August 29, 2023<project_name><Designer> GRANDTETON_SWB_20230829222 P1V2_AUX_RT9059<Reviewer>SizeDoc NumberRevDate: SheetofReviewerDesignerDepartmentProject
Page TitleCCBU 11222 257Tuesday, August 29, 2023<project_name><Designer> GRANDTETON_SWB_20230829222 P1V2_AUX_RT9059<Reviewer>
C28510.1UFC0402-020110%25V<Part Number>X7RC24911UFX6S25VC0402-0201<Part Number>R443212K<Part Number>1%R0402-02011/16WU342RT9059GQW<Part Number>PGOOD5EN6ADJ4VOUT11VIN17VDD10EPTHVOUT22VOUT33VIN28VIN39R443424K<Part Number>1%R0402-02011/16WC285010UFC0805_H6110%16V<Part Number>X7RR55380<Part Number>5%R0402-02011/16WC28481UFC0402-020110%25V<Part Number>X6SR443310K<Part Number>1%R0402-02011/16WR252010KR0402-02015%<Part Number>
NI
C284910UFC0805_H6110%16V<Part Number>X7RP1V2_AUX_ADJPWRGD_P1V2_AUX_RPWRGD_P1V2_AUXPWR_EN_P1V2_AUX_R



5
5
4
4
3
3
2
2
1
1
D D
C C
B B
A A
CLOSE TO OUPUT DIFFERENTIAL PAIRTRACE WIDTH = 10MILTRACE SPACING = 5MIL
Note:CAP & DAMPING RS CLOSE TO DRIVE-END
Rail A Rail A Rail A 
Rail BRail B Rail B 
P0V8_PEX0/1  Design specification
0.816V Boot / NominalOutput Ripple & Noise <= 16mV Transient Tolerance <= 80 mV (0.76V~0.84V)TDC = 47.1AMax current = 66.1AOver-Current Protection(Max Current x130%) = 86ACurrent Step = 33.05ASlew Rate = 2.5A/usWork frequency = 600 KHzEfficiency > 80% @TDCLL= NASVID Address = NA
Configuration ID :  0  ( 0R )
CLOSE TO OUPUT DIFFERENTIAL PAIRTRACE WIDTH = 10MILTRACE SPACING = 5MIL
Enable:Vth > 0.8V (High)
Enable:Vth > 0.8V (High)
Renesas (7bit) Renesas InfineonP0V8_PEX0/1
Address 60H C0H C0H
T I
C0H
Res (UP)
Res (Down)
NI
0 OHM
NI
17.4K
332K
115K
NI
0 OHM
Rail A Rail B
P0V8_PEX0/1_controller(1/3)
Note: For MP2971 PR7165 POP
20220817 Design changePWRGD_P0V8_PEX0_R[118]PWR_EN_PEX_R[118,217,218,223,226,229,230,231,232,233]VSENSE_P0V8_PEX0_SKT_VSEN[17]VSENSE_P0V8_PEX0_SKT_VRTN[17]P0V8_PEX0_VREF[223,224,225]
P0V8_PEX0_ISEN1 [224]P0V8_PEX0_VREF [223,224,225]P0V8_PEX0_PWM2 [224]P0V8_PEX0_ISEN2 [224]
P0V8_PEX0_TSEN [224]P0V8_PEX1_TSEN [225]VSENSE_P0V8_PEX1_SKT_VSEN[30]VSENSE_P0V8_PEX1_SKT_VRTN[30]PWRGD_P0V8_PEX1_R[118]
SMB_BIC_I2C6_MUX_VR_R_SCL[99,213,214,226]SMB_BIC_I2C6_MUX_VR_R_SDA[99,213,214,226]PWR_EN_PEX_R[118,217,218,223,226,229,230,231,232,233]SMB_ALERT_PMBUS_R_N[88,226]P0V8_PEX0_PWM1 [224]P0V8_PEX1_PWM1 [225]P0V8_PEX1_ISEN1 [225]P0V8_PEX1_PWM2 [225]P0V8_PEX1_ISEN2 [225]P0V8_PEX0_VREF[223,224,225]P3V3_AUX
P3V3_AUX
P3V3_AUX
P12V_AUX
P0V8_PEX0
P3V3_AUX
P0V8_PEX1
P3V3_AUXP12V_AUXP5V_AUXP3V3_AUXSizeDoc NumberRevDate: SheetofReviewerDesignerDepartmentProject
Page TitleCCBU 11223 257Tuesday, August 29, 2023<project_name><Designer> GRANDTETON_SWB_20230829223 P0V8_PEX0/1_controller(1/3)<Reviewer>SizeDoc NumberRevDate: SheetofReviewerDesignerDepartmentProject
Page TitleCCBU 11223 257Tuesday, August 29, 2023<project_name><Designer> GRANDTETON_SWB_20230829223 P0V8_PEX0/1_controller(1/3)<Reviewer>SizeDoc NumberRevDate: SheetofReviewerDesignerDepartmentProject
Page TitleCCBU 11223 257Tuesday, August 29, 2023<project_name><Designer> GRANDTETON_SWB_20230829223 P0V8_PEX0/1_controller(1/3)<Reviewer>
PC44 100NFC0402-020150VX7R<Part Number>
PR821K1%R0402-0201<Part Number>
NI
PR7305% R0402-0201<Part Number>PR7849.91%<Part Number>R0402-0201PR8405%R0402-0201<Part Number>PC503300PF50VC0402-0201<Part Number>X7R
PR65 1<Part Number>R0402-02015%
PR80 05%R0402-0201<Part Number>PR9410K1%R0402-0201<Part Number>PJ20SHORT <Part Number>
NI1122PR71311K1% R0402-0201<Part Number>PR7133 05%R0402-0201<Part Number>PR714105%R0402-0201<Part Number>PR831K1%R0402-0201<Part Number>PJ18SHORT <Part Number>
NI1122 PR851K1%R0402-0201<Part Number>PC55470PF50V5%C0402-0201<Part Number>NPO
PU6
ISL69259IRAZ-T
CS723VCC39
EN120PMSCL10SVDATA18CS624nSVALERT19
nVRHOT14CS525CS426PG116
SVCLK17nPMALERT11EN013RGND022PMSDA9PWM45PWM56VSEN021PWM12
PG012PWM67VCCS40
VMON||IINSEN37VINSEN38TEMP136nPINALERT15VSEN132RGND131CS129PWM78PWM34CS327PWM23CS228CONFIG33TH_GNDTHADDRESS34TEMP035PWM01CS030
PJP1SCONN3_TSM-103-01-S-SV-TR<Part Number>123
PR981K1%R0402-0201<Part Number>
NI
PC493300PF50VC0402-0201<Part Number>X7R
PR96 40.2K1% R0402-0201<Part Number>
R82605% R0402-0201<Part Number>
PC53470PF50V5%C0402-0201<Part Number>NPO
R8251K1%R0402-0201<Part Number>PR6905% R0402-0201<Part Number>
R83205% R0402-0201<Part Number>PJ19SHORT <Part Number>
NI1122PR77 05%R0402-0201<Part Number>PR91 332K<Part Number>R0402-02011%
NI
PR7132 05%R0402-0201<Part Number>PC540.1UFX7R25VC0402-0201<Part Number>PR8149.91%<Part Number>R0402-0201
C200 1000PFC0402-020150VX7R<Part Number>PR7134 05%R0402-0201<Part Number>PJ5SHORTSHORT_R0603
NI
1122R83005% R0402-0201<Part Number>PR93 05%R0402-0201<Part Number>
NI
PR7140 4.99K1% R0402-0201WR04X4991FTR
NI
PR7135 05%R0402-0201<Part Number>PJ21SHORT <Part Number>
NI1122 PC47100NFX7R<Part Number>C0402-020150V
PC560.1UFX7R25VC0402-0201<Part Number>
PR7649.91%<Part Number>R0402-0201
PR9705% R0402-0201<Part Number>PR9505% R0402-0201<Part Number>
R5772331% R0402-0201<Part Number>R8311K1%R0402-0201<Part Number>PR9005% R0402-0201<Part Number>C833 1000PFC0402-020150VX7R<Part Number>NI
R829 331% R0402-0201<Part Number>R82705% R0402-0201<Part Number>R828 331% R0402-0201<Part Number>PJ6SHORTSHORT_R0603
NI
1122PR7949.91%<Part Number>R0402-0201C832 1000PFC0402-020150VX7R<Part Number>
PR7165 05%R0402-0201<Part Number>NIPC46 10UF25V10%C0805_H61 <Part Number>X6S
PR9205%<Part Number>R0402-0201
C199 1000PFC0402-020150VX7R<Part Number>NIPC45 1UFC0402-020125VX6S<Part Number>P0V8_PEX0_VDDP0V8_PEX0_VREFP0V8_PEX0_VSEN0SMB_VR_P0V8_PEX0_SCLP0V8_PEX0_VRHOT_R
FM_P0V8_PEX0_EN_R
P0V8_PEX0_VR_CONFIGP0V8_PEX0_PINALRTP0V8_PEX0_ADDRP0V8_PEX0_IINSENP0V8_PEX0_VINSEN
P0V8_PEX0_AVRRDY
P0V8_PEX1_TSEN_RP0V8_PEX0_TSEN_R
P0V8_PEX0_SMBALERTSMB_VR_P0V8_PEX0_SDANC_P0V8_PEX0_PWM3NC_P0V8_PEX0_ISEN3NC_P0V8_PEX0_PWM2NC_P0V8_PEX0_ISEN2P0V8_PEX1_VSEN1FM_P0V8_PEX1_EN_RP0V8_PEX1_BVRRDY
SMB_PJP1_SDASH_P0V8_PEX0_VSEN0_LSH_P0V8_PEX0_RGND0SH_P0V8_PEX1_VSEN1_LSH_P0V8_PEX1_RGND1SH_P0V8_PEX0_VSEN0_RSH_P0V8_PEX1_VSEN1_RNC_P0V8_PEX0_PWM4NC_P0V8_PEX0_PWM5NC_P0V8_PEX0_ISEN4NC_P0V8_PEX0_ISEN5NC_P0V8_PEX0_SVID_ALERT_N_RSMB_PJP1_SCLP0V8_PEX0_SVID



5
5
4
4
3
3
2
2
1
1
D D
C C
B B
A A
P0V8_PEX0_Phase-1
6.3*7.7ESR=10mΩRI=5.08A
ESR=3mΩ7.3*4.3
SMD
ESR=3mΩ7.3*4.3
ESR=3mΩ7.3*4.3
P0V8_PEX0_Phase-2
ESR=3mΩ7.3*4.3
ISAT=52A @100CDCR=0.175MOHM9.6 x 6.4 x 12
ISAT=52A @100CDCR=0.175MOHM9.6 x 6.4 x 12
Isat=13A @100℃
P0V8_PEX0_Phase(2/3)
Note: For MP87000 POP: PR7176, R6762, R6763NI: PR7175, PR7167, PR7166
20220817 Design changeP0V8_PEX0_TSEN[223,224]P0V8_PEX0_PWM1[223]P0V8_PEX0_ISEN1[223]P0V8_PEX0_VREF[223,224,225]P0V8_PEX0_TSEN[223,224]P0V8_PEX0_PWM2[223]P0V8_PEX0_ISEN2[223]P0V8_PEX0_VREF
SW_P12V_P0V8_PEX0_FLTP12V_AUX
P0V8_PEX0P0V8_PEX0_PVCCSW_P12V_P0V8_PEX0_FLTP0V8_PEX0
P3V3_AUXP5V_AUXP0V8_PEX0_PVCC
SizeDoc NumberRevDate: SheetofReviewerDesignerDepartmentProject
Page TitleCCBU 11224 257Tuesday, August 29, 2023<project_name><Designer> GRANDTETON_SWB_20230829224 P0V8_PEX0_Phase(2/3)<Reviewer>SizeDoc NumberRevDate: SheetofReviewerDesignerDepartmentProject
Page TitleCCBU 11224 257Tuesday, August 29, 2023<project_name><Designer> GRANDTETON_SWB_20230829224 P0V8_PEX0_Phase(2/3)<Reviewer>SizeDoc NumberRevDate: SheetofReviewerDesignerDepartmentProject
Page TitleCCBU 11224 257Tuesday, August 29, 2023<project_name><Designer> GRANDTETON_SWB_20230829224 P0V8_PEX0_Phase(2/3)<Reviewer>
PU7ISL99380FRZ-TR5935<Part Number>PWM34REFIN39VCC3AGND2BOOT33VIN25_29PHASE32PVCC4TOUT_FLT36IOUT38PGND7_9-20_24LSET37SW10_19PGND_15VIN130VOS1PGND_240EN35DNC31GL_16GL_241PR716605%R0402-0201<Part Number>PR104 3.31/16W1% R0402-0201<Part Number>
PR717505%R0402-0201<Part Number>PC742.2UF10VC0402-0201<Part Number>10%X7SPR10611K1%R0402-0201<Part Number>
R67622K1%R0402-0201NI<Part Number>PC8622UFX6S4VC0805_H61<Part Number>  PR94991%R0603<Part Number>
PL5100NH<Part Number>L_HCBS4545_4-5X4-516ADCR=0.12MOHM21PC591UFX6S25VC0402-0201<Part Number>PR716705%R0402-0201<Part Number>PR10211K1%R0402-0201<Part Number>PC661022UF16V<Part Number>C0805_H57X6SPC660722UF16V<Part Number>C0805_H57X6SPC8422UFX6S4VC0805_H61<Part Number>  
PC660.22UFX7R25VC0402-0201<Part Number>PC750.1UFX7R25VC0402-0201<Part Number>PU8ISL99380FRZ-TR5935<Part Number>PWM34REFIN39VCC3AGND2BOOT33VIN25_29PHASE32PVCC4TOUT_FLT36IOUT38PGND7_9-20_24LSET37SW10_19PGND_15VIN130VOS1PGND_240EN35DNC31GL_16GL_241PC7922UF16V<Part Number>C0805_H57X6SPC9820.1UFX7R25VC0402-0201<Part Number>
+PC88470UF2V<Part Number>*LF_C_POSCAP12PC660922UF16V<Part Number>C0805_H57X6SPC6222UF16V<Part Number>C0805_H57X6S
PR10505% R0402-0201<Part Number>PC830.1UF25VX7RC0402-0201<Part Number>
PR100 3.31/16W1% R0402-0201<Part Number>PR10105% R0402-0201<Part Number>PC6322UF16V<Part Number>C0805_H57X6SPC730.1UFX7R25VC0402-0201<Part Number>+PC64270UF16V<Part Number>OSCON12
PC890.1UFX7R25VC0402-0201<Part Number>+PC71470UF2V<Part Number>*LF_C_POSCAP12PR1032.21/16W1%R0402-0201<Part Number>R67632K1%R0402-0201NI<Part Number>
PC652.2UF10VC0402-0201<Part Number>10%X7SPC812.2UF10VC0402-0201<Part Number>10%X7S
PC572.2UF10VC0402-0201<Part Number>10%X7S+PC72470UF2V<Part Number>*LF_C_POSCAP12PC8022UF16V<Part Number>C0805_H57X6SPC7722UF16V<Part Number>C0805_H57X6S
PR717605%R0402-0201<Part Number>NI PC670.1UF25VX7RC0402-0201<Part Number>
+PC87470UF2V<Part Number>*LF_C_POSCAP12
PL6220NH<Part Number>PGL6216.221HLT61A21PC7022UFX6S4VC0805_H61<Part Number>  PC660822UF16V<Part Number>C0805_H57X6SPC580.1UFX7R25VC0402-0201<Part Number>PC820.22UFX7R25VC0402-0201<Part Number>
PR992.21/16W1%R0402-0201<Part Number>PC761UFX6S25VC0402-0201<Part Number>PC6122UF16V<Part Number>C0805_H57X6S
PL7220NH<Part Number>PGL6216.221HLT61A21PC6922UFX6S4VC0805_H61<Part Number>  PC8522UFX6S4VC0805_H61<Part Number>  PC7822UF16V<Part Number>C0805_H57X6SPC6822UFX6S4VC0805_H61<Part Number>  PC6022UF16V<Part Number>C0805_H57X6SSW_P0V8_PEX0_BOOT1SW_P0V8_PEX0_BOOT1_RSW_P0V8_PEX0_PHASE1SW_P0V8_PEX0_PH1SW_P0V8_PEX0_VOS1P0V8_PEX0_VCC1P0V8_PEX0_LSET1P0V8_PEX0_VCC2SW_P0V8_PEX0_BOOT2SW_P0V8_PEX0_BOOT2_RSW_P0V8_PEX0_PHASE2SW_P0V8_PEX0_PH2SW_P0V8_PEX0_VOS2P0V8_PEX0_LSET2NC_P0V8_PEX0_PH1_NC3NC_P0V8_PEX0_PH1_NC1NC_P0V8_PEX0_PH1_NC2NC_P0V8_PEX0_PH2_NC3NC_P0V8_PEX0_PH2_NC1NC_P0V8_PEX0_PH2_NC2
P0V8_PEX0_PVCCP0V8_PEX0_EN1P0V8_PEX0_EN2



5
5
4
4
3
3
2
2
1
1
D D
C C
B B
A A
P0V8_PEX1_Phase-1
ESR=3mΩ7.3*4.3
SMD
ESR=3mΩ7.3*4.3
P0V8_PEX1_Phase-2
ISAT=52A @100CDCR=0.175MOHM9.6 x 6.4 x 12
ISAT=52A @100CDCR=0.175MOHM9.6 x 6.4 x 12
Isat=13A @100℃
6.3*7.7ESR=10mΩRI=5.08A
ESR=3mΩ7.3*4.3 ESR=3mΩ7.3*4.3
P0V8_PEX1_Phase(3/3)
Note: For MP87000 POP: PR7177, R6764, R6765NI: PR7178, PR7168, PR7169
20220817 Design changeP0V8_PEX1_TSEN[223,225]P0V8_PEX1_PWM1[223]P0V8_PEX1_ISEN1[223]P0V8_PEX0_VREF[223,224,225]P0V8_PEX1_TSEN[223,225]P0V8_PEX1_PWM2[223]P0V8_PEX1_ISEN2[223]P0V8_PEX0_VREF[223,224,225]
SW_P12V_P0V8_PEX1_FLTP12V_AUX
P0V8_PEX1P0V8_PEX1_PVCCSW_P12V_P0V8_PEX1_FLTP0V8_PEX1
P3V3_AUXP5V_AUXP0V8_PEX1_PVCC
SizeDoc NumberRevDate: SheetofReviewerDesignerDepartmentProject
Page TitleCCBU 11225 257Tuesday, August 29, 2023<project_name><Designer> GRANDTETON_SWB_20230829225 P0V8_PEX1_Phase(3/3)<Reviewer>SizeDoc NumberRevDate: SheetofReviewerDesignerDepartmentProject
Page TitleCCBU 11225 257Tuesday, August 29, 2023<project_name><Designer> GRANDTETON_SWB_20230829225 P0V8_PEX1_Phase(3/3)<Reviewer>SizeDoc NumberRevDate: SheetofReviewerDesignerDepartmentProject
Page TitleCCBU 11225 257Tuesday, August 29, 2023<project_name><Designer> GRANDTETON_SWB_20230829225 P0V8_PEX1_Phase(3/3)<Reviewer>+PC119470UF2V<Part Number>*LF_C_POSCAP12
PR717805%R0402-0201<Part Number>PC11422UF16V<Part Number>C0805_H57X6SPC9422UF16V<Part Number>C0805_H57X6SPC661222UF16V<Part Number>C0805_H57X6SPR1112.21/16W1%R0402-0201<Part Number>PC1220.1UFX7R25VC0402-0201<Part Number>PC12022UFX6S4VC0805_H61<Part Number>  PC661322UF16V<Part Number>C0805_H57X6SPR11411K1%R0402-0201<Part Number>
PU9ISL99380FRZ-TR5935<Part Number>PWM34REFIN39VCC3AGND2BOOT33VIN25_29PHASE32PVCC4TOUT_FLT36IOUT38PGND7_9-20_24LSET37SW10_19PGND_15VIN130VOS1PGND_240EN35DNC31GL_16GL_241PR10905% R0402-0201<Part Number>PC910.1UFX7R25VC0402-0201<Part Number>PC11222UF16V<Part Number>C0805_H57X6SPC1080.1UFX7R25VC0402-0201<Part Number>PR108 3.31/16W1% R0402-0201<Part Number>PC982.2UF10VC0402-0201<Part Number>10%X7S
PR11305% R0402-0201<Part Number>
PC9522UF16V<Part Number>C0805_H57X6S
PC12122UFX6S4VC0805_H61<Part Number>  PL10220NH<Part Number>PGL6216.221HLT61A21PR716905%R0402-0201<Part Number>PC1091UFX6S25VC0402-0201<Part Number>PC902.2UF10VC0402-0201<Part Number>10%X7SPC661122UF16V<Part Number>C0805_H57X6S+PC104470UF2V<Part Number>*LF_C_POSCAP12PC1150.22UFX7R25VC0402-0201<Part Number>PC661422UF16V<Part Number>C0805_H57X6SR67642K1%R0402-0201NI<Part Number>PR1072.21/16W1%R0402-0201<Part Number>PC9322UF16V<Part Number>C0805_H57X6SPC9830.1UFX7R25VC0402-0201<Part Number>PC10322UFX6S4VC0805_H61<Part Number>  PR112 3.31/16W1% R0402-0201<Part Number>PC1000.1UF25VX7RC0402-0201<Part Number>PC1072.2UF10VC0402-0201<Part Number>10%X7SPC10222UFX6S4VC0805_H61<Part Number>  PU10ISL99380FRZ-TR5935<Part Number>PWM34REFIN39VCC3AGND2BOOT33VIN25_29PHASE32PVCC4TOUT_FLT36IOUT38PGND7_9-20_24LSET37SW10_19PGND_15VIN130VOS1PGND_240EN35DNC31GL_16GL_241PL9220NH<Part Number>PGL6216.221HLT61A21PC990.22UFX7R25VC0402-0201<Part Number>PR11011K1%R0402-0201<Part Number>PC11022UF16V<Part Number>C0805_H57X6SR67652K1%R0402-0201NI<Part Number>PC1160.1UF25VX7RC0402-0201<Part Number>PR104991%R0603<Part Number>
PR717705%R0402-0201<Part Number>NI PC9622UF16V<Part Number>C0805_H57X6SPC1132.2UF10VC0402-0201<Part Number>10%X7S+PC118470UF2V<Part Number>*LF_C_POSCAP12
PR716805%R0402-0201<Part Number>PC10122UFX6S4VC0805_H61<Part Number>  PC11722UFX6S4VC0805_H61<Part Number>  PC1060.1UFX7R25VC0402-0201<Part Number>+PC105470UF2V<Part Number>*LF_C_POSCAP12PL8100NH<Part Number>L_HCBS4545_4-5X4-516ADCR=0.12MOHM21+PC97270UF16V<Part Number>OSCON12PC921UFX6S25VC0402-0201<Part Number>PC11122UF16V<Part Number>C0805_H57X6SSW_P0V8_PEX1_BOOT1SW_P0V8_PEX1_BOOT1_RSW_P0V8_PEX1_PHASE1SW_P0V8_PEX1_PH1SW_P0V8_PEX1_VOS1P0V8_PEX1_VCC1P0V8_PEX1_LSET1P0V8_PEX1_VCC2SW_P0V8_PEX1_BOOT2SW_P0V8_PEX1_BOOT2_RSW_P0V8_PEX1_PHASE2SW_P0V8_PEX1_PH2SW_P0V8_PEX1_VOS2P0V8_PEX1_LSET2NC_P0V8_PEX1_PH1_NC3NC_P0V8_PEX1_PH1_NC1NC_P0V8_PEX1_PH1_NC2NC_P0V8_PEX1_PH2_NC3NC_P0V8_PEX1_PH2_NC1NC_P0V8_PEX1_PH2_NC2
P0V8_PEX1_PVCCP0V8_PEX0_EN3P0V8_PEX0_EN4



5
5
4
4
3
3
2
2
1
1
D D
C C
B B
A A
CLOSE TO OUPUT DIFFERENTIAL PAIRTRACE WIDTH = 10MILTRACE SPACING = 5MIL
Note:CAP & DAMPING RS CLOSE TO DRIVE-END
Rail A 
Rail A Rail A Rail A 
Rail BRail B Rail B 
P0V8_PEX2/3  Design specification
0.816V Boot / NominalOutput Ripple & Noise <= 16mV Transient Tolerance <= 80 mV (0.76V~0.84V)TDC = 47.1AMax current = 66.1AOver-Current Protection(Max Current x130%) = 86ACurrent Step = 33.05ASlew Rate = 2.5A/usWork frequency = 600 KHzEfficiency > 80% @TDCLL= NASVID Address = NA
CLOSE TO OUPUT DIFFERENTIAL PAIRTRACE WIDTH = 10MILTRACE SPACING = 5MIL
Rail B
Enable:Vth > 0.8V (High)
Enable:Vth > 0.8V (High)
Configuration ID :  0  ( 0R )
C4H
Renesas (7bit)
NI
316 OHM
62H
P0V8_PEX0/1 Infineon
115K
Address
Res (Down)
C4H
T I
C4H
Res (UP)
Renesas
NI 249K
13.3K
NI
316 OHM
P0V8_PEX2/3_controller(1/3)
Note: For MP2971 PR7170 POP
20220817 Design changePWRGD_P0V8_PEX2_R[118]PWR_EN_PEX_R[118,217,218,223,226,229,230,231,232,233]VSENSE_P0V8_PEX2_SKT_VSEN[43]VSENSE_P0V8_PEX2_SKT_VRTN[43]P0V8_PEX2_VREF[226,227,228]
P0V8_PEX2_PWM1 [227]P0V8_PEX2_ISEN1 [227]P0V8_PEX2_VREF [226,227,228]P0V8_PEX2_PWM2 [227]P0V8_PEX2_ISEN2 [227]
P0V8_PEX2_TSEN [227]P0V8_PEX3_TSEN [228]VSENSE_P0V8_PEX3_SKT_VSEN[56]VSENSE_P0V8_PEX3_SKT_VRTN[56]PWR_EN_PEX_R[118,217,218,223,226,229,230,231,232,233]PWRGD_P0V8_PEX3_R[118]
SMB_BIC_I2C6_MUX_VR_R_SCL[99,213,214,223]SMB_BIC_I2C6_MUX_VR_R_SDA[99,213,214,223]SMB_ALERT_PMBUS_R_N[88,223]P0V8_PEX3_PWM1 [228]P0V8_PEX3_ISEN1 [228]P0V8_PEX3_PWM2 [228]P0V8_PEX3_ISEN2 [228]P0V8_PEX2_VREF[226,227,228]P3V3_AUX
P3V3_AUX
P3V3_AUX
P12V_AUX
P0V8_PEX2
P3V3_AUX
P0V8_PEX3
P3V3_AUXP12V_AUXP5V_AUXP3V3_AUXSizeDoc NumberRevDate: SheetofReviewerDesignerDepartmentProject
Page TitleCCBU 11226 257Tuesday, August 29, 2023<project_name><Designer> GRANDTETON_SWB_20230829226 P0V8_PEX2/3_controller(1/3)<Reviewer>SizeDoc NumberRevDate: SheetofReviewerDesignerDepartmentProject
Page TitleCCBU 11226 257Tuesday, August 29, 2023<project_name><Designer> GRANDTETON_SWB_20230829226 P0V8_PEX2/3_controller(1/3)<Reviewer>SizeDoc NumberRevDate: SheetofReviewerDesignerDepartmentProject
Page TitleCCBU 11226 257Tuesday, August 29, 2023<project_name><Designer> GRANDTETON_SWB_20230829226 P0V8_PEX2/3_controller(1/3)<Reviewer>
PR12549.91%<Part Number>R0402-0201PR1241K1% R0402-0201<Part Number>PR1321K1%R0402-0201<Part Number>
C834 1000PFC0402-020150VX7R<Part Number>
NI
PR142 05%R0402-0201<Part Number>
NI
PR129 05%R0402-0201<Part Number>PJ8SHORTSHORT_R0603
NI
1122 PR7139 05%R0402-0201<Part Number>R83505% R0402-0201<Part Number>
R84005% R0402-0201<Part Number>C836 1000PFC0402-020150VX7R<Part Number>
PR717005%R0402-0201<Part Number>NIPC1293300PF50VC0402-0201<Part Number>X7RPC127 10UF25V10%C0805_H61 <Part Number>X6S
R83805% R0402-0201<Part Number>PR145 40.2K1% R0402-0201<Part Number>PR1413161%<Part Number>R0402-0201PR7137 05%R0402-0201<Part Number>PR140 249K<Part Number>R0402-02011%
NI
PJ24SHORT <Part Number>
NI1122PR13305%R0402-0201<Part Number>
C835 1000PFC0402-020150VX7R<Part Number>R83405% R0402-0201<Part Number>PR12749.91%<Part Number>R0402-0201PC1303300PF50VC0402-0201<Part Number>X7RPC128100NFX7R<Part Number>C0402-020150VPR7136 05%R0402-0201<Part Number>C837 1000PFC0402-020150VX7R<Part Number>NIPR7138 05%R0402-0201<Part Number>PR12849.91%<Part Number>R0402-0201PR1311K1%R0402-0201<Part Number>
NI
PR14605% R0402-0201<Part Number>
PJ22SHORT <Part Number>
NI1122 PU11
ISL69259IRAZ-T
CS723VCC39
EN120PMSCL10SVDATA18CS624nSVALERT19
nVRHOT14CS525CS426PG116
SVCLK17nPMALERT11EN013RGND022PMSDA9PWM45PWM56VSEN021PWM12
PG012PWM67VCCS40
VMON||IINSEN37VINSEN38TEMP136nPINALERT15VSEN132RGND131CS129PWM78PWM34CS327PWM23CS228CONFIG33TH_GNDTHADDRESS34TEMP035PWM01CS030PC133470PF50V5%C0402-0201<Part Number>NPOPJ23SHORT <Part Number>
NI1122 PR14405% R0402-0201<Part Number>
R837331% R0402-0201<Part Number>
PC135470PF50V5%C0402-0201<Part Number>NPOPC1340.1UFX7R25VC0402-0201<Part Number>
R8331K1%R0402-0201<Part Number>
PJ25SHORT <Part Number>
NI1122PR14310K1%R0402-0201<Part Number>PR13905% R0402-0201<Part Number>PR1471K1%R0402-0201<Part Number>
NI
PR126 05%R0402-0201<Part Number>PC124 100NFC0402-020150VX7R<Part Number>R5773331% R0402-0201<Part Number>R836 331% R0402-0201<Part Number>PR7142 4.99K1% R0402-0201WR04X4991FTR
NI
PC1360.1UFX7R25VC0402-0201<Part Number>PR13049.91%<Part Number>R0402-0201R8391K1%R0402-0201<Part Number>PR1341K1%R0402-0201<Part Number>
PC126 1UFC0402-020125VX6S<Part Number>PJ7SHORTSHORT_R0603
NI
1122PR714305%R0402-0201<Part Number>PR116 1<Part Number>R0402-02015%P0V8_PEX2_VDDP0V8_PEX2_VREFP0V8_PEX2_VSEN2SMB_VR_P0V8_PEX2_SCLP0V8_PEX2_VRHOT_R
FM_P0V8_PEX2_EN_R
P0V8_PEX2_VR_CONFIGP0V8_PEX2_PINALRTP0V8_PEX2_ADDRP0V8_PEX2_IINSENP0V8_PEX2_VINSEN
P0V8_PEX2_AVRRDY
P0V8_PEX3_TSEN_RP0V8_PEX2_TSEN_R
P0V8_PEX2_SMBALERTSMB_VR_P0V8_PEX2_SDANC_P0V8_PEX2_PWM4NC_P0V8_PEX2_ISEN4NC_P0V8_PEX2_PWM3NC_P0V8_PEX2_ISEN3P0V8_PEX3_VSEN3FM_P0V8_PEX3_EN_RP0V8_PEX3_BVRRDYSH_P0V8_PEX2_VSEN2_LSH_P0V8_PEX2_RGND2SH_P0V8_PEX3_VSEN3_LSH_P0V8_PEX3_RGND3SH_P0V8_PEX2_VSEN2_RSH_P0V8_PEX3_VSEN3_RNC_P0V8_PEX2_PWM6NC_P0V8_PEX2_ISEN6NC_P0V8_PEX2_PWM5NC_P0V8_PEX2_ISEN5P0V8_PEX2_SVIDNC_P0V8_PEX2_SVID_ALERT_N_R



5
5
4
4
3
3
2
2
1
1
D D
C C
B B
A A
P0V8_PEX2_Phase-1
6.3*7.7ESR=10mΩRI=5.08A
ESR=3mΩ7.3*4.3
SMD
ESR=3mΩ7.3*4.3
P0V8_PEX2_Phase-2
ISAT=52A @100CDCR=0.175MOHM9.6 x 6.4 x 12
ISAT=52A @100CDCR=0.175MOHM9.6 x 6.4 x 12
Isat=13A @100℃
ESR=3mΩ7.3*4.3ESR=3mΩ7.3*4.3
P0V8_PEX2_Phase(2/3)
Note: For MP87000 POP: PR7179, R6766, R6767NI: PR7180, PR7171, PR7172
20220817 Design changeP0V8_PEX2_TSEN[226,227]P0V8_PEX2_PWM1[226]P0V8_PEX2_ISEN1[226]P0V8_PEX2_VREF[226,227,228]P0V8_PEX2_TSEN[226,227]P0V8_PEX2_PWM2[226]P0V8_PEX2_ISEN2[226]P0V8_PEX2_VREF
SW_P12V_P0V8_PEX2_FLTP12V_AUX
P0V8_PEX2P0V8_PEX2_PVCCSW_P12V_P0V8_PEX2_FLTP0V8_PEX2
P3V3_AUXP5V_AUXP0V8_PEX2_PVCC
SizeDoc NumberRevDate: SheetofReviewerDesignerDepartmentProject
Page TitleCCBU 11227 257Tuesday, August 29, 2023<project_name><Designer> GRANDTETON_SWB_20230829227 P0V8_PEX2_Phase(2/3)<Reviewer>SizeDoc NumberRevDate: SheetofReviewerDesignerDepartmentProject
Page TitleCCBU 11227 257Tuesday, August 29, 2023<project_name><Designer> GRANDTETON_SWB_20230829227 P0V8_PEX2_Phase(2/3)<Reviewer>SizeDoc NumberRevDate: SheetofReviewerDesignerDepartmentProject
Page TitleCCBU 11227 257Tuesday, August 29, 2023<project_name><Designer> GRANDTETON_SWB_20230829227 P0V8_PEX2_Phase(2/3)<Reviewer>
PC661722UF16V<Part Number>C0805_H57X6SPC1460.22UFX7R25VC0402-0201<Part Number>PR1482.21/16W1%R0402-0201<Part Number>PC15922UF16V<Part Number>C0805_H57X6S+PC165470UF2V<Part Number>*LF_C_POSCAP12
PR717105%R0402-0201<Part Number>PC14122UF16V<Part Number>C0805_H57X6SPC16022UF16V<Part Number>C0805_H57X6SPC14822UFX6S4VC0805_H61<Part Number>  PC1571UFX6S25VC0402-0201<Part Number>PL13220NH<Part Number>PGL6216.221HLT61A21PR15511K1%R0402-0201<Part Number>
PL11100NH<Part Number>L_HCBS4545_4-5X4-516ADCR=0.12MOHM21PC14322UF16V<Part Number>C0805_H57X6S
PR15405% R0402-0201<Part Number>
PC14022UF16V<Part Number>C0805_H57X6SPC15022UFX6S4VC0805_H61<Part Number>  PC14222UF16V<Part Number>C0805_H57X6SPU12ISL99380FRZ-TR5935<Part Number>PWM34REFIN39VCC3AGND2BOOT33VIN25_29PHASE32PVCC4TOUT_FLT36IOUT38PGND7_9-20_24LSET37SW10_19PGND_15VIN130VOS1PGND_240EN35DNC31GL_16GL_241PC1530.1UFX7R25VC0402-0201<Part Number>PC14922UFX6S4VC0805_H61<Part Number>  PC16122UF16V<Part Number>C0805_H57X6SPC1630.1UF25VX7RC0402-0201<Part Number>PR15005% R0402-0201<Part Number>PC1380.1UFX7R25VC0402-0201<Part Number>PR717205%R0402-0201<Part Number>PC1552.2UF10VC0402-0201<Part Number>10%X7SPC16422UFX6S4VC0805_H61<Part Number>  PC1470.1UF25VX7RC0402-0201<Part Number>PC1660.1UFX7R25VC0402-0201<Part Number>
R67662K1%R0402-0201NI<Part Number>PC1452.2UF10VC0402-0201<Part Number>10%X7SPC15822UF16V<Part Number>C0805_H57X6SPC9840.1UFX7R25VC0402-0201<Part Number>PR718005%R0402-0201<Part Number>+PC152470UF2V<Part Number>*LF_C_POSCAP12R67672K1%R0402-0201NI<Part Number>PC1560.1UFX7R25VC0402-0201<Part Number>PR124991%R0603<Part Number>
+PC144270UF16V<Part Number>OSCON12
PC16822UFX6S4VC0805_H61<Part Number>  PC1620.22UFX7R25VC0402-0201<Part Number>
PR717905%R0402-0201<Part Number>NI
+PC169470UF2V<Part Number>*LF_C_POSCAP12
PC1391UFX6S25VC0402-0201<Part Number>PR15111K1%R0402-0201<Part Number>PC1542.2UF10VC0402-0201<Part Number>10%X7SPR149 3.31/16W1% R0402-0201<Part Number>PC661822UF16V<Part Number>C0805_H57X6SPR153 3.31/16W1%R0402-0201<Part Number>PC16722UFX6S4VC0805_H61<Part Number>  PC661622UF16V<Part Number>C0805_H57X6SPL12220NH<Part Number>PGL6216.221HLT61A21PC1372.2UF10VC0402-0201<Part Number>10%X7S+PC151470UF2V<Part Number>*LF_C_POSCAP12PR1522.21/16W1%R0402-0201<Part Number>PU13ISL99380FRZ-TR5935<Part Number>PWM34REFIN39VCC3AGND2BOOT33VIN25_29PHASE32PVCC4TOUT_FLT36IOUT38PGND7_9-20_24LSET37SW10_19PGND_15VIN130VOS1PGND_240EN35DNC31GL_16GL_241PC661522UF16V<Part Number>C0805_H57X6SSW_P0V8_PEX2_BOOT1SW_P0V8_PEX2_BOOT1_RSW_P0V8_PEX2_PHASE1SW_P0V8_PEX2_PH1SW_P0V8_PEX2_VOS1P0V8_PEX2_VCC1P0V8_PEX2_LSET1P0V8_PEX2_VCC2SW_P0V8_PEX2_BOOT2SW_P0V8_PEX2_BOOT2_RSW_P0V8_PEX2_PHASE2SW_P0V8_PEX2_PH2SW_P0V8_PEX2_VOS2P0V8_PEX2_LSET2NC_P0V8_PEX2_PH1_NC3NC_P0V8_PEX2_PH1_NC1NC_P0V8_PEX2_PH1_NC2NC_P0V8_PEX2_PH2_NC3NC_P0V8_PEX2_PH2_NC1NC_P0V8_PEX2_PH2_NC2
P0V8_PEX2_PVCCP0V8_PEX2_EN1P0V8_PEX2_EN2



5
5
4
4
3
3
2
2
1
1
D D
C C
B B
A A
P0V8_PEX3_Phase-1
ESR=3mΩ7.3*4.3 ESR=3mΩ7.3*4.3
P0V8_PEX3_Phase-2
ISAT=52A @100CDCR=0.175MOHM9.6 x 6.4 x 12
ISAT=52A @100CDCR=0.175MOHM9.6 x 6.4 x 12
Isat=13A @100℃
6.3*7.7ESR=10mΩRI=5.08ASMD
ESR=3mΩ7.3*4.3ESR=3mΩ7.3*4.3
P0V8_PEX3_Phase(3/3)
Note: For MP87000 POP: PR7181, R6768, R6769NI: PR7182, PR7173, PR7174
20220817 Design changeP0V8_PEX3_TSEN[226,228]P0V8_PEX3_PWM1[226]P0V8_PEX3_ISEN1[226]P0V8_PEX2_VREF[226,227,228]P0V8_PEX3_TSEN[226,228]P0V8_PEX3_PWM2[226]P0V8_PEX3_ISEN2[226]P0V8_PEX2_VREF[226,227,228]
SW_P12V_P0V8_PEX3_FLTP12V_AUX
P0V8_PEX3P0V8_PEX3_PVCCSW_P12V_P0V8_PEX3_FLTP0V8_PEX3
P3V3_AUXP5V_AUXP0V8_PEX3_PVCC
SizeDoc NumberRevDate: SheetofReviewerDesignerDepartmentProject
Page TitleCCBU 11228 257Tuesday, August 29, 2023<project_name><Designer> GRANDTETON_SWB_20230829228 P0V8_PEX3_Phase(3/3)<Reviewer>SizeDoc NumberRevDate: SheetofReviewerDesignerDepartmentProject
Page TitleCCBU 11228 257Tuesday, August 29, 2023<project_name><Designer> GRANDTETON_SWB_20230829228 P0V8_PEX3_Phase(3/3)<Reviewer>SizeDoc NumberRevDate: SheetofReviewerDesignerDepartmentProject
Page TitleCCBU 11228 257Tuesday, August 29, 2023<project_name><Designer> GRANDTETON_SWB_20230829228 P0V8_PEX3_Phase(3/3)<Reviewer>
PC17622UF16V<Part Number>C0805_H57X6SR67682K1%R0402-0201NI<Part Number>PR161 3.31/16W1%R0402-0201<Part Number>PR15805% R0402-0201<Part Number>PC18322UFX6S4VC0805_H61<Part Number>  PC1960.1UF25VX7RC0402-0201<Part Number>PR16205% R0402-0201<Part Number>PC19922UFX6S4VC0805_H61<Part Number>  
PR718205%R0402-0201<Part Number>PC1710.1UFX7R25VC0402-0201<Part Number>PL16220NH<Part Number>PGL6216.221HLT61A21PU14ISL99380FRZ-TR5935<Part Number>PWM34REFIN39VCC3AGND2BOOT33VIN25_29PHASE32PVCC4TOUT_FLT36IOUT38PGND7_9-20_24LSET37SW10_19PGND_15VIN130VOS1PGND_240EN35DNC31GL_16GL_241PC1891UFX6S25VC0402-0201<Part Number>PL14100NH<Part Number>L_HCBS4545_4-5X4-5DCR=0.12MOHM16A21PC18222UFX6S4VC0805_H61<Part Number>  PC17422UF16V<Part Number>C0805_H57X6SPC19122UF16V<Part Number>C0805_H57X6SPC1950.22UFX7R25VC0402-0201<Part Number>PU15ISL99380FRZ-TR5935<Part Number>PWM34REFIN39VCC3AGND2BOOT33VIN25_29PHASE32PVCC4TOUT_FLT36IOUT38PGND7_9-20_24LSET37SW10_19PGND_15VIN130VOS1PGND_240EN35DNC31GL_16GL_241
PC1721UFX6S25VC0402-0201<Part Number>PC1800.1UF25VX7RC0402-0201<Part Number>PR16311K1%R0402-0201<Part Number>PC18122UFX6S4VC0805_H61<Part Number>  PC1790.22UFX7R25VC0402-0201<Part Number>PC17322UF16V<Part Number>C0805_H57X6S
+PC201470UF2V<Part Number>*LF_C_POSCAP12PC1872.2UF10VC0402-0201<Part Number>10%X7SPC662122UF16V<Part Number>C0805_H57X6SPC662022UF16V<Part Number>C0805_H57X6S
PR718105%R0402-0201<Part Number>NIPR1562.21/16W1%R0402-0201<Part Number>PC19222UF16V<Part Number>C0805_H57X6SPC19822UFX6S4VC0805_H61<Part Number>  
PR157 3.31/16W1%R0402-0201<Part Number>PR15911K1%R0402-0201<Part Number>PR717405%R0402-0201<Part Number>PC19322UF16V<Part Number>C0805_H57X6S+PC177270UF16V<Part Number>OSCON12PC661922UF16V<Part Number>C0805_H57X6SPC2020.1UFX7R25VC0402-0201<Part Number>PC1880.1UFX7R25VC0402-0201<Part Number>+PC185470UF2V<Part Number>*LF_C_POSCAP12PR1602.21/16W1%R0402-0201<Part Number>+PC200470UF2V<Part Number>*LF_C_POSCAP12
PC9850.1UFX7R25VC0402-0201<Part Number>PR717305%R0402-0201<Part Number>PC1942.2UF10VC0402-0201<Part Number>10%X7SPC1782.2UF10VC0402-0201<Part Number>10%X7SPC662222UF16V<Part Number>C0805_H57X6SR67692K1%R0402-0201NI<Part Number>PL15220NH<Part Number>PGL6216.221HLT61A21PC19022UF16V<Part Number>C0805_H57X6SPC1702.2UF10VC0402-0201<Part Number>10%X7S
PR184991%R0603<Part Number>
+PC184470UF2V<Part Number>*LF_C_POSCAP12PC17522UF16V<Part Number>C0805_H57X6S
PC19722UFX6S4VC0805_H61<Part Number>  PC1860.1UFX7R25VC0402-0201<Part Number>SW_P0V8_PEX3_BOOT1SW_P0V8_PEX3_BOOT1_RSW_P0V8_PEX3_PHASE1SW_P0V8_PEX3_PH1SW_P0V8_PEX3_VOS1P0V8_PEX3_VCC1P0V8_PEX3_LSET1P0V8_PEX3_VCC2SW_P0V8_PEX3_BOOT2SW_P0V8_PEX3_BOOT2_RSW_P0V8_PEX3_PHASE2SW_P0V8_PEX3_PH2SW_P0V8_PEX3_VOS2P0V8_PEX3_LSET2NC_P0V8_PEX3_PH1_NC3NC_P0V8_PEX3_PH1_NC1NC_P0V8_PEX3_PH1_NC2NC_P0V8_PEX3_PH2_NC3NC_P0V8_PEX3_PH2_NC1NC_P0V8_PEX3_PH2_NC2
P0V8_PEX3_PVCCP0V8_PEX2_EN3P0V8_PEX2_EN4



5
5
4
4
3
3
2
2
1
1
D D
C C
B B
A A
P1V25_PEX0 Design specification
OUTPUT VOLTAGE = 1.25V +/-5%OUTPUT RIPPLE <= 20MVDC TOLERANCE <= 125MV (1.1875V~1.3125V)
TDC = 17AMAX CURRENT = 17AOCP (IMAX*125%)=22.7ACURRENT STEP = 8.5ASLEW RATE = 2.5A/USWork frequency = 600KHZEfficiency > 85% @TDC
Rb
Ra
Vo=0.6(1+Ra/Rb) = 1.25V
Enable:Vth > 1.27V (High)
FCCM
Isat=5A @100℃
place short close to load
DIFFERENTIAL PAIRTRACE WIDTH = 10MILTRACE SPACING = 5MIL
P1V25_PEX0
20220817 Design changePWRGD_P1V25_PEX0_R [118]PWR_EN_PEX_R[118,217,218,223,226,230,231,232,233]P12V_AUXP1V25_PEX0_RP1V25_PEX0_VCCP1V25_PEX0P1V25_PEX0_R
SizeDoc NumberRevDate: SheetofReviewerDesignerDepartmentProject
Page TitleCCBU 11229 257Tuesday, August 29, 2023<project_name><Designer> GRANDTETON_SWB_20230829229 P1V25_PEX0<Reviewer>SizeDoc NumberRevDate: SheetofReviewerDesignerDepartmentProject
Page TitleCCBU 11229 257Tuesday, August 29, 2023<project_name><Designer> GRANDTETON_SWB_20230829229 P1V25_PEX0<Reviewer>SizeDoc NumberRevDate: SheetofReviewerDesignerDepartmentProject
Page TitleCCBU 11229 257Tuesday, August 29, 2023<project_name><Designer> GRANDTETON_SWB_20230829229 P1V25_PEX0<Reviewer>
PL17BLM18SN220TN1D<Part Number>8000MADCR=0.12MOHM21 PR16812K1%R0402-0201<Part Number>PC98722UFC0805_H614VX6S<Part Number>
NI
PC9780.1UFX7R25VC0402-0201<Part Number>R84110KR0402-02011%<Part Number>PC98622UFC0805_H614VX6S<Part Number>
NI
PC2220.1UFX7R25VC0402-0201<Part Number>R842 0<Part Number>5%R0402-02011/16WPC98922UFC0805_H614VX6S<Part Number>
NI
PC2030.1UFX7R25VC0402-0201<Part Number>PC219 330PFC0402-020150VX7R<Part Number>PR1676.04K<Part Number>R0402-02011%PC20422UFX6S16VC0805_H57<Part Number>PR166 13K1% R0402-0201<Part Number>PL180.33UH<Part Number>65ADCR=10.8MOHMMMD-12FD-R33M-V1Q21+PC217390UF<Part Number>20%2.5VALUM12PC2201UFX6S25VC0402-0201<Part Number>+PC218390UF<Part Number>20%2.5VALUM12PJ10SHORT<Part Number>NI1122PC20622UFX6S16VC0805_H57<Part Number>PC2210.022UFX7R25VC0402-0201<Part Number>PC21322UFC0805_H614VX6S<Part Number>PC98822UFC0805_H614VX6S<Part Number>
NI
PC2160.1UFX7R25VC0402-0201<Part Number>PC211 0.1UFC0402-020125VX7R<Part Number>10%PC21222UFC0805_H614VX6S<Part Number>R4435 0<Part Number>5%R0402-02011/16WPC21522UFC0805_H614VX6S<Part Number>PC20722UFX6S16VC0805_H57<Part Number>PC100722UFX6S16VC0805_H57<Part Number>PC20922UFX6S16VC0805_H57<Part Number>PU16RS53319LR<Part Number>VIN110PGOOD9PGND11_18EN8BST1FB7AGND2VCC19RTN6SW20REF5MODE4CS3VIN221PC20522UFX6S16VC0805_H57<Part Number>PC20822UFX6S16VC0805_H57<Part Number>PJ9SHORT<Part Number>NI1122PC21422UFC0805_H614VX6S<Part Number>PC2101UFX6S25VC0402-0201<Part Number>SW_P12V_P1V25_PEX0_FLTPWRGD_P1V25_PEX0SW_P1V25_PEX0_BTSW_P1V25_PEX0_PHP1V25_PEX0_VCCP1V25_PEX0_FBP1V25_PEX0_REFP1V25_PEX0_CSSH_P1V25_PEX0_FB_PP1V25_PEX0SH_P1V25_PEX0_FB_NPWRGD_P1V25_PEX0_RP1V25_PEX0_ENPWR_PAX_EN_R



5
5
4
4
3
3
2
2
1
1
D D
C C
B B
A A
Ra
Vo=0.6(1+Ra/Rb) = 1.25V
Isat=5A @100℃
Enable:Vth > 1.27V (High)
Rb
P1V25_PEX1 Design specification
FCCM
OUTPUT VOLTAGE = 1.25V +/-5%OUTPUT RIPPLE <= 20MVDC TOLERANCE <= 125MV (1.1875V~1.3125V)
TDC = 17AMAX CURRENT = 17AOCP (IMAX*125%)=22.7ACURRENT STEP = 8.5ASLEW RATE = 2.5A/USWork frequency = 600KHZEfficiency > 85% @TDC
place short close to load
DIFFERENTIAL PAIRTRACE WIDTH = 10MILTRACE SPACING = 5MIL
P1V25_PEX1
20220817 Design changePWRGD_P1V25_PEX1_R [118]PWR_EN_PEX_R[118,217,218,223,226,229,231,232,233]P1V25_PEX1_VCCP12V_AUXP1V25_PEX1_RP1V25_PEX1P1V25_PEX1_R
SizeDoc NumberRevDate: SheetofReviewerDesignerDepartmentProject
Page TitleCCBU 11230 257Tuesday, August 29, 2023<project_name><Designer> GRANDTETON_SWB_20230829230 P1V25_PEX1<Reviewer>SizeDoc NumberRevDate: SheetofReviewerDesignerDepartmentProject
Page TitleCCBU 11230 257Tuesday, August 29, 2023<project_name><Designer> GRANDTETON_SWB_20230829230 P1V25_PEX1<Reviewer>SizeDoc NumberRevDate: SheetofReviewerDesignerDepartmentProject
Page TitleCCBU 11230 257Tuesday, August 29, 2023<project_name><Designer> GRANDTETON_SWB_20230829230 P1V25_PEX1<Reviewer>
PC2301UFX6S25VC0402-0201<Part Number>+PC238390UF<Part Number>20%2.5VALUM12PC231 0.1UFC0402-020125VX7R<Part Number>10%PC99022UFC0805_H614VX6S<Part Number>
NI
PC22422UFX6S16VC0805_H57<Part Number>R4436 0<Part Number>5%R0402-02011/16WPC2420.1UFX7R25VC0402-0201<Part Number>PC22622UFX6S16VC0805_H57<Part Number>PC100822UFX6S16VC0805_H57<Part Number>PU17RS53319LR<Part Number>VIN110PGOOD9PGND11_18EN8BST1FB7AGND2VCC19RTN6SW20REF5MODE4CS3VIN221PC9790.1UFX7R25VC0402-0201<Part Number>R84310KR0402-02011%<Part Number>PJ12SHORT<Part Number>NI1122PC2230.1UFX7R25VC0402-0201<Part Number>PC99122UFC0805_H614VX6S<Part Number>
NI
PC23522UFC0805_H614VX6S<Part Number>PC23422UFC0805_H614VX6S<Part Number>PC22922UFX6S16VC0805_H57<Part Number>PL200.33UH<Part Number>65ADCR=10.8MOHMMMD-12FD-R33M-V1Q21PC22522UFX6S16VC0805_H57<Part Number>PC22722UFX6S16VC0805_H57<Part Number>PL19BLM18SN220TN1D<Part Number>8000MADCR=0.12MOHM21 PC240 330PFC0402-020150VX7R<Part Number>PC2371UFX6S25VC0402-0201<Part Number>+PC239390UF<Part Number>20%2.5VALUM12PR171 13K1% R0402-0201<Part Number>PC2360.1UFX7R25VC0402-0201<Part Number>PC22822UFX6S16VC0805_H57<Part Number>PC99222UFC0805_H614VX6S<Part Number>
NI
PC99322UFC0805_H614VX6S<Part Number>
NI
PC2410.022UFX7R25VC0402-0201<Part Number>PR17312K1%R0402-0201<Part Number>PJ11SHORT<Part Number>NI1122PR1726.04K<Part Number>R0402-02011%R844 0<Part Number>5%R0402-02011/16WPC23322UFC0805_H614VX6S<Part Number>PC23222UFC0805_H614VX6S<Part Number>SW_P12V_P1V25_PEX1_FLTPWRGD_P1V25_PEX1SW_P1V25_PEX1_BTSW_P1V25_PEX1_PHP1V25_PEX1_VCCP1V25_PEX1_FBSH_P1V25_PEX1_FB_PP1V25_PEX1P1V25_PEX1_REFP1V25_PEX1_CSSH_P1V25_PEX1_FB_NPWRGD_P1V25_PEX1_RP1V25_PEX1_ENPWR_PAX_EN_R



5
5
4
4
3
3
2
2
1
1
D D
C C
B B
A A
P1V25_PEX2 Design specification
OUTPUT VOLTAGE = 1.25V +/-5%OUTPUT RIPPLE <= 20MVDC TOLERANCE <= 125MV (1.1875V~1.3125V)
TDC = 17AMAX CURRENT = 17AOCP (IMAX*125%)=22.7ACURRENT STEP = 8.5ASLEW RATE = 2.5A/USWork frequency = 600KHZEfficiency > 85% @TDC
Ra
Vo=0.6(1+Ra/Rb) = 1.25V
Isat=5A @100℃
Enable:Vth > 1.27V (High)
Rb
FCCM
place short close to load
DIFFERENTIAL PAIRTRACE WIDTH = 10MILTRACE SPACING = 5MIL
P1V25_PEX2
20220817 Design changePWRGD_P1V25_PEX2_R [118]PWR_EN_PEX_R[118,217,218,223,226,229,230,232,233]P1V25_PEX2_VCCP12V_AUXP1V25_PEX2_RP1V25_PEX2P1V25_PEX2_R
SizeDoc NumberRevDate: SheetofReviewerDesignerDepartmentProject
Page TitleCCBU 11231 257Tuesday, August 29, 2023<project_name><Designer> GRANDTETON_SWB_20230829231 P1V25_PEX2<Reviewer>SizeDoc NumberRevDate: SheetofReviewerDesignerDepartmentProject
Page TitleCCBU 11231 257Tuesday, August 29, 2023<project_name><Designer> GRANDTETON_SWB_20230829231 P1V25_PEX2<Reviewer>SizeDoc NumberRevDate: SheetofReviewerDesignerDepartmentProject
Page TitleCCBU 11231 257Tuesday, August 29, 2023<project_name><Designer> GRANDTETON_SWB_20230829231 P1V25_PEX2<Reviewer>
PL220.33UH<Part Number>65ADCR=10.8MOHMMMD-12FD-R33M-V1Q21PR176 13K1% R0402-0201<Part Number>PR17812K1%R0402-0201<Part Number>PC251 0.1UFC0402-020125VX7R<Part Number>10%PC24422UFX6S16VC0805_H57<Part Number>PC100922UFX6S16VC0805_H57<Part Number>PC24722UFX6S16VC0805_H57<Part Number>PJ14SHORT<Part Number>NI1122+PC259390UF<Part Number>20%2.5VALUM12PC99522UFC0805_H614VX6S<Part Number>
NI
PC2620.1UFX7R25VC0402-0201<Part Number>PC2481UFX6S25VC0402-0201<Part Number>PC2571UFX6S25VC0402-0201<Part Number>PC99622UFC0805_H614VX6S<Part Number>
NI
PC25022UFX6S16VC0805_H57<Part Number>PC260 330PFC0402-020150VX7R<Part Number>PC99422UFC0805_H614VX6S<Part Number>
NI
PL21BLM18SN220TN1D<Part Number>8000MADCR=0.12MOHM21 PC2560.1UFX7R25VC0402-0201<Part Number>PC2430.1UFX7R25VC0402-0201<Part Number>PC24622UFX6S16VC0805_H57<Part Number>PC99722UFC0805_H614VX6S<Part Number>
NI
PC25522UFC0805_H614VX6S<Part Number>PC25322UFC0805_H614VX6S<Part Number>+PC258390UF<Part Number>20%2.5VALUM12PR1776.04K<Part Number>R0402-02011%PU18RS53319LR<Part Number>VIN110PGOOD9PGND11_18EN8BST1FB7AGND2VCC19RTN6SW20REF5MODE4CS3VIN221PC25422UFC0805_H614VX6S<Part Number>PC2610.022UFX7R25VC0402-0201<Part Number>PC9800.1UFX7R25VC0402-0201<Part Number>PC25222UFC0805_H614VX6S<Part Number>PC24522UFX6S16VC0805_H57<Part Number>R846 0<Part Number>5%R0402-02011/16WPJ13SHORT<Part Number>NI1122PC24922UFX6S16VC0805_H57<Part Number>R4437 0<Part Number>5%R0402-02011/16WR84510KR0402-02011%<Part Number>SW_P12V_P1V25_PEX2_FLTPWRGD_P1V25_PEX2SW_P1V25_PEX2_BTSW_P1V25_PEX2_PHP1V25_PEX2_VCCP1V25_PEX2_FBSH_P1V25_PEX2_FB_PP1V25_PEX2P1V25_PEX2_REFP1V25_PEX2_CSSH_P1V25_PEX2_FB_NPWRGD_P1V25_PEX2_RP1V25_PEX2_ENPWR_PAX_EN_R



5
5
4
4
3
3
2
2
1
1
D D
C C
B B
A A
P1V25_PEX3 Design specification
OUTPUT VOLTAGE = 1.25V +/-5%OUTPUT RIPPLE <= 20MVDC TOLERANCE <= 125MV (1.1875V~1.3125V)
TDC = 17AMAX CURRENT = 17AOCP (IMAX*125%)=22.7ACURRENT STEP = 8.5ASLEW RATE = 2.5A/USWork frequency = 600KHZEfficiency > 85% @TDC
Ra
Vo=0.6(1+Ra/Rb) = 1.25V
Isat=5A @100℃
Enable:Vth > 1.27V (High)
Rb
FCCM
place short close to load
DIFFERENTIAL PAIRTRACE WIDTH = 10MILTRACE SPACING = 5MIL
P1V25_PEX3
20220817 Design changePWRGD_P1V25_PEX3_R [118]PWR_EN_PEX_R[118,217,218,223,226,229,230,231,233]P1V25_PEX3_VCCP12V_AUXP1V25_PEX3_RP1V25_PEX3P1V25_PEX3_R
SizeDoc NumberRevDate: SheetofReviewerDesignerDepartmentProject
Page TitleCCBU 11232 257Tuesday, August 29, 2023<project_name><Designer> GRANDTETON_SWB_20230829232 P1V25_PEX3<Reviewer>SizeDoc NumberRevDate: SheetofReviewerDesignerDepartmentProject
Page TitleCCBU 11232 257Tuesday, August 29, 2023<project_name><Designer> GRANDTETON_SWB_20230829232 P1V25_PEX3<Reviewer>SizeDoc NumberRevDate: SheetofReviewerDesignerDepartmentProject
Page TitleCCBU 11232 257Tuesday, August 29, 2023<project_name><Designer> GRANDTETON_SWB_20230829232 P1V25_PEX3<Reviewer>
PC26622UFX6S16VC0805_H57<Part Number>PC9810.1UFX7R25VC0402-0201<Part Number>PR18312K1%R0402-0201<Part Number>PC26522UFX6S16VC0805_H57<Part Number>PU19RS53319LR<Part Number>VIN110PGOOD9PGND11_18EN8BST1FB7AGND2VCC19RTN6SW20REF5MODE4CS3VIN221PC26322UFX6S16VC0805_H57<Part Number>PC27422UFC0805_H614VX6S<Part Number>PC2760.1UFX7R25VC0402-0201<Part Number>+PC278390UF<Part Number>20%2.5VALUM12PL240.33UH<Part Number>65ADCR=10.8MOHMMMD-12FD-R33M-V1Q21PJ16SHORT<Part Number>NI1122PC2810.022UFX7R25VC0402-0201<Part Number>PR181 13K1% R0402-0201<Part Number>PC280 330PFC0402-020150VX7R<Part Number>+PC279390UF<Part Number>20%2.5VALUM12R84710KR0402-02011%<Part Number>PC27322UFC0805_H614VX6S<Part Number>R848 0<Part Number>5%R0402-02011/16WPC99822UFC0805_H614VX6S<Part Number>
NI
PC26722UFX6S16VC0805_H57<Part Number>PC100122UFC0805_H614VX6S<Part Number>
NI
PC2820.1UFX7R25VC0402-0201<Part Number>PC100022UFC0805_H614VX6S<Part Number>
NI
PC101022UFX6S16VC0805_H57<Part Number>PC26922UFX6S16VC0805_H57<Part Number>PR1826.04K<Part Number>R0402-02011%PC99922UFC0805_H614VX6S<Part Number>
NI
PC2640.1UFX7R25VC0402-0201<Part Number>PC2771UFX6S25VC0402-0201<Part Number>PJ15SHORT<Part Number>NI1122PL23BLM18SN220TN1D<Part Number>8000MADCR=0.12MOHM21 PC27522UFC0805_H614VX6S<Part Number>PC2701UFX6S25VC0402-0201<Part Number>PC26822UFX6S16VC0805_H57<Part Number>PC27222UFC0805_H614VX6S<Part Number>R4438 0<Part Number>5%R0402-02011/16WPC271 0.1UFC0402-020125VX7R<Part Number>10%SW_P12V_P1V25_PEX3_FLTPWRGD_P1V25_PEX3SW_P1V25_PEX3_BTSW_P1V25_PEX3_PHP1V25_PEX3_VCCP1V25_PEX3_FBSH_P1V25_PEX3_FB_PP1V25_PEX3P1V25_PEX3_REFP1V25_PEX3_CSSH_P1V25_PEX3_FB_NPWRGD_P1V25_PEX3_RP1V25_PEX3_ENPWR_PAX_EN_R



5
5
4
4
3
3
2
2
1
1
D D
C C
B B
A A
Ra
Vo=0.6(1+Ra/Rb) = 1.8V
Enable:Vth > 1.27V (High)
FCCM
Rb
OUTPUT VOLTAGE = 1.8V +/-5%OUTPUT RIPPLE <= 36MVDC TOLERANCE <= 180MV (1.71V~1.89V)
TDC = 4.88AMAX CURRENT = 4.88AOCP (IMAX * 130%) = 6.3ACURRENT STEP = 2.44ASLEW RATE = 2.5A/USWork frequency = 600KHZEfficiency > 85% @TDC
P1V8_PEX Design specification
P1V8_PEX_VCC is 3V
P1V8_PEX_RS53318LR
PWRGD_P1V8_PEX_R [16,29,42,55,95,118]PWR_EN_PEX_R[118,217,218,223,226,229,230,231,232]P12V_AUXP1V8_PEX_VCCP1V8_PEX_RP3V3_AUXP1V8_PEX_R
SizeDoc NumberRevDate: SheetofReviewerDesignerDepartmentProject
Page TitleCCBU 11233 257Tuesday, August 29, 2023<project_name><Designer> GRANDTETON_SWB_20230829233 P1V8_PEX_MPQ8633AGLE-C807-Z<Reviewer>SizeDoc NumberRevDate: SheetofReviewerDesignerDepartmentProject
Page TitleCCBU 11233 257Tuesday, August 29, 2023<project_name><Designer> GRANDTETON_SWB_20230829233 P1V8_PEX_MPQ8633AGLE-C807-Z<Reviewer>SizeDoc NumberRevDate: SheetofReviewerDesignerDepartmentProject
Page TitleCCBU 11233 257Tuesday, August 29, 2023<project_name><Designer> GRANDTETON_SWB_20230829233 P1V8_PEX_MPQ8633AGLE-C807-Z<Reviewer>
PC289 0.1UFC0402-020125VX7R<Part Number>10%PR18710.7K<Part Number>R0402-02011%PC29122UFX6S<Part Number>C0805_H614VPJ17SHORT
NI
1122PC2951UFX6S25VC0402-0201<Part Number>PR18812K1%R0402-0201<Part Number>PC28622UFX6S16VC0805_H57<Part Number>R85010KR0402-02015%<Part Number>NI PC29322UFX6S<Part Number>C0805_H614VC8381000PFX7R50VC0402-0201<Part Number>R4439 0<Part Number>5%R0402-02011/16WPC100222UFC0805_H614VX6S<Part Number>
NI
PC2900.1UFX7R<Part Number>C0402-020125VPC100522UFC0805_H614VX6S<Part Number>
NI
PC28722UFX6S16VC0805_H57<Part Number>PC2960.1UFX7R25VC0402-0201<Part Number>PR186 24K1% R0402-0201<Part Number>PC2881UFX6S25VC0402-0201<Part Number>PL25BLM18SN220TN1D<Part Number>8000MA L060321 PC100422UFC0805_H614VX6S<Part Number>
NI
PC28522UFX6S16VC0805_H57<Part Number>R851 05% R0402-0201<Part Number>PL262.2UHPCMC063T-2R2MN<Part Number>8A21PU20RS53318LR<Part Number>VIN110PGOOD9PGND11_18EN8BST1FB7AGND2VCC19RTN6SW20REF5MODE4CS3VIN221PC29222UFX6S<Part Number>C0805_H614VPC2830.1UFX7R25VC0402-0201<Part Number>PC100322UFC0805_H614VX6S<Part Number>
NI
R84910KR0402-02011%<Part Number>PC29422UFX6S<Part Number>C0805_H614V+PC1006470UF2.5V<Part Number>*LF_SP_CAP12PC28422UFX6S16VC0805_H57<Part Number>PC297 150PFC0402-020150VNPO<Part Number>SW_P12V_P1V8_PEX_FLTPWRGD_P1V8_PEXSW_P1V8_PEX_BTSW_P1V8_PEX_PHP1V8_PEX_VCCP1V8_PEX_FBP1V8_PEX_REFSH_P1V8_PEX_FBP1V8_PEX_CSPWRGD_P1V8_PEX_RP1V8_PEX_EN



5
5
4
4
3
3
2
2
1
1
D D
C C
B B
A A
Enable:Vth > 2V (High)
Soft-Start timeTSS=3.33ms
P3V3 E-fuse
Iout_max=1.449ACurrent limit=2ASoft-Start time=3.33msEnable Vth > 2V (High)
Design specification
P3V3_SQ24801BDCD
20220817 Design change20220817 Design changePWR_EN_P3V3_R[118,241]PWRGD_P3V3_R [118,241]P3V3_AUXP3V3P5V_AUXP3V3P3V3_AUX
SizeDoc NumberRevDate: SheetofReviewerDesignerDepartmentProject
Page TitleCCBU 11234 257Tuesday, August 29, 2023<project_name><Designer> GRANDTETON_SWB_20230829234 P3V3_NCP45750IMN24TWG<Reviewer>SizeDoc NumberRevDate: SheetofReviewerDesignerDepartmentProject
Page TitleCCBU 11234 257Tuesday, August 29, 2023<project_name><Designer> GRANDTETON_SWB_20230829234 P3V3_NCP45750IMN24TWG<Reviewer>SizeDoc NumberRevDate: SheetofReviewerDesignerDepartmentProject
Page TitleCCBU 11234 257Tuesday, August 29, 2023<project_name><Designer> GRANDTETON_SWB_20230829234 P3V3_NCP45750IMN24TWG<Reviewer>
PU21SQ24801BDCD
NI
VIN113VCC10OCP9PG8NC11VOUT12VOUT23VOUT34NC25EN11SR7VSS6VIN212PC3020.1UFX7RC0402-020125V<Part Number>
NI
C28520.1UF25V 10%C0402-0201X7R
NI
<Part Number>PC29910UFX6S16V 10%<Part Number>C0805_H57
NI
PR190309K1%R0402-0201<Part Number>
NI
PC30110UFX6S16VC0805_H57<Part Number>
NI
R4440 05%1/16WR0402-0201
NI
R852100K<Part Number>R0402-02011%
NI
R277410KR0402-02015%<Part Number>
NI
PD3B340A-13-F<Part Number>
NI
ACPC3000.1UF25VC0402-0201<Part Number>X7R
NI
PC2980.1UF25VC0402-0201<Part Number>X7R10%
NI
PC3030.1UFX7R25VC0402-0201<Part Number>
NI
P3V3_OCPPWRGD_P3V3P3V3_SSPWRGD_P3V3_RPWR_EN_P3V3_R



5
5
4
4
3
3
2
2
1
1
D D
C C
B B
A A
Soft-Start timeTSS=630us
Enable:Vth > 2V (High)
Enable:Vth > 2V (High)
Soft-Start timeTSS=630us
Enable:Vth > 2V (High)
Soft-Start timeTSS=630us
Enable:Vth > 2V (High)
Soft-Start timeTSS=630us
Soft-Start timeTSS=630us
Enable:Vth > 2V (High)
Enable:Vth > 2V (High)
Soft-Start timeTSS=630us
Enable:Vth > 2V (High)
Soft-Start timeTSS=630us
Soft-Start timeTSS=630us
Enable:Vth > 2V (High)
Design specification
P12V_NIC E-fuseIout_max=6.6ACurrent limit=8.8ASoft-Start time=2.77msEnable Vth > 2V (High)
P12V_NIC_SQ24801BDCD
Design change 20220707Design change 20220707Design change 20220707Design change 20220707Design change 20220707Design change 20220707Design change 20220707Design change 20220707
20220802 Fine tune OCP20220802 Fine tune OCP20220802 Fine tune OCP 20220802 Fine tune OCP20220802 Fine tune OCP20220802 Fine tune OCP20220802 Fine tune OCP 20220802 Fine tune OCP
HP_NIC0_EN[170,238,242,248]HP_NIC4_EN[182,238,243,249]HP_NIC1_EN[173,238,242,248]HP_NIC5_EN[185,238,243,249]HP_NIC2_EN[176,238,242,248]HP_NIC6_EN[188,238,243,249]HP_NIC3_EN[179,238,242,248]HP_NIC7_EN[191,238,243,249]
PWRGD_P12V_NIC0_R [116,170,242]PWRGD_P12V_NIC1_R [116,173,242]PWRGD_P12V_NIC2_R [116,176,242]PWRGD_P12V_NIC3_R [116,179,242]
PWRGD_P12V_NIC4_R [116,182,243]PWRGD_P12V_NIC5_R [116,185,243]PWRGD_P12V_NIC6_R [116,188,243]PWRGD_P12V_NIC7_R [116,191,243]
P3V3_AUXP12V_NIC0_RP5V_AUXP12V_NIC1_RP5V_AUXP12V_NIC2_RP5V_AUXP12V_NIC3_RP5V_AUX
P12V_NIC4_RP5V_AUXP12V_NIC5_RP5V_AUXP12V_NIC6_RP5V_AUXP12V_NIC7_RP5V_AUX
P12V_AUXP3V3_AUXP12V_AUXP12V_AUXP3V3_AUXP12V_AUXP3V3_AUXP12V_AUXP3V3_AUXP12V_AUXP3V3_AUXP12V_AUXP3V3_AUXP12V_AUXP3V3_AUX
SizeDoc NumberRevDate: SheetofReviewerDesignerDepartmentProject
Page TitleCCBU 11235 257Tuesday, August 29, 2023<project_name><Designer> GRANDTETON_SWB_20230829235 P12V_NIC_NCP45750IMN24TWG<Reviewer>SizeDoc NumberRevDate: SheetofReviewerDesignerDepartmentProject
Page TitleCCBU 11235 257Tuesday, August 29, 2023<project_name><Designer> GRANDTETON_SWB_20230829235 P12V_NIC_NCP45750IMN24TWG<Reviewer>SizeDoc NumberRevDate: SheetofReviewerDesignerDepartmentProject
Page TitleCCBU 11235 257Tuesday, August 29, 2023<project_name><Designer> GRANDTETON_SWB_20230829235 P12V_NIC_NCP45750IMN24TWG<Reviewer>PC62610UFX6S25VC0805_H61<Part Number>
NI
PC3250.1UFX7RC0402-020125V<Part Number>
NI
PU28SQ24801BDCD
NI
VIN113VCC10OCP9PG8NC11VOUT12VOUT23VOUT34NC25EN11SR7VSS6VIN212R4450 05%1/16WR0402-0201
NI
PC31010UFX6S25VC0805_H61<Part Number>
NI
C28580.1UF25V 10%C0402-0201X7R
NI
<Part Number>
R853100K<Part Number>R0402-02011%
NI
R4449 05%1/16WR0402-0201
NI
R860100K<Part Number>R0402-02011%
NI
PC3441UF25VC0402-0201<Part Number>X6S
NI
PC3420.1UF25VC0402-0201<Part Number>X7R10%
NI
C28550.1UF25V 10%C0402-0201X7R
NI
<Part Number>PR19810.2K1%R0402-0201<Part Number>
NI
PC3201UF25VC0402-0201<Part Number>X6S
NI
PU29SQ24801BDCD
NI
VIN113VCC10OCP9PG8NC11VOUT12VOUT23VOUT34NC25EN11SR7VSS6VIN212PC82510UFX6S25VC0805_H61<Part Number>
NI
R859100K<Part Number>R0402-02011%
NI
PU23SQ24801BDCD
NI
VIN113VCC10OCP9PG8NC11VOUT12VOUT23VOUT34NC25EN11SR7VSS6VIN212
C28590.1UF25V 10%C0402-0201X7R
NI
<Part Number>PR20110.2K1%R0402-0201<Part Number>
NI
PC30510UFX6S25V 10%<Part Number>C0805_H61
NI
PC3221UF25VC0402-0201<Part Number>X6S
NI
R857100K<Part Number>R0402-02011%
NI
PD19B340A-13-F<Part Number>
NI
ACR4453 05%1/16WR0402-0201
NI
R858100K<Part Number>R0402-02011%
NI
PC34310UFX6S25V 10%<Part Number>C0805_H61
NI
PR19310.2K1%R0402-0201<Part Number>NI
PC33110UFX6S25V 10%<Part Number>C0805_H61
NI
PD92SMBJ14A<Part Number>
NIAC
PC33310UFX6S25VC0805_H61<Part Number>
NI
PC34110UFX6S25V 10%<Part Number>C0805_H61
NI
PC3143300PFX7R50VC0402-0201<Part Number>NI
PC3400.1UF25VC0402-0201<Part Number>X7R10%
NI
C28600.1UF25V 10%C0402-0201X7R
NI
<Part Number>PU27SQ24801BDCD
NI
VIN113VCC10OCP9PG8NC11VOUT12VOUT23VOUT34NC25EN11SR7VSS6VIN212PC3383300PFX7R50VC0402<Part Number>NIPC3321UF25VC0402-0201<Part Number>X6S
NI
PC3263300PFX7R50VC0402<Part Number>NIPU25SQ24801BDCD
NI
VIN113VCC10OCP9PG8NC11VOUT12VOUT23VOUT34NC25EN11SR7VSS6VIN212PC35310UFX6S25V 10%<Part Number>C0805_H61
NI
R4452 05%1/16WR0402-0201
NI
PR20610.2K1%R0402-0201<Part Number>
NI
R4451 05%1/16WR0402-0201
NI
R4456 05%1/16WR0402-0201
NI
PC3360.1UFX7RC0402-020125V<Part Number>
NI
PR20510.2K1%R0402-0201<Part Number>
NI
PC3060.1UF25VC0402-0201<Part Number>X7R10%
NI
PD79B340A-13-F<Part Number>
NI
ACPC3040.1UF25VC0402-0201<Part Number>X7R10%
NI
PD98B340A-13-F<Part Number>
NI
ACPD13SMBJ14A<Part Number>
NIACR4455 05%1/16WR0402-0201
NI
PC3240.1UFX7RC0402-020125V<Part Number>
NI
PC3091UF25VC0402-0201<Part Number>X6S
NI
PC3081UF25VC0402-0201<Part Number>X6S
NI
C28540.1UF25V 10%C0402-0201X7R
NI
<Part Number>R4446 05%1/16WR0402-0201
NI
PC3490.1UFX7RC0402-020125V<Part Number>
NI
R4443 05%1/16WR0402-0201
NI
PC3153300PFX7R50VC0402<Part Number>NIR854100K<Part Number>R0402-02011%
NI
PC3300.1UF25VC0402-0201<Part Number>X7R10%
NI
PC32110UFX6S25VC0805_H61<Part Number>
NI
PD14B340A-13-F<Part Number>
NI
AC PC80610UFX6S25VC0805_H61<Part Number>
NI
PC3520.1UF25VC0402-0201<Part Number>X7R10%
NI
PD9SMBJ14A<Part Number>
NIACR855100K<Part Number>R0402-02011%
NI
PC81910UFX6S25VC0805_H61<Part Number>
NI
PC32910UFX6S25V 10%<Part Number>C0805_H61
NI
PD6B340A-13-F<Part Number>
NI
AC
PC3461UF25VC0402-0201<Part Number>X6S
NI
PC3480.1UFX7RC0402-020125V<Part Number>
NI
PD4SMBJ14A<Part Number>
NIAC PC3180.1UF25VC0402-0201<Part Number>X7R10%
NI
PR19410.2K1%R0402-0201<Part Number>
NI
PD83B340A-13-F<Part Number>
NI
ACPC3503300PFX7R50VC0402<Part Number>NIPC3513300PFX7R50VC0402<Part Number>NI
PC31110UFX6S25VC0805_H61<Part Number>
NI
PC30710UFX6S25V 10%<Part Number>C0805_H61
NI
PC3280.1UF25VC0402-0201<Part Number>X7R10%
NI
R856100K<Part Number>R0402-02011%
NI
C28560.1UF25V 10%C0402-0201X7R
NI
<Part Number>C28530.1UF25V 10%C0402-0201X7R
NI
<Part Number>PU26SQ24801BDCD
NI
VIN113VCC10OCP9PG8NC11VOUT12VOUT23VOUT34NC25EN11SR7VSS6VIN212PC3370.1UFX7RC0402-020125V<Part Number>
NI
PC3341UF25VC0402-0201<Part Number>X6S
NI
R4442 05%1/16WR0402-0201
NI
PC3273300PFX7R50VC0402-0201<Part Number>NIPC3393300PFX7R50VC0402<Part Number>NIPR19710.2K1%R0402-0201<Part Number>
NI
R4444 05%1/16WR0402-0201
NI
PR20210.2K1%R0402-0201<Part Number>
NI
PD7B340A-13-F<Part Number>
NI
ACPC3120.1UFX7RC0402-020125V<Part Number>
NI
PD8SMBJ14A<Part Number>
NIAC
PU24SQ24801BDCD
NI
VIN113VCC10OCP9PG8NC11VOUT12VOUT23VOUT34NC25EN11SR7VSS6VIN212PD24SMBJ14A<Part Number>
NIAC
C28570.1UF25V 10%C0402-0201X7R
NI
<Part Number>R4454 05%1/16WR0402-0201
NI
PD12SMBJ14A<Part Number>
NIAC PC31910UFX6S25V 10%<Part Number>C0805_H61
NI
R4448 05%1/16WR0402-0201
NI
PC3130.1UFX7RC0402-020125V<Part Number>
NI
R4445 05%1/16WR0402-0201
NI
PU22SQ24801BDCD
NI
VIN113VCC10OCP9PG8NC11VOUT12VOUT23VOUT34NC25EN11SR7VSS6VIN212 PD11B340A-13-F<Part Number>
NI
ACR4447 05%1/16WR0402-0201
NI
PD96SMBJ14A<Part Number>
NIAC
R4457 05%1/16WR0402-0201
NI
PWRGD_P12V_NIC0P12V_NIC0_EN_RP12V_NIC0_SSP12V_NIC0_OCPPWRGD_P12V_NIC1P12V_NIC1_EN_RP12V_NIC1_SSP12V_NIC1_OCPPWRGD_P12V_NIC2P12V_NIC2_EN_RP12V_NIC2_SSP12V_NIC2_OCPPWRGD_P12V_NIC3P12V_NIC3_EN_RP12V_NIC3_SSP12V_NIC3_OCP
PWRGD_P12V_NIC4P12V_NIC4_EN_RP12V_NIC4_SSP12V_NIC4_OCPPWRGD_P12V_NIC5P12V_NIC5_EN_RP12V_NIC5_SSP12V_NIC5_OCPPWRGD_P12V_NIC6P12V_NIC6_EN_RP12V_NIC6_SSP12V_NIC6_OCPPWRGD_P12V_NIC7P12V_NIC7_EN_RP12V_NIC7_SSP12V_NIC7_OCP



5
5
4
4
3
3
2
2
1
1
D D
C C
B B
A A
Design specification
P12V_SSD E-fuseIout_max=2.083ACurrent limit=2.58ASoft-Start time=2.77msEnable Vth > 2V (High)
Enable:Vth > 2V (High)
Soft-Start timeTSS=630us
Soft-Start timeTSS=630us
Enable:Vth > 2V (High)
Soft-Start timeTSS=630us
Enable:Vth > 2V (High)
Soft-Start timeTSS=630us
Enable:Vth > 2V (High)
Soft-Start timeTSS=630us
Enable:Vth > 2V (High)
Soft-Start timeTSS=630us
Enable:Vth > 2V (High)
Enable:Vth > 2V (High)
Soft-Start timeTSS=630us
Soft-Start timeTSS=630us
Enable:Vth > 2V (High)
P12V_SSD_SQ24801BDCD
Design change 20220707 Design change 20220707Design change 20220707 Design change 20220707Design change 20220707Design change 20220707Design change 20220707 Design change 20220707
20220802 Fine tune OCP20220802 Fine tune OCP20220802 Fine tune OCP20220802 Fine tune OCP20220802 Fine tune OCP20220802 Fine tune OCP20220802 Fine tune OCP20220802 Fine tune OCP
SSD0_PWR_EN_R[115,117,244]SSD4_PWR_EN_R[115,117,245]SSD1_PWR_EN_R[115,117,244]SSD5_PWR_EN_R[115,117,245]SSD2_PWR_EN_R[115,117,244]SSD6_PWR_EN_R[115,117,245]SSD3_PWR_EN_R[115,117,244]SSD7_PWR_EN_R[115,117,245]
PWRGD_P12V_SSD0_R [115,244]PWRGD_P12V_SSD4_R [115,245]PWRGD_P12V_SSD1_R [115,244]PWRGD_P12V_SSD5_R [115,245]PWRGD_P12V_SSD2_R [115,244]PWRGD_P12V_SSD6_R [115,245]PWRGD_P12V_SSD3_R [115,244]PWRGD_P12V_SSD7_R [115,245]
P12V_AUXP3V3_AUXP12V_SSD0_RP5V_AUXP12V_AUXP3V3_AUXP12V_SSD1_RP5V_AUXP12V_AUXP3V3_AUXP12V_SSD2_RP5V_AUXP12V_AUXP3V3_AUXP12V_SSD3_RP5V_AUX
P12V_AUXP3V3_AUXP12V_SSD4_RP5V_AUXP12V_AUXP3V3_AUXP12V_SSD5_RP5V_AUXP12V_AUXP3V3_AUXP12V_SSD6_RP5V_AUXP12V_AUXP3V3_AUXP12V_SSD7_RP5V_AUXSizeDoc NumberRevDate: SheetofReviewerDesignerDepartmentProject
Page TitleCCBU 11236 257Tuesday, August 29, 2023<project_name><Designer> GRANDTETON_SWB_20230829236 P12V_SSD_NCP45750IMN24TWG<Reviewer>SizeDoc NumberRevDate: SheetofReviewerDesignerDepartmentProject
Page TitleCCBU 11236 257Tuesday, August 29, 2023<project_name><Designer> GRANDTETON_SWB_20230829236 P12V_SSD_NCP45750IMN24TWG<Reviewer>SizeDoc NumberRevDate: SheetofReviewerDesignerDepartmentProject
Page TitleCCBU 11236 257Tuesday, August 29, 2023<project_name><Designer> GRANDTETON_SWB_20230829236 P12V_SSD_NCP45750IMN24TWG<Reviewer>C28670.1UF25V 10%C0402-0201X7R
NI
<Part Number>
PC31710UFX6S25V 10%<Part Number>C0805_H61
NI
PD32SMBJ14A<Part Number>
NIACPR209182K1%R0402-0201<Part Number>
NI
PR214182K1%R0402-0201<Part Number>
NI
R4458 05%1/16WR0402-0201
NI
PC3743300PFX7R50VC0402<Part Number>NI PC35910UFX6S25VC0805_H61<Part Number>
NI
PD21SMBJ14A<Part Number>
NIACPC37710UFX6S25V 10%<Part Number>C0805_H61
NI
PC3840.1UFX7RC0402-020125V<Part Number>
NI
PC3633300PFX7R50VC0402<Part Number>NIPD22B340A-13-F<Part Number>
NI
ACPC35710UFX6S25VC0805_H61<Part Number>
NI
PD16SMBJ14A<Part Number>
NIACPC3160.1UF25VC0402-0201<Part Number>X7R10%
NI
PC3821UF25VC0402-0201<Part Number>X6S
NI
R863100K<Part Number>R0402-02011%
NI
PR218182K1%R0402-0201<Part Number>
NI
PC3600.1UFX7RC0402-020125V<Part Number>
NI
PC3561UF25VC0402-0201<Part Number>X6S
NI
PC3801UF25VC0402-0201<Part Number>X6S
NI
R867100K<Part Number>R0402-02011%
NI
PC3873300PFX7R50VC0402-0201<Part Number>NIPC3730.1UFX7RC0402-020125V<Part Number>
NI
PR221182K1%R0402-0201<Part Number>
NI
R864100K<Part Number>R0402-02011%
NI
PC35510UFX6S25V 10%<Part Number>C0805_H61
NI
PD31B340A-13-F<Part Number>
NI
ACPD27B340A-13-F<Part Number>
NI
ACPU32SQ24801BDCD
NI
VIN113VCC10OCP9PG8NC11VOUT12VOUT23VOUT34NC25EN11SR7VSS6VIN212PC36510UFX6S25V 10%<Part Number>C0805_H61
NI
PC3623300PFX7R50VC0402-0201<Part Number>NI
R4465 05%1/16WR0402-0201
NI
C28640.1UF25V 10%C0402-0201X7R
NI
<Part Number>R861100K<Part Number>R0402-02011%
NI R4459 05%1/16WR0402-0201
NI
PC3760.1UF25VC0402-0201<Part Number>X7R10%
NI
PC85610UFX6S25VC0805_H61<Part Number>
NI
C28620.1UF25V 10%C0402-0201X7R
NI
<Part Number>PC4020.1UF25VC0402-0201<Part Number>X7R10%
NI
PC3581UF25VC0402-0201<Part Number>X6S
NI
R4463 05%1/16WR0402-0201
NI
C28610.1UF25V 10%C0402-0201X7R
NI
<Part Number>PC3753300PFX7R50VC0402<Part Number>NIPU35SQ24801BDCD
NI
VIN113VCC10OCP9PG8NC11VOUT12VOUT23VOUT34NC25EN11SR7VSS6VIN212PD23B340A-13-F<Part Number>
NI
ACR865100K<Part Number>R0402-02011%
NI
PC3863300PFX7R50VC0402<Part Number>NIPC3880.1UF25VC0402-0201<Part Number>X7R10%
NI
PR213182K1%R0402-0201<Part Number>
NI
PR217182K1%R0402-0201<Part Number>
NI
PD28SMBJ14A<Part Number>
NIACR4462 05%1/16WR0402-0201
NI
PU36SQ24801BDCD
NI
VIN113VCC10OCP9PG8NC11VOUT12VOUT23VOUT34NC25EN11SR7VSS6VIN212PC3780.1UF25VC0402-0201<Part Number>X7R10%
NI
PC65010UFX6S25VC0805_H61<Part Number>
NI
R868100K<Part Number>R0402-02011%
NI
PC3970.1UFX7RC0402-020125V<Part Number>
NI
PC3701UF25VC0402-0201<Part Number>X6S
NI
PC3960.1UFX7RC0402-020125V<Part Number>
NI
PU37SQ24801BDCD
NI
VIN113VCC10OCP9PG8NC11VOUT12VOUT23VOUT34NC25EN11SR7VSS6VIN212PC39310UFX6S25VC0805_H61<Part Number>
NI
PC3921UF25VC0402-0201<Part Number>X6S
NI
PU31SQ24801BDCD
NI
VIN113VCC10OCP9PG8NC11VOUT12VOUT23VOUT34NC25EN11SR7VSS6VIN212R4460 05%1/16WR0402-0201
NI
R862100K<Part Number>R0402-02011%
NI
PC3941UF25VC0402-0201<Part Number>X6S
NI
PD25SMBJ14A<Part Number>
NIACPD30B340A-13-F<Part Number>
NI
ACPR210182K1%R0402-0201<Part Number>
NI
PD20SMBJ14A<Part Number>
NIACPC37110UFX6S25VC0805_H61<Part Number>
NI
PC3993300PFX7R50VC0402<Part Number>NI
PC3681UF25VC0402-0201<Part Number>X6S
NI
C28680.1UF25V 10%C0402-0201X7R
NI
<Part Number>
PD26B340A-13-F<Part Number>
NI
ACPD29SMBJ14A<Part Number>
NIAC PC37910UFX6S25V 10%<Part Number>C0805_H61
NI
PC39110UFX6S25V 10%<Part Number>C0805_H61
NI
R4461 05%1/16WR0402-0201
NI
PU33SQ24801BDCD
NI
VIN113VCC10OCP9PG8NC11VOUT12VOUT23VOUT34NC25EN11SR7VSS6VIN212PC3900.1UF25VC0402-0201<Part Number>X7R10%
NI
C28630.1UF25V 10%C0402-0201X7R
NI
<Part Number>PC3610.1UFX7RC0402-020125V<Part Number>
NI
PC36710UFX6S25V 10%<Part Number>C0805_H61
NI
PU34SQ24801BDCD
NI
VIN113VCC10OCP9PG8NC11VOUT12VOUT23VOUT34NC25EN11SR7VSS6VIN212PC3983300PFX7R50VC0402<Part Number>NIPD33SMBJ14A<Part Number>
NIACC28650.1UF25V 10%C0402-0201X7R
NI
<Part Number>PC3850.1UFX7RC0402-020125V<Part Number>
NI
PC38310UFX6S25VC0805_H61<Part Number>
NI
PR222182K1%R0402-0201<Part Number>
NI
PD34B340A-13-F<Part Number>
NI
AC
PC3660.1UF25VC0402-0201<Part Number>X7R10%
NI
C28660.1UF25V 10%C0402-0201X7R
NI
<Part Number>PC3720.1UFX7RC0402-020125V<Part Number>
NI
PU30SQ24801BDCD
NI
VIN113VCC10OCP9PG8NC11VOUT12VOUT23VOUT34NC25EN11SR7VSS6VIN212
PD107B340A-13-F<Part Number>
NI
AC
PC64510UFX6S25VC0805_H61<Part Number>
NI
R4464 05%1/16WR0402-0201
NI
R866100K<Part Number>R0402-02011%
NI
PC3540.1UF25VC0402-0201<Part Number>X7R10%
NI
PC38910UFX6S25V 10%<Part Number>C0805_H61
NI
PWRGD_P12V_SSD0P12V_SSD0_SSP12V_SSD0_OCPPWRGD_P12V_SSD1P12V_SSD1_SSP12V_SSD1_OCPPWRGD_P12V_SSD2P12V_SSD2_SSP12V_SSD2_OCPPWRGD_P12V_SSD3P12V_SSD3_SSP12V_SSD3_OCP
PWRGD_P12V_SSD4P12V_SSD4_SSP12V_SSD4_OCPPWRGD_P12V_SSD5P12V_SSD5_SSP12V_SSD5_OCPPWRGD_P12V_SSD6P12V_SSD6_SSP12V_SSD6_OCPPWRGD_P12V_SSD7P12V_SSD7_SSP12V_SSD7_OCP
SSD0_PWR_EN_RSSD4_PWR_EN_RSSD1_PWR_EN_RSSD5_PWR_EN_RSSD2_PWR_EN_RSSD6_PWR_EN_RSSD3_PWR_EN_RSSD7_PWR_EN_R
PWRGD_P12V_SSD0_RPWRGD_P12V_SSD4_RPWRGD_P12V_SSD1_RPWRGD_P12V_SSD5_RPWRGD_P12V_SSD2_RPWRGD_P12V_SSD6_RPWRGD_P12V_SSD3_RPWRGD_P12V_SSD7_R



5
5
4
4
3
3
2
2
1
1
D D
C C
B B
A A
Soft-Start timeTSS=630us
Enable:Vth > 2V (High)
Soft-Start timeTSS=630us
Enable:Vth > 2V (High)
Enable:Vth > 2V (High)
Soft-Start timeTSS=630us
Soft-Start timeTSS=630us
Soft-Start timeTSS=630us
Enable:Vth > 2V (High)
P12V_SSD E-fuseIout_max=2.083ACurrent limit=2.58ASoft-Start time=2.77msEnable Vth > 2V (High)
Design specification
Enable:Vth > 2V (High)
Soft-Start timeTSS=630us
Enable:Vth > 2V (High)
Enable:Vth > 2V (High)
Soft-Start timeTSS=630us
Soft-Start timeTSS=630us
Enable:Vth > 2V (High)
P12V_SSD_SQ24801BDCD
Design change 20220707Design change 20220707Design change 20220707Design change 20220707Design change 20220707Design change 20220707Design change 20220707Design change 20220707
20220802 Fine tune OCP20220802 Fine tune OCP20220802 Fine tune OCP20220802 Fine tune OCP20220802 Fine tune OCP 20220802 Fine tune OCP20220802 Fine tune OCP20220802 Fine tune OCP
SSD8_PWR_EN_R[117,246]SSD12_PWR_EN_R[117,247]SSD9_PWR_EN_R[117,246]SSD13_PWR_EN_R[117,247]SSD10_PWR_EN_R[117,246]SSD14_PWR_EN_R[117,247]SSD11_PWR_EN_R[117,246]SSD15_PWR_EN_R[117,247]
PWRGD_P12V_SSD8_R [117,246]PWRGD_P12V_SSD12_R [117,247]PWRGD_P12V_SSD9_R [117,246]PWRGD_P12V_SSD13_R [117,247]PWRGD_P12V_SSD10_R [117,246]PWRGD_P12V_SSD14_R [117,247]PWRGD_P12V_SSD11_R [117,246]PWRGD_P12V_SSD15_R [117,247]
P12V_AUXP3V3_AUXP12V_AUXP3V3_AUXP12V_SSD8_RP12V_SSD12_RP5V_AUXP5V_AUXP12V_AUXP3V3_AUXP12V_AUXP3V3_AUXP12V_SSD9_RP12V_SSD13_RP5V_AUXP5V_AUXP12V_AUXP3V3_AUXP12V_AUXP3V3_AUXP12V_SSD10_RP12V_SSD14_RP5V_AUXP5V_AUXP12V_AUXP3V3_AUXP12V_AUXP3V3_AUXP12V_SSD11_RP12V_SSD15_RP5V_AUXP5V_AUXSizeDoc NumberRevDate: SheetofReviewerDesignerDepartmentProject
Page TitleCCBU 11237 257Tuesday, August 29, 2023<project_name><Designer> GRANDTETON_SWB_20230829237 P12V_SSD_NCP45750<Reviewer>SizeDoc NumberRevDate: SheetofReviewerDesignerDepartmentProject
Page TitleCCBU 11237 257Tuesday, August 29, 2023<project_name><Designer> GRANDTETON_SWB_20230829237 P12V_SSD_NCP45750<Reviewer>SizeDoc NumberRevDate: SheetofReviewerDesignerDepartmentProject
Page TitleCCBU 11237 257Tuesday, August 29, 2023<project_name><Designer> GRANDTETON_SWB_20230829237 P12V_SSD_NCP45750<Reviewer>
PC41310UFX6S25V 10%<Part Number>C0805_H61
NI
PC4223300PFX7R50VC0402-0201<Part Number>
NI
PC4090.1UFX7RC0402-020125V<Part Number>
NI
PC4200.1UFX7RC0402-020125V<Part Number>
NI
PD115B340A-13-F<Part Number>
NI
ACPC4463300PFX7R50VC0402-0201<Part Number>
NI
PC4103300PFX7R50VC0402-0201<Part Number>
NI
PR225182K1%R0402-0201<Part Number>
NI
PC4000.1UF25VC0402-0201<Part Number>X7R10%
NI
PC4061UF25VC0402-0201<Part Number>X6S
NI
PU39SQ24801BDCD
NI
VIN113VCC10OCP9PG8NC11VOUT12VOUT23VOUT34NC25EN11SR7VSS6VIN212PD44SMBJ14A<Part Number>
NIAC
PC44110UFX6S25VC0805_H61<Part Number>
NI
PR226182K1%R0402-0201<Part Number>
NI
PC4233300PFX7R50VC0402-0201<Part Number>
NI
PC89210UFX6S25VC0805_H61<Part Number>
NI
PC43910UFX6S25V 10%<Part Number>C0805_H61
NI
PU42SQ24801BDCD
NI
VIN113VCC10OCP9PG8NC11VOUT12VOUT23VOUT34NC25EN11SR7VSS6VIN212PU41SQ24801BDCD
NI
VIN113VCC10OCP9PG8NC11VOUT12VOUT23VOUT34NC25EN11SR7VSS6VIN212PU45SQ24801BDCD
NI
VIN113VCC10OCP9PG8NC11VOUT12VOUT23VOUT34NC25EN11SR7VSS6VIN212R873100K<Part Number>R0402-02011%
NI
R4473 05%1/16WR0402-0201
NI
C28700.1UF25V 10%C0402-0201X7R
NI
<Part Number>PC4301UF25VC0402-0201<Part Number>X6S
NI
PC42510UFX6S25V 10%<Part Number>C0805_H61
NI
R869100K<Part Number>R0402-02011%
NI
PU38SQ24801BDCD
NI
VIN113VCC10OCP9PG8NC11VOUT12VOUT23VOUT34NC25EN11SR7VSS6VIN212C28720.1UF25V 10%C0402-0201X7R
NI
<Part Number>PC4380.1UF25VC0402-0201<Part Number>X7R10%
NI
PC4161UF25VC0402-0201<Part Number>X6S
NI
PU44SQ24801BDCD
NI
VIN113VCC10OCP9PG8NC11VOUT12VOUT23VOUT34NC25EN11SR7VSS6VIN212PC87210UFX6S25VC0805_H61<Part Number>
NI
PD39B340A-13-F<Part Number>
NI
ACPD111B340A-13-F<Part Number>
NI
AC PC40710UFX6S25VC0805_H61<Part Number>
NI
PC4210.1UFX7RC0402-020125V<Part Number>
NI
PR234182K1%R0402-0201<Part Number>
NI
C28740.1UF25V 10%C0402-0201X7R
NI
<Part Number>PC4320.1UFX7RC0402-020125V<Part Number>
NI
C28730.1UF25V 10%C0402-0201X7R
NI
<Part Number>PU43SQ24801BDCD
NI
VIN113VCC10OCP9PG8NC11VOUT12VOUT23VOUT34NC25EN11SR7VSS6VIN212PC86110UFX6S25VC0805_H61<Part Number>
NI
PU40SQ24801BDCD
NI
VIN113VCC10OCP9PG8NC11VOUT12VOUT23VOUT34NC25EN11SR7VSS6VIN212PC41710UFX6S25VC0805_H61<Part Number>
NI
C28690.1UF25V 10%C0402-0201X7R
NI
<Part Number>
PC4330.1UFX7RC0402-020125V<Part Number>
NI
PC4181UF25VC0402-0201<Part Number>X6S
NI
PD40SMBJ14A<Part Number>
NIACPC4360.1UF25VC0402-0201<Part Number>X7R10%
NI
PC4113300PFX7R50VC0402-0201<Part Number>
NI
PR233182K1%R0402-0201<Part Number>
NI
R4469 05%1/16WR0402-0201
NI
PD48SMBJ14A<Part Number>
NIAC PR238182K1%R0402-0201<Part Number>
NI
PD41SMBJ14A<Part Number>
NIACPC4120.1UF25VC0402-0201<Part Number>X7R10%
NI
R872100K<Part Number>R0402-02011%
NI
PC40110UFX6S25V 10%<Part Number>C0805_H61
NI
PD123B340A-13-F<Part Number>
NI
ACPC4450.1UFX7RC0402-020125V<Part Number>
NI
PC4080.1UFX7RC0402-020125V<Part Number>
NI
PC4343300PFX7R50VC0402-0201<Part Number>
NI
PC4353300PFX7R50VC0402-0201<Part Number>
NI
PD42B340A-13-F<Part Number>
NI
ACR4470 05%1/16WR0402-0201
NI
C28760.1UF25V 10%C0402-0201X7R
NI
<Part Number>R4471 05%1/16WR0402-0201
NI
PC89410UFX6S25VC0805_H61<Part Number>
NI
PD49SMBJ14A<Part Number>
NIACR4468 05%1/16WR0402-0201
NI
PC4140.1UF25VC0402-0201<Part Number>X7R10%
NI
R877100K<Part Number>R0402-02011%
NIR4472 05%1/16WR0402-0201
NI
R4467 05%1/16WR0402-0201
NI
PD114B340A-13-F<Part Number>
NI
AC PD122B340A-13-F<Part Number>
NI
ACPR237182K1%R0402-0201<Part Number>
NI
R4466 05%1/16WR0402-0201
NI
PR230182K1%R0402-0201<Part Number>
NI
PD121SMBJ14A<Part Number>
NIACPC3640.1UF25VC0402-0201<Part Number>X7R10%
NI
R874100K<Part Number>R0402-02011%
NI
PC41910UFX6S25VC0805_H61<Part Number>
NI
PC4440.1UFX7RC0402-020125V<Part Number>
NI
PC4401UF25VC0402-0201<Part Number>X6S
NI
PC41510UFX6S25V 10%<Part Number>C0805_H61
NI
PC40310UFX6S25V 10%<Part Number>C0805_H61
NI
PC43710UFX6S25V 10%<Part Number>C0805_H61
NI
PC4473300PFX7R50VC0402-0201<Part Number>
NI
R876100K<Part Number>R0402-02011%
NI
PC4240.1UF25VC0402-0201<Part Number>X7R10%
NI
R871100K<Part Number>R0402-02011%
NI
PC4041UF25VC0402-0201<Part Number>X6S
NI
PD43B340A-13-F<Part Number>
NI
AC
C28750.1UF25V 10%C0402-0201X7R
NI
<Part Number>PC42710UFX6S25V 10%<Part Number>C0805_H61
NI
R870100K<Part Number>R0402-02011%
NI
PR229182K1%R0402-0201<Part Number>
NI
PC4421UF25VC0402-0201<Part Number>X6S
NI
PC4260.1UF25VC0402-0201<Part Number>X7R10%
NI
PD113SMBJ14A<Part Number>
NIAC PD45SMBJ14A<Part Number>
NIACPC4281UF25VC0402-0201<Part Number>X6S
NI
C28710.1UF25V 10%C0402-0201X7R
NI
<Part Number>PWRGD_P12V_SSD8PWRGD_P12V_SSD12P12V_SSD8_SSP12V_SSD12_SSP12V_SSD8_OCPP12V_SSD12_OCPPWRGD_P12V_SSD9PWRGD_P12V_SSD13P12V_SSD9_SSP12V_SSD13_SSP12V_SSD9_OCPP12V_SSD13_OCPPWRGD_P12V_SSD10PWRGD_P12V_SSD14P12V_SSD10_SSP12V_SSD14_SSP12V_SSD10_OCPP12V_SSD14_OCPPWRGD_P12V_SSD11PWRGD_P12V_SSD15P12V_SSD11_SSP12V_SSD15_SSP12V_SSD11_OCPP12V_SSD15_OCP
SSD8_PWR_EN_RSSD12_PWR_EN_RSSD9_PWR_EN_RSSD13_PWR_EN_RSSD10_PWR_EN_RSSD14_PWR_EN_RSSD11_PWR_EN_RSSD15_PWR_EN_R
PWRGD_P12V_SSD8_RPWRGD_P12V_SSD12_RPWRGD_P12V_SSD9_RPWRGD_P12V_SSD13_RPWRGD_P12V_SSD10_RPWRGD_P12V_SSD14_RPWRGD_P12V_SSD11_RPWRGD_P12V_SSD15_R



5
5
4
4
3
3
2
2
1
1
D D
C C
B B
A A
Design specification
P3V3_NIC E-fuseIout_max=1.1ACurrent limit=1.59ASoft-Start time=3.33msEnable Vth > 2V (High)
Soft-Start timeTSS=3.33ms
Enable:Vth > 2V (High) Enable:Vth > 2V (High)
Soft-Start timeTSS=3.33ms
Enable:Vth > 2V (High)
Soft-Start timeTSS=3.33ms
Enable:Vth > 2V (High)
Soft-Start timeTSS=3.33ms
Enable:Vth > 2V (High)
Soft-Start timeTSS=3.33ms
Enable:Vth > 2V (High)
Soft-Start timeTSS=3.33ms
Enable:Vth > 2V (High)
Soft-Start timeTSS=3.33ms
Enable:Vth > 2V (High)
Soft-Start timeTSS=3.33ms
P3V3_NIC_SQ24801BDCD
20220802 Fine tune OCP 20220802 Fine tune OCP20220802 Fine tune OCP20220802 Fine tune OCP20220802 Fine tune OCP 20220802 Fine tune OCP20220802 Fine tune OCP 20220802 Fine tune OCP
HP_NIC0_EN[170,235,242,248]HP_NIC4_EN[182,235,243,249]HP_NIC1_EN[173,235,242,248]HP_NIC5_EN[185,235,243,249]HP_NIC2_EN[176,235,242,248]HP_NIC6_EN[188,235,243,249]HP_NIC3_EN[179,235,242,248]HP_NIC7_EN[191,235,243,249]
PWRGD_P3V3_NIC0_R [116,248]PWRGD_P3V3_NIC4_R [116,249]PWRGD_P3V3_NIC1_R [116,248]PWRGD_P3V3_NIC5_R [116,249]PWRGD_P3V3_NIC2_R [116,248]PWRGD_P3V3_NIC6_R [116,249]PWRGD_P3V3_NIC3_R [116,248]PWRGD_P3V3_NIC7_R [116,249]
P3V3_AUXP3V3_NIC0P3V3_NIC0P5V_AUXP3V3_AUXP3V3_NIC4P3V3_NIC4P5V_AUXP3V3_AUXP3V3_NIC1P3V3_NIC1P5V_AUXP3V3_AUXP3V3_NIC2P3V3_NIC2P5V_AUXP3V3_AUXP3V3_NIC3P3V3_NIC3P5V_AUX
P3V3_AUXP3V3_NIC5P3V3_NIC5P5V_AUXP3V3_AUXP3V3_NIC6P3V3_NIC6P5V_AUXP3V3_AUXP3V3_NIC7P3V3_NIC7P5V_AUXSizeDoc NumberRevDate: SheetofReviewerDesignerDepartmentProject
Page TitleCCBU 11238 257Tuesday, August 29, 2023<project_name><Designer> GRANDTETON_SWB_20230829238 P3V3_NIC_NCP45750IMN24TWG<Reviewer>SizeDoc NumberRevDate: SheetofReviewerDesignerDepartmentProject
Page TitleCCBU 11238 257Tuesday, August 29, 2023<project_name><Designer> GRANDTETON_SWB_20230829238 P3V3_NIC_NCP45750IMN24TWG<Reviewer>SizeDoc NumberRevDate: SheetofReviewerDesignerDepartmentProject
Page TitleCCBU 11238 257Tuesday, August 29, 2023<project_name><Designer> GRANDTETON_SWB_20230829238 P3V3_NIC_NCP45750IMN24TWG<Reviewer>
R878100K<Part Number>R0402-02011%
NI
PC4570.1UFX7RC0402-020125V<Part Number>
NIPC4580.1UFX7R25VC0402-0201<Part Number>
NI
PC47510UFX6S16V 10%<Part Number>C0805_H57
NI
PR242432K1%R0402-0201<Part Number>
NI
PC4700.1UFX7R25VC0402-0201<Part Number>
NI
C28790.1UF25V 10%C0402-0201X7R
NI
<Part Number>R4474 05%1/16WR0402-0201
NI
C28820.1UF25V 10%C0402-0201X7R
NI
<Part Number>
C28780.1UF25V 10%C0402-0201X7R
NI
<Part Number>R4478 05%1/16WR0402-0201
NI
PC4760.1UF25VC0402-0201<Part Number>X7R
NI
PC47910UFX6S16VC0805_H57<Part Number>
NI
PU53SQ24801BDCD
NI
VIN113VCC10OCP9PG8NC11VOUT12VOUT23VOUT34NC25EN11SR7VSS6VIN212
PC45110UFX6S16V 10%<Part Number>C0805_H57
NI
PC49110UFX6S16VC0805_H57<Part Number>
NI
C28830.1UF25V 10%C0402-0201X7R
NI
<Part Number>
PC4710.1UFX7R25VC0402-0201<Part Number>
NI
PD56B340A-13-F<Part Number>
NI
ACPU51SQ24801BDCD
NI
VIN113VCC10OCP9PG8NC11VOUT12VOUT23VOUT34NC25EN11SR7VSS6VIN212R883100K<Part Number>R0402-02011%
NI
C28810.1UF25V 10%C0402-0201X7R
NI
<Part Number>PU50SQ24801BDCD
NI
VIN113VCC10OCP9PG8NC11VOUT12VOUT23VOUT34NC25EN11SR7VSS6VIN212PR250432K1%R0402-0201<Part Number>
NI
PC4720.1UF25VC0402-0201<Part Number>X7R10%
NI
PC4600.1UF25VC0402-0201<Part Number>X7R10%
NI
R880100K<Part Number>R0402-02011%
NI
PC45510UFX6S16VC0805_H57<Part Number>
NI
PU48SQ24801BDCD
NI
VIN113VCC10OCP9PG8NC11VOUT12VOUT23VOUT34NC25EN11SR7VSS6VIN212PD52B340A-13-F<Part Number>
NI
ACPC46510UFX6S16VC0805_H57<Part Number>
NI
PC48710UFX6S16V 10%<Part Number>C0805_H57
NI
PC4680.1UFX7RC0402-020125V<Part Number>
NI
PR253432K1%R0402-0201<Part Number>
NI
PC47310UFX6S16V 10%<Part Number>C0805_H57
NI
R881100K<Part Number>R0402-02011%
NI
PC48910UFX6S16VC0805_H57<Part Number>
NI
R884100K<Part Number>R0402-02011%
NI
PD58B340A-13-F<Part Number>
NI
ACC28840.1UF25V 10%C0402-0201X7R
NI
<Part Number>PC4480.1UF25VC0402-0201<Part Number>X7R10%
NI
R882100K<Part Number>R0402-02011%
NI
PC4640.1UF25VC0402-0201<Part Number>X7R
NI
PR249432K1%R0402-0201<Part Number>
NI
PC4590.1UFX7R25VC0402-0201<Part Number>
NI
PC4840.1UF25VC0402-0201<Part Number>X7R10%
NI
R885100K<Part Number>R0402-02011%
NI
PC4880.1UF25VC0402-0201<Part Number>X7R
NI
PC4920.1UFX7RC0402-020125V<Part Number>
NI
R879100K<Part Number>R0402-02011%
NI
PD59B340A-13-F<Part Number>
NI
ACPC4830.1UFX7R25VC0402-0201<Part Number>
NI
PC4780.1UF25VC0402-0201<Part Number>X7R
NI
PU52SQ24801BDCD
NI
VIN113VCC10OCP9PG8NC11VOUT12VOUT23VOUT34NC25EN11SR7VSS6VIN212 R4479 05%1/16WR0402-0201
NI
R4480 05%1/16WR0402-0201
NI
PC4940.1UFX7R25VC0402-0201<Part Number>
NI
PC4810.1UFX7RC0402-020125V<Part Number>
NI
PC45310UFX6S16VC0805_H57<Part Number>
NI
PC4660.1UF25VC0402-0201<Part Number>X7R
NI
PC4860.1UF25VC0402-0201<Part Number>X7R10%
NI
PC4520.1UF25VC0402-0201<Part Number>X7R
NI
R4481 05%1/16WR0402-0201
NI
PC47710UFX6S16VC0805_H57<Part Number>
NI
PC4800.1UFX7RC0402-020125V<Part Number>
NI
PR254432K1%R0402-0201<Part Number>
NI
PC4500.1UF25VC0402-0201<Part Number>X7R10%
NI
PD54B340A-13-F<Part Number>
NI
ACPC4560.1UFX7RC0402-020125V<Part Number>
NI
PC4900.1UF25VC0402-0201<Part Number>X7R
NI
PC4950.1UFX7R25VC0402-0201<Part Number>
NI
PR246432K1%R0402-0201<Part Number>
NI
PU47SQ24801BDCD
NI
VIN113VCC10OCP9PG8NC11VOUT12VOUT23VOUT34NC25EN11SR7VSS6VIN212PD55B340A-13-F<Part Number>
NI
ACPC4820.1UFX7R25VC0402-0201<Part Number>
NI
PR245432K1%R0402-0201<Part Number>
NI
C28770.1UF25V 10%C0402-0201X7R
NI
<Part Number>PC4690.1UFX7RC0402-020125V<Part Number>
NI
PC44910UFX6S16V 10%<Part Number>C0805_H57
NI
C28800.1UF25V 10%C0402-0201X7R
NI
<Part Number>PR241432K1%R0402-0201<Part Number>
NI
PC46110UFX6S16V 10%<Part Number>C0805_H57
NI
PU46SQ24801BDCD
NI
VIN113VCC10OCP9PG8NC11VOUT12VOUT23VOUT34NC25EN11SR7VSS6VIN212 PC4540.1UF25VC0402-0201<Part Number>X7R
NI
PC4740.1UF25VC0402-0201<Part Number>X7R10%
NI
PC4620.1UF25VC0402-0201<Part Number>X7R10%
NI
R4477 05%1/16WR0402-0201
NI
PC46710UFX6S16VC0805_H57<Part Number>
NI
PU49SQ24801BDCD
NI
VIN113VCC10OCP9PG8NC11VOUT12VOUT23VOUT34NC25EN11SR7VSS6VIN212PD53B340A-13-F<Part Number>
NI
ACPC46310UFX6S16V 10%<Part Number>C0805_H57
NI
R4475 05%1/16WR0402-0201
NI
PC48510UFX6S16V 10%<Part Number>C0805_H57
NI
PD57B340A-13-F<Part Number>
NI
ACPC4930.1UFX7RC0402-020125V<Part Number>
NI
R4476 05%1/16WR0402-0201
NI
PWRGD_P3V3_NIC0P3V3_NIC0_SSP3V3_NIC0_OCPPWRGD_P3V3_NIC4P3V3_NIC4_SSP3V3_NIC4_OCPPWRGD_P3V3_NIC1P3V3_NIC1_SSP3V3_NIC1_OCPPWRGD_P3V3_NIC2P3V3_NIC2_SSP3V3_NIC2_OCPPWRGD_P3V3_NIC3P3V3_NIC3_SSP3V3_NIC3_OCP
PWRGD_P3V3_NIC5P3V3_NIC5_SSP3V3_NIC5_OCPPWRGD_P3V3_NIC6P3V3_NIC6_SSP3V3_NIC6_OCPPWRGD_P3V3_NIC7P3V3_NIC7_SSP3V3_NIC7_OCP
PWRGD_P3V3_NIC0_RPWRGD_P3V3_NIC4_RPWRGD_P3V3_NIC1_RPWRGD_P3V3_NIC5_RPWRGD_P3V3_NIC2_RPWRGD_P3V3_NIC6_RPWRGD_P3V3_NIC3_RPWRGD_P3V3_NIC7_R



5
5
4
4
3
3
2
2
1
1
D D
C C
B B
A A
Design specification
P3V3_SSD E-fuseIout_max=0.025ACurrent limit=0.85ASoft-Start time=3.33msEnable Vth > 2V (High)
Soft-Start timeTSS=3.33ms
Enable:Vth > 2V (High) Enable:Vth > 2V (High)
Soft-Start timeTSS=3.33ms
Enable:Vth > 2V (High)
Soft-Start timeTSS=3.33ms
Enable:Vth > 2V (High)
Soft-Start timeTSS=3.33ms
Enable:Vth > 2V (High)
Soft-Start timeTSS=3.33ms
Enable:Vth > 2V (High)
Soft-Start timeTSS=3.33ms
Soft-Start timeTSS=3.33ms
Enable:Vth > 2V (High)
Soft-Start timeTSS=3.33ms
Enable:Vth > 2V (High)
P3V3_SSD_SQ24801BDCD
PWRGD_P3V3_SSD0_R [101,115,250]PWRGD_P3V3_SSD4_R [101,115,251]PWRGD_P3V3_SSD1_R [101,115,250]PWRGD_P3V3_SSD5_R [101,115,251]PWRGD_P3V3_SSD6_R [101,115,251]PWRGD_P3V3_SSD2_R [101,115,250]PWRGD_P3V3_SSD7_R [101,115,251]PWRGD_P3V3_SSD3_R [101,115,250]
SSD0_AUX_P3V3_EN_R[202,250]SSD1_AUX_P3V3_EN_R[202,250]SSD2_AUX_P3V3_EN_R[202,250]SSD3_AUX_P3V3_EN_R[202,250]
SSD4_AUX_P3V3_EN_R[202,251]SSD5_AUX_P3V3_EN_R[202,251]SSD6_AUX_P3V3_EN_R[202,251]SSD7_AUX_P3V3_EN_R[202,251]
P3V3_AUXP3V3_SSD0P3V3_SSD0P5V_AUXP3V3_AUXP3V3_SSD4P3V3_SSD4P5V_AUXP3V3_AUXP3V3_SSD1P3V3_AUXP3V3_SSD5P3V3_SSD1P3V3_SSD5P5V_AUXP5V_AUXP3V3_AUXP3V3_SSD2P3V3_AUXP3V3_SSD6P3V3_SSD2P3V3_SSD6P5V_AUXP5V_AUXP3V3_AUXP3V3_SSD3P3V3_AUXP3V3_SSD7P3V3_SSD3P3V3_SSD7P5V_AUXP5V_AUXSizeDoc NumberRevDate: SheetofReviewerDesignerDepartmentProject
Page TitleCCBU 11239 257Tuesday, August 29, 2023<project_name><Designer> GRANDTETON_SWB_20230829239 P3V3_SSD_NCP45750IMN24TWG<Reviewer>SizeDoc NumberRevDate: SheetofReviewerDesignerDepartmentProject
Page TitleCCBU 11239 257Tuesday, August 29, 2023<project_name><Designer> GRANDTETON_SWB_20230829239 P3V3_SSD_NCP45750IMN24TWG<Reviewer>SizeDoc NumberRevDate: SheetofReviewerDesignerDepartmentProject
Page TitleCCBU 11239 257Tuesday, August 29, 2023<project_name><Designer> GRANDTETON_SWB_20230829239 P3V3_SSD_NCP45750IMN24TWG<Reviewer>
PC5100.1UF25VC0402-0201<Part Number>X7R10%
NI
PD66B340A-13-F<Part Number>
NI
ACPC5300.1UFX7R25VC0402-0201<Part Number>
NI
PC5060.1UFX7R25VC0402-0201<Part Number>
NI
PC5040.1UFX7RC0402-020125V<Part Number>
NI
PD60B340A-13-F<Part Number>
NI
ACPR2572M 1%R0402-0201<Part Number>
NI
PC5320.1UF25VC0402-0201<Part Number>X7R10%
NI
R4482 05%1/16WR0402-0201
NI
PU61SQ24801BDCD
NI
VIN113VCC10OCP9PG8NC11VOUT12VOUT23VOUT34NC25EN11SR7VSS6VIN212PC5410.1UFX7RC0402-020125V<Part Number>
NI
PU57SQ24801BDCD
NI
VIN113VCC10OCP9PG8NC11VOUT12VOUT23VOUT34NC25EN11SR7VSS6VIN212PC52310UFX6S16V 10%<Part Number>C0805_H57
NI
PC53510UFX6S16V 10%<Part Number>C0805_H57
NI
PC52110UFX6S16V 10%<Part Number>C0805_H57
NI
R890100K<Part Number>R0402-02011%
NI
PD61B340A-13-F<Part Number>
NI
ACPC5120.1UF25VC0402-0201<Part Number>X7R
NI
PR2582M 1%R0402-0201<Part Number>
NI
PU59SQ24801BDCD
NI
VIN113VCC10OCP9PG8NC11VOUT12VOUT23VOUT34NC25EN11SR7VSS6VIN212PC51310UFX6S16VC0805_H57<Part Number>
NI
PC5050.1UFX7RC0402-020125V<Part Number>
NI
PC50910UFX6S16V 10%<Part Number>C0805_H57
NI
PC49910UFX6S16V 10%<Part Number>C0805_H57
NI
PC53310UFX6S16V 10%<Part Number>C0805_H57
NI
PU54SQ24801BDCD
NI
VIN113VCC10OCP9PG8NC11VOUT12VOUT23VOUT34NC25EN11SR7VSS6VIN212C28850.1UF25V 10%C0402-0201X7R
NI
<Part Number>
PC5290.1UFX7RC0402-020125V<Part Number>
NI
PR2622M 1%R0402-0201<Part Number>
NI
PC53710UFX6S16VC0805_H57<Part Number>
NI
PR2692M 1%R0402-0201<Part Number>
NI
C28870.1UF25V 10%C0402-0201X7R
NI
<Part Number>R4491 05%1/16WR0402-0201
NI
PR2612M 1%R0402-0201<Part Number>
NI
PC5000.1UF25VC0402-0201<Part Number>X7R
NI
R886100K<Part Number>R0402-02011%
NI
C28860.1UF25V 10%C0402-0201X7R
NI
<Part Number>R4486 05%1/16WR0402-0201
NI
R888100K<Part Number>R0402-02011%
NI
PC51510UFX6S16VC0805_H57<Part Number>
NI
R893100K<Part Number>R0402-02011%
NI
C28920.1UF25V 10%C0402-0201X7R
NI
<Part Number>PD65B340A-13-F<Part Number>
NI
ACPR2652M 1%R0402-0201<Part Number>
NI
PC52710UFX6S16VC0805_H57<Part Number>
NI
PR2702M 1%R0402-0201<Part Number>
NI
PU55SQ24801BDCD
NI
VIN113VCC10OCP9PG8NC11VOUT12VOUT23VOUT34NC25EN11SR7VSS6VIN212
C28890.1UF25V 10%C0402-0201X7R
NI
<Part Number>PD63B340A-13-F<Part Number>
NI
ACPC49710UFX6S16V 10%<Part Number>C0805_H57
NI
PD67B340A-13-F<Part Number>
NI
AC
PC5070.1UFX7R25VC0402-0201<Part Number>
NI
PU60SQ24801BDCD
NI
VIN113VCC10OCP9PG8NC11VOUT12VOUT23VOUT34NC25EN11SR7VSS6VIN212
R887100K<Part Number>R0402-02011%
NI
PC5360.1UF25VC0402-0201<Part Number>X7R
NI
PC5220.1UF25VC0402-0201<Part Number>X7R10%
NI
PC53910UFX6S16VC0805_H57<Part Number>
NI
R4483 05%1/16WR0402-0201
NI
PC5200.1UF25VC0402-0201<Part Number>X7R10%
NI
PC50110UFX6S16VC0805_H57<Part Number>
NI
PC5140.1UF25VC0402-0201<Part Number>X7R
NI
C28910.1UF25V 10%C0402-0201X7R
NI
<Part Number>PC5280.1UFX7RC0402-020125V<Part Number>
NI
PD64B340A-13-F<Part Number>
NI
ACC28880.1UF25V 10%C0402-0201X7R
NI
<Part Number>R4487 05%1/16WR0402-0201
NI
PC5160.1UFX7RC0402-020125V<Part Number>
NI
PC5240.1UF25VC0402-0201<Part Number>X7R
NI
R4495 05%1/16WR0402-0201
NI
PC5380.1UF25VC0402-0201<Part Number>X7R
NI
PD62B340A-13-F<Part Number>
NI
AC PC50310UFX6S16VC0805_H57<Part Number>
NI
PC5180.1UFX7R25VC0402-0201<Part Number>
NI
PC5340.1UF25VC0402-0201<Part Number>X7R10%
NI
PC4960.1UF25VC0402-0201<Part Number>X7R10%
NI
PC5420.1UFX7R25VC0402-0201<Part Number>
NI
PR2662M 1%R0402-0201<Part Number>
NI
PC5020.1UF25VC0402-0201<Part Number>X7R
NI
R891100K<Part Number>R0402-02011%
NI
PC5170.1UFX7RC0402-020125V<Part Number>
NI
PC5080.1UF25VC0402-0201<Part Number>X7R10%
NI
C28900.1UF25V 10%C0402-0201X7R
NI
<Part Number>PC5260.1UF25VC0402-0201<Part Number>X7R
NI
PC5310.1UFX7R25VC0402-0201<Part Number>
NI
PC5190.1UFX7R25VC0402-0201<Part Number>
NI
PC4980.1UF25VC0402-0201<Part Number>X7R10%
NI
PU56SQ24801BDCD
NI
VIN113VCC10OCP9PG8NC11VOUT12VOUT23VOUT34NC25EN11SR7VSS6VIN212 R892100K<Part Number>R0402-02011%
NI
PC52510UFX6S16VC0805_H57<Part Number>
NI
PC5430.1UFX7R25VC0402-0201<Part Number>
NI
R4490 05%1/16WR0402-0201
NI
R4494 05%1/16WR0402-0201
NI
PC51110UFX6S16V 10%<Part Number>C0805_H57
NI
PC5400.1UFX7RC0402-020125V<Part Number>
NI
PU58SQ24801BDCD
NI
VIN113VCC10OCP9PG8NC11VOUT12VOUT23VOUT34NC25EN11SR7VSS6VIN212R889100K<Part Number>R0402-02011%
NI
PWRGD_P3V3_SSD0P3V3_SSD0_SSP3V3_SSD0_OCPPWRGD_P3V3_SSD4P3V3_SSD4_SSP3V3_SSD4_OCPPWRGD_P3V3_SSD1PWRGD_P3V3_SSD5P3V3_SSD1_SSP3V3_SSD5_SSP3V3_SSD1_OCPP3V3_SSD5_OCPPWRGD_P3V3_SSD2PWRGD_P3V3_SSD6P3V3_SSD2_SSP3V3_SSD6_SSP3V3_SSD2_OCPP3V3_SSD6_OCPPWRGD_P3V3_SSD3PWRGD_P3V3_SSD7P3V3_SSD3_SSP3V3_SSD7_SSP3V3_SSD3_OCPP3V3_SSD7_OCP
PWRGD_P3V3_SSD0_RPWRGD_P3V3_SSD4_RPWRGD_P3V3_SSD1_RPWRGD_P3V3_SSD5_RPWRGD_P3V3_SSD6_RPWRGD_P3V3_SSD2_RPWRGD_P3V3_SSD7_RPWRGD_P3V3_SSD3_R
SSD0_AUX_P3V3_EN_RSSD1_AUX_P3V3_EN_RSSD2_AUX_P3V3_EN_RSSD3_AUX_P3V3_EN_R
SSD4_AUX_P3V3_EN_RSSD5_AUX_P3V3_EN_RSSD6_AUX_P3V3_EN_RSSD7_AUX_P3V3_EN_R



5
5
4
4
3
3
2
2
1
1
D D
C C
B B
A A
Enable:Vth > 2V (High)
Soft-Start timeTSS=3.33ms
Enable:Vth > 2V (High)
Soft-Start timeTSS=3.33ms
Enable:Vth > 2V (High)
Soft-Start timeTSS=3.33ms
Enable:Vth > 2V (High)
Design specification
Soft-Start timeTSS=3.33ms
Soft-Start timeTSS=3.33ms
Enable:Vth > 2V (High)
P3V3_SSD E-fuseIout_max=0.025ACurrent limit=0.85ASoft-Start time=3.33msEnable Vth > 2V (High)
Soft-Start timeTSS=3.33ms
Soft-Start timeTSS=3.33ms
Enable:Vth > 2V (High)
Enable:Vth > 2V (High)
Soft-Start timeTSS=3.33ms
Enable:Vth > 2V (High)
P3V3_SSD_SQ24801BDCD
PWRGD_P3V3_SSD8_R [102,117,252]PWRGD_P3V3_SSD12_R [102,117,253]PWRGD_P3V3_SSD9_R [102,117,252]PWRGD_P3V3_SSD13_R [102,117,253]PWRGD_P3V3_SSD14_R [102,117,253]PWRGD_P3V3_SSD10_R [102,117,252]PWRGD_P3V3_SSD15_R [102,117,253]PWRGD_P3V3_SSD11_R [102,117,252]
SSD8_AUX_P3V3_EN_R[203,252]SSD9_AUX_P3V3_EN_R[203,252]SSD10_AUX_P3V3_EN_R[203,252]SSD11_AUX_P3V3_EN_R[203,252]
SSD12_AUX_P3V3_EN_R[203,253]SSD13_AUX_P3V3_EN_R[203,253]SSD14_AUX_P3V3_EN_R[203,253]SSD15_AUX_P3V3_EN_R[203,253]
P3V3_AUXP3V3_SSD8P3V3_AUXP3V3_SSD12P3V3_SSD8P3V3_SSD12P5V_AUXP5V_AUXP3V3_AUXP3V3_SSD9P3V3_AUXP3V3_SSD13P3V3_SSD9P3V3_SSD13P5V_AUXP5V_AUXP3V3_AUXP3V3_SSD14P3V3_AUXP3V3_SSD10P3V3_SSD14P3V3_SSD10P5V_AUXP5V_AUXP3V3_AUXP3V3_SSD15P3V3_AUXP3V3_SSD11P3V3_SSD15P3V3_SSD11P5V_AUXP5V_AUXSizeDoc NumberRevDate: SheetofReviewerDesignerDepartmentProject
Page TitleCCBU 11240 257Tuesday, August 29, 2023<project_name><Designer> GRANDTETON_SWB_20230829250 P3V3_SSD_NCP45750<Reviewer>SizeDoc NumberRevDate: SheetofReviewerDesignerDepartmentProject
Page TitleCCBU 11240 257Tuesday, August 29, 2023<project_name><Designer> GRANDTETON_SWB_20230829250 P3V3_SSD_NCP45750<Reviewer>SizeDoc NumberRevDate: SheetofReviewerDesignerDepartmentProject
Page TitleCCBU 11240 257Tuesday, August 29, 2023<project_name><Designer> GRANDTETON_SWB_20230829250 P3V3_SSD_NCP45750<Reviewer>
PR2732M 1%R0402-0201<Part Number>
NI
PU62SQ24801BDCD
NI
VIN113VCC10OCP9PG8NC11VOUT12VOUT23VOUT34NC25EN11SR7VSS6VIN212
PC57510UFX6S16VC0805_H57<Part Number>
NI
PC54710UFX6S16V 10%<Part Number>C0805_H57
NI
PC5520.1UFX7RC0402-020125V<Part Number>
NI
PC5760.1UFX7RC0402-020125V<Part Number>
NI
PC5910.1UFX7R25VC0402-0201<Part Number>
NI
R4498 05%1/16WR0402-0201
NI
R898100K<Part Number>R0402-02011%
NI
PC5580.1UF25VC0402-0201<Part Number>X7R10%
NI
PC5870.1UF25VC0402-0201<Part Number>X7R
NI
C28980.1UF25V 10%C0402-0201X7R
NI
<Part Number>PC58310UFX6S16V 10%<Part Number>C0805_H57
NI
PC5820.1UF25VC0402-0201<Part Number>X7R10%
NI
PD74B340A-13-F<Part Number>
NI
AC
PC55110UFX6S16VC0805_H57<Part Number>
NI
PU63SQ24801BDCD
NI
VIN113VCC10OCP9PG8NC11VOUT12VOUT23VOUT34NC25EN11SR7VSS6VIN212
R4510 05%1/16WR0402-0201
NI
PC5650.1UFX7RC0402-020125V<Part Number>
NI
C28960.1UF25V 10%C0402-0201X7R
NI
<Part Number>PR2772M 1%R0402-0201<Part Number>
NI
C28930.1UF25V 10%C0402-0201X7R
NI
<Part Number>
PD75B340A-13-F<Part Number>
NI
AC
PU65SQ24801BDCD
NI
VIN113VCC10OCP9PG8NC11VOUT12VOUT23VOUT34NC25EN11SR7VSS6VIN212PC56310UFX6S16VC0805_H57<Part Number>
NI
PC5600.1UF25VC0402-0201<Part Number>X7R
NI
PC54510UFX6S16V 10%<Part Number>C0805_H57
NI
PU66SQ24801BDCD
NI
VIN113VCC10OCP9PG8NC11VOUT12VOUT23VOUT34NC25EN11SR7VSS6VIN212PC5770.1UFX7RC0402-020125V<Part Number>
NI
PC5620.1UF25VC0402-0201<Part Number>X7R
NI
PC58410UFX6S16VC0805_H57<Part Number>
NI
PC5530.1UFX7RC0402-020125V<Part Number>
NI
PR2782M 1%R0402-0201<Part Number>
NI
PD71B340A-13-F<Part Number>
NI
ACPC5790.1UFX7R25VC0402-0201<Part Number>
NI
C28990.1UF25V 10%C0402-0201X7R
NI
<Part Number>
PC5660.1UFX7R25VC0402-0201<Part Number>
NI
R900100K<Part Number>R0402-02011%
NI
PD72B340A-13-F<Part Number>
NI
ACPC58610UFX6S16VC0805_H57<Part Number>
NI
PC5540.1UFX7R25VC0402-0201<Part Number>
NI
R4511 05%1/16WR0402-0201
NI
R4499 05%1/16WR0402-0201
NI
R899100K<Part Number>R0402-02011%
NI
C28950.1UF25V 10%C0402-0201X7R
NI
<Part Number>R4507 05%1/16WR0402-0201
NI
PC5500.1UF25VC0402-0201<Part Number>X7R
NI
R897100K<Part Number>R0402-02011%
NI
C28970.1UF25V 10%C0402-0201X7R
NI
<Part Number>
PC5480.1UF25VC0402-0201<Part Number>X7R
NI
PC58110UFX6S16V 10%<Part Number>C0805_H57
NI
PD68B340A-13-F<Part Number>
NI
AC
PC5880.1UFX7RC0402-020125V<Part Number>
NI
PC5890.1UFX7RC0402-020125V<Part Number>
NI
R896100K<Part Number>R0402-02011%
NI
PC55910UFX6S16V 10%<Part Number>C0805_H57
NI
PC5720.1UF25VC0402-0201<Part Number>X7R
NI
PC56910UFX6S16V 10%<Part Number>C0805_H57
NI
PC5740.1UF25VC0402-0201<Part Number>X7R
NI
PR2742M 1%R0402-0201<Part Number>
NI
C29000.1UF25V 10%C0402-0201X7R
NI
<Part Number>
R895100K<Part Number>R0402-02011%
NI
C28940.1UF25V 10%C0402-0201X7R
NI
<Part Number>R894100K<Part Number>R0402-02011%
NI
PU67SQ24801BDCD
NI
VIN113VCC10OCP9PG8NC11VOUT12VOUT23VOUT34NC25EN11SR7VSS6VIN212PC5560.1UF25VC0402-0201<Part Number>X7R10%
NI
PC5700.1UF25VC0402-0201<Part Number>X7R10%
NI
PU68SQ24801BDCD
NI
VIN113VCC10OCP9PG8NC11VOUT12VOUT23VOUT34NC25EN11SR7VSS6VIN212R4506 05%1/16WR0402-0201
NI
PC5550.1UFX7R25VC0402-0201<Part Number>
NI
PD73B340A-13-F<Part Number>
NI
ACPC57110UFX6S16V 10%<Part Number>C0805_H57
NI
R901100K<Part Number>R0402-02011%
NI
PR2862M 1%R0402-0201<Part Number>
NI
PU69SQ24801BDCD
NI
VIN113VCC10OCP9PG8NC11VOUT12VOUT23VOUT34NC25EN11SR7VSS6VIN212 PC5670.1UFX7R25VC0402-0201<Part Number>
NI
PC5850.1UF25VC0402-0201<Part Number>X7R
NI
PD69B340A-13-F<Part Number>
NI
ACR4502 05%1/16WR0402-0201
NI
R4503 05%1/16WR0402-0201
NI
PC5800.1UF25VC0402-0201<Part Number>X7R10%
NI
PC5440.1UF25VC0402-0201<Part Number>X7R10%
NI
PD70B340A-13-F<Part Number>
NI
ACPC56110UFX6S16VC0805_H57<Part Number>
NI
PR2852M 1%R0402-0201<Part Number>
NI
PC5680.1UF25VC0402-0201<Part Number>X7R10%
NI
PC5780.1UFX7R25VC0402-0201<Part Number>
NI
PC5900.1UFX7R25VC0402-0201<Part Number>
NI
PR2812M 1%R0402-0201<Part Number>
NI
PC57310UFX6S16VC0805_H57<Part Number>
NI
PU64SQ24801BDCD
NI
VIN113VCC10OCP9PG8NC11VOUT12VOUT23VOUT34NC25EN11SR7VSS6VIN212PC54910UFX6S16VC0805_H57<Part Number>
NI
PC5640.1UFX7RC0402-020125V<Part Number>
NI
PC5460.1UF25VC0402-0201<Part Number>X7R10%
NI
PC55710UFX6S16V 10%<Part Number>C0805_H57
NI
PR2822M 1%R0402-0201<Part Number>
NI
PWRGD_P3V3_SSD8PWRGD_P3V3_SSD12P3V3_SSD8_SSP3V3_SSD12_SSP3V3_SSD8_OCPP3V3_SSD12_OCPPWRGD_P3V3_SSD9PWRGD_P3V3_SSD13P3V3_SSD9_SSP3V3_SSD13_SSP3V3_SSD9_OCPP3V3_SSD13_OCPPWRGD_P3V3_SSD14PWRGD_P3V3_SSD10P3V3_SSD14_SSP3V3_SSD10_SSP3V3_SSD14_OCPP3V3_SSD10_OCPPWRGD_P3V3_SSD15PWRGD_P3V3_SSD11P3V3_SSD15_SSP3V3_SSD11_SSP3V3_SSD15_OCPP3V3_SSD11_OCP
PWRGD_P3V3_SSD8_RPWRGD_P3V3_SSD12_RPWRGD_P3V3_SSD9_RPWRGD_P3V3_SSD13_RPWRGD_P3V3_SSD14_RPWRGD_P3V3_SSD10_RPWRGD_P3V3_SSD15_RPWRGD_P3V3_SSD11_R
SSD8_AUX_P3V3_EN_RSSD9_AUX_P3V3_EN_RSSD10_AUX_P3V3_EN_RSSD11_AUX_P3V3_EN_R
SSD12_AUX_P3V3_EN_RSSD13_AUX_P3V3_EN_RSSD14_AUX_P3V3_EN_RSSD15_AUX_P3V3_EN_R



5
5
4
4
3
3
2
2
1
1
D D
C C
B B
A A
Design specification
P3V3 E-fuse
Iout_max=1.449ACurrent limit=2ASoft-Start time=3.33msEnable Vth > 2V (High)
OCP2AVclamp3.66V
t_SS3.26ms
P3V3_MP5016_Colay
20220817 Design change20220817 Design changePWR_EN_P3V3_R[118,234]PWRGD_P3V3_R [118,234]P3V3_AUXP3V3P3V3_AUXP3V3P3V3
SizeDoc NumberRevDate: SheetofReviewerDesignerDepartmentProject
Page TitleCCBU 11241 257Tuesday, August 29, 2023<project_name><Designer> GRANDTETON_SWB_20230829241 P3V3_MP5016_Colay<Reviewer>SizeDoc NumberRevDate: SheetofReviewerDesignerDepartmentProject
Page TitleCCBU 11241 257Tuesday, August 29, 2023<project_name><Designer> GRANDTETON_SWB_20230829241 P3V3_MP5016_Colay<Reviewer>SizeDoc NumberRevDate: SheetofReviewerDesignerDepartmentProject
Page TitleCCBU 11241 257Tuesday, August 29, 2023<project_name><Designer> GRANDTETON_SWB_20230829241 P3V3_MP5016_Colay<Reviewer>
PC594100PFX7R50VC0402-0201<Part Number>R582710K1%R0402-0201<Part Number>PR685371.5K<Part Number>R0402-02011%PC5931UF25VC0402-0201<Part Number>X6SQ126BBSS138BKS<Part Number>D23G25S24PU70MP5016GQH-L-ZEN9MODE5ILIMIT4GND3VCC1_2DV_DT10GATE8SOURCE6_7Q126ABSS138BKS<Part Number>S11G12D16PR68541.05K1%R0402-0201<Part Number>R582510K1%R0402-0201<Part Number>PC5970.047UFX7RC0402-020125V<Part Number>R582810K1%R0402-0201<Part Number>PC59639PF<Part Number>C0402-020150VNPOR5826 0R0402-02015%1/16WPC59510UFX6S25VC0805_H61<Part Number>R582910K1%R0402-0201<Part Number>R5824 0R0402-02015%1/16WP3V3_CO_ENP3V3_CO_MODEP3V3_CO_GATEP3V3_CO_ILIMITP3V3_CO_DV_DTP3V3_PG_G2P3V3_PG_G1PWRGD_P3V3_DPWRGD_P3V3_R



5
5
4
4
3
3
2
2
1
1
D D
C C
B B
A A
OV:15.6V 16.12V 16.64V
tdelay: 6.29mstfault: 1.27ms
Enable:Vth>1.391V(high)
Current limit =8.8A
Soft start time=2.75ms
De-pop
Pop
De-pop
MP5025C/
MP5022C
MP5025A/
MP5022A
PU71 optional BOM
De-pop
De-pop
PR6861=100
PR6862=71.5K
De-pop
PR6865=49.9
PopPR6866=120K
Pop
Pop
PC610=2.2uF
Pop
P12V_NICx E-fuseIout_max=6.6ACurrent limit=8.8ASoft-Start time=2.77msEnable Vth > 1.391V (High)
Design specification
PU72 optional BOM
Current limit =8.8A
OV:15.6V 16.12V 16.64V
Soft start time=2.75ms
tdelay: 6.29mstfault: 1.27ms
Enable:Vth>1.391V(high)
tdelay: 6.29mstfault: 1.27msCurrent limit =8.8A
Current limit =8.8A
OV:15.6V 16.12V 16.64V Enable:Vth>1.391V(high)
OV:15.6V 16.12V 16.64V
Soft start time=2.75ms
tdelay: 6.29mstfault: 1.27ms Soft start time=2.75ms
Enable:Vth>1.391V(high)
Pop
Pop
PR6864=71.5K
De-pop
MP5025C/
MP5022C
De-pop
PC611=2.2uF
PR6868=120K
De-pop
De-pop
MP5025A/
MP5022A
Pop
Pop
PopPR6867=49.9
PR6863=100
De-pop
PU74 optional BOM
PR6892=120K
MP5025C/
MP5022C
Pop
PR6891=49.9
Pop De-pop
De-pop
PR6888=71.5K
PR6887=100 Pop
De-pop
PC631=2.2uF
De-pop
Pop
De-pop
Pop
MP5025A/
MP5022A
PU73 optional BOM
PR6890=120K
MP5025C/
MP5022C
Pop
PR6889=49.9
Pop De-pop
De-pop
PR6886=71.5K
PR6885=100 Pop
De-pop
PC630=2.2uF
De-pop
Pop
De-pop
Pop
MP5025A/
MP5022A
P12V_NICx_MP5025C_Colay_1
PWRGD_P12V_NIC0_R [116,170,235]HP_NIC0_EN[170,235,238,248]PWRGD_P12V_NIC1_R [116,173,235]HP_NIC1_EN[173,235,238,248]PWRGD_P12V_NIC2_R [116,176,235]PWRGD_P12V_NIC3_R [116,179,235]HP_NIC2_EN[176,235,238,248]HP_NIC3_EN[179,235,238,248]
P12V_AUXP3V3_AUXP12V_NIC0_RP3V3_AUXP12V_AUXP12V_AUXP3V3_AUXP12V_NIC1_RP12V_AUXP3V3_AUXP12V_AUXP12V_AUXP3V3_AUXP3V3_AUXP12V_NIC2_RP12V_NIC3_RP12V_AUXP12V_AUXP3V3_AUXP3V3_AUXSizeDoc NumberRevDate: SheetofReviewerDesignerDepartmentProject
Page TitleCCBU 11242 257Tuesday, August 29, 2023<project_name><Designer> GRANDTETON_SWB_20230829242 P12V_NICx_MP5025C_Colay_1<Reviewer>SizeDoc NumberRevDate: SheetofReviewerDesignerDepartmentProject
Page TitleCCBU 11242 257Tuesday, August 29, 2023<project_name><Designer> GRANDTETON_SWB_20230829242 P12V_NICx_MP5025C_Colay_1<Reviewer>SizeDoc NumberRevDate: SheetofReviewerDesignerDepartmentProject
Page TitleCCBU 11242 257Tuesday, August 29, 2023<project_name><Designer> GRANDTETON_SWB_20230829242 P12V_NICx_MP5025C_Colay_1<Reviewer>R946 05% R0402-0201<Part Number>PR6886 71.5K1%R0402-0201<Part Number>
NI
PR6867 49.91%R0603<Part Number>R5833 05%1/16WR0402-0201PC6320.022UFX7R25VC0402-0201<Part Number>
R5830 05%1/16WR0402-0201
PC5991UFX6S25VC0402-0201<Part Number>PR6888 71.5K1%R0402-0201<Part Number>
NIPR6890 120K1%R0402-0201<Part Number>PR6892 120K1%R0402-0201<Part Number>PC6160.22UFX7R16VC0402-0201<Part Number>PC62510UFX6S25VC0805_H61<Part Number>PR687220K1%R0402-0201<Part Number>PR686920K1%R0402-0201<Part Number>
PC637560PFX7R50VC0402-0201<Part Number>
PD77SMBJ14A<Part Number>AC
PR6898 10K1%R0402-0201<Part Number>PR6893 10K1%R0402-0201<Part Number>
R905 100K1% R0402-0201<Part Number>
NI PD10B340A-13-F<Part Number>ACPR687614.7K1%R0402-0201<Part Number>PR6868 120K1%R0402-0201<Part Number>C839 0.01UFX7R 25VC0402-0201<Part Number>NI
R5831 05%1/16WR0402-0201PC60210UFX6S25VC0805_H61<Part Number>PD82B340A-13-F<Part Number>AC PR6891 49.91%R0603<Part Number>PR6874 10K1%R0402-0201<Part Number>PC60510UFX6S25VC0805_H61<Part Number>PC610 2.2UFX7R 16VC0603_H40<Part Number>PR6862 71.5K1%R0402-0201<Part Number>
NI
PC6200.1UFX7R25VC0402-0201<Part Number>
R903 05% R0402-0201<Part Number>PU72RS31312R<Part Number>VOUT_2020VIN_21_2221_22VOUT_1919VOUT_1818VOUT_1717VOUT_1616VOUT_1515VOUT_1414AVIN12VOUT_1313OV11PG10FLTB9IMON8VIN_2323VIN_2424VIN_2525VIN_2626EN1LOADEN2ENTM3TIMER4ISET5SS6GND7PC611 2.2UFX7R 16VC0603_H40<Part Number>PC34510UFX6S25VC0805_H61<Part Number>PC615560PFX7R50VC0402-0201<Part Number>PR6870 10K1%R0402-0201<Part Number>PC6270.1UFX7R25VC0402-0201<Part Number>PU74RS31312R<Part Number>VOUT_2020VIN_21_2221_22VOUT_1919VOUT_1818VOUT_1717VOUT_1616VOUT_1515VOUT_1414AVIN12VOUT_1313OV11PG10FLTB9IMON8VIN_2323VIN_2424VIN_2525VIN_2626EN1LOADEN2ENTM3TIMER4ISET5SS6GND7PC617560PFX7R50VC0402-0201<Part Number>C841 0.01UFX7R 25VC0402-0201<Part Number>NI
PU73RS31312R<Part Number>VOUT_2020VIN_21_2221_22VOUT_1919VOUT_1818VOUT_1717VOUT_1616VOUT_1515VOUT_1414AVIN12VOUT_1313OV11PG10FLTB9IMON8VIN_2323VIN_2424VIN_2525VIN_2626EN1LOADEN2ENTM3TIMER4ISET5SS6GND7 PC6130.022UFX7R25VC0402-0201<Part Number>R5832 05%1/16WR0402-0201PR6871 10K1%R0402-0201<Part Number>R948 100K1% R0402-0201<Part Number>
NI
PD18B340A-13-F<Part Number>ACPR68851001%R0402-0201<Part Number>
NI
PC62210UFX6S25VC0805_H61<Part Number>PR687514.7K1%R0402-0201<Part Number>PC635560PFX7R50VC0402-0201<Part Number>
R944 100K1% R0402-0201<Part Number>
NI
R94710K1%R0402-0201<Part Number>PR6896 10K1%R0402-0201<Part Number>PC6191UFX6S25VC0402-0201<Part Number>PC6330.022UFX7R25VC0402-0201<Part Number>
PC60110UFX6S25VC0805_H61<Part Number>PD78B340A-13-F<Part Number>ACPD76SMBJ14A<Part Number>AC
R950 100K1% R0402-0201<Part Number>
NI
PR68611001%R0402-0201<Part Number>
NI
PR6873 10K1%R0402-0201<Part Number>PC6120.022UFX7R25VC0402-0201<Part Number>PC62410UFX6S25VC0805_H61<Part Number>PD81SMBJ14A<Part Number>AC C840 0.01UFX7R 25VC0402-0201<Part Number>
NI
PC60410UFX6S25VC0805_H61<Part Number>PC6181UFX6S25VC0402-0201<Part Number>PD80SMBJ14A<Part Number>ACPR6864 71.5K1%R0402-0201<Part Number>
NI
PR690110K1%R0402-0201<Part Number>PR6889 49.91%R0603<Part Number>
R906 05% R0402-0201<Part Number>
PR68871001%R0402-0201<Part Number>
NI
PC6340.22UFX7R16VC0402-0201<Part Number>PR6894 10K1%R0402-0201<Part Number>
PR6865 49.91%R0603<Part Number>R90410K1%R0402-0201<Part Number>PC60010UFX6S25VC0805_H61<Part Number>R90210K1%R0402-0201<Part Number>PR687810K1%R0402-0201<Part Number>PC5981UFX6S25VC0402-0201<Part Number>PR6866 120K1%R0402-0201<Part Number>
PR689520K1%R0402-0201<Part Number>PC62110UFX6S25VC0805_H61<Part Number>PC6360.22UFX7R16VC0402-0201<Part Number>
PR687710K1%R0402-0201<Part Number>PC6030.1UFX7R25VC0402-0201<Part Number>
PR689914.7K1%R0402-0201<Part Number>PC62310UFX6S25VC0805_H61<Part Number>PR689720K1%R0402-0201<Part Number>
PC6070.1UFX7R25VC0402-0201<Part Number>PU71RS31312R<Part Number>VOUT_2020VIN_21_2221_22VOUT_1919VOUT_1818VOUT_1717VOUT_1616VOUT_1515VOUT_1414AVIN12VOUT_1313OV11PG10FLTB9IMON8VIN_2323VIN_2424VIN_2525VIN_2626EN1LOADEN2ENTM3TIMER4ISET5SS6GND7
PR690014.7K1%R0402-0201<Part Number>R949 05% R0402-0201<Part Number>PC631 2.2UFX7R 16VC0603_H40<Part Number>
PR68631001%R0402-0201<Part Number>
NI
C842 0.01UFX7R 25VC0402-0201<Part Number>NI
PR690210K1%R0402-0201<Part Number>PC630 2.2UFX7R 16VC0603_H40<Part Number>PC6140.22UFX7R16VC0402-0201<Part Number>R94510K1%R0402-0201<Part Number>PC60610UFX6S25VC0805_H61<Part Number>PWRGD_P12V_NIC0_COP12V_NIC0_CO_ENP12V_NIC0_CO_AVIN_PDP12V_NIC0_CO_TIMERP12V_NIC0_CO_OV_FBP12V_NIC0_CO_ISETP12V_NIC0_CO_SSP12V_NIC0_CO_FLTBP12V_NIC0_CO_IMON_VRPWRGD_P12V_NIC1_COP12V_NIC1_CO_ENP12V_NIC1_CO_AVIN_PDP12V_NIC1_CO_TIMERP12V_NIC1_CO_OV_FBP12V_NIC1_CO_ISETP12V_NIC1_CO_SSP12V_NIC1_CO_FLTBP12V_NIC1_CO_IMON_VRPWRGD_P12V_NIC2_COPWRGD_P12V_NIC3_COP12V_NIC2_CO_ENP12V_NIC3_CO_ENP12V_NIC2_CO_AVIN_PDP12V_NIC3_CO_AVIN_PDP12V_NIC2_CO_TIMERP12V_NIC3_CO_TIMERP12V_NIC2_CO_OV_FBP12V_NIC3_CO_OV_FBP12V_NIC2_CO_ISETP12V_NIC3_CO_ISETP12V_NIC2_CO_SSP12V_NIC2_CO_FLTBP12V_NIC3_CO_SSP12V_NIC3_CO_FLTBP12V_NIC2_CO_IMON_VRP12V_NIC3_CO_IMON_VRP12V_NIC0_CO_ISET_RP12V_NIC1_CO_ISET_RP12V_NIC2_CO_ISET_RP12V_NIC3_CO_ISET_R



5
5
4
4
3
3
2
2
1
1
D D
C C
B B
A A
P12V_NICx E-fuseIout_max=6.6ACurrent limit=8.8ASoft-Start time=2.77msEnable Vth > 1.391V (High)
Current limit =8.8A
OV:15.6V 16.12V 16.64V
Design specification
Soft start time=2.75ms
tdelay: 6.29mstfault: 1.27ms
Enable:Vth>1.391V(high)
tdelay: 6.29mstfault: 1.27msCurrent limit =8.8A
Enable:Vth>1.391V(high)
OV:15.6V 16.12V 16.64V
Soft start time=2.75ms
Enable:Vth>1.391V(high)
OV:15.6V 16.12V 16.64V
Current limit =8.8Atdelay: 6.29mstfault: 1.27ms
Soft start time=2.75ms
Current limit =8.8A
Enable:Vth>1.391V(high)
OV:15.6V 16.12V 16.64V
tdelay: 6.29mstfault: 1.27ms
Soft start time=2.75ms
PU103 optional BOM
PR7024=120K
MP5025C/
MP5022C
Pop
PR7023=49.9
Pop De-pop
De-pop
PR7021=71.5K
PR7020=100 Pop
De-pop
PC810=2.2uF
De-pop
Pop
De-pop
Pop
MP5025A/
MP5022A PU104 optional BOM
PR7031=120K
MP5025C/
MP5022C
Pop
PR6867=49.9
Pop De-pop
De-pop
PR7030=71.5K
PR7025=100 Pop
De-pop
PC812=2.2uF
De-pop
Pop
De-pop
Pop
MP5025A/
MP5022A
PU105 optional BOM
PR7048=120K
MP5025C/
MP5022C
Pop
PR7047=49.9
Pop De-pop
De-pop
PR7045=71.5K
PR7044=100 Pop
De-pop
PC830=2.2uF
De-pop
Pop
De-pop
Pop
MP5025A/
MP5022A PU106 optional BOM
PR7055=120K
MP5025C/
MP5022C
Pop
PR7054=49.9
Pop De-pop
De-pop
PR7050=71.5K
PR7049=100 Pop
De-pop
PC832=2.2uF
De-pop
Pop
De-pop
Pop
MP5025A/
MP5022A
P12V_NICx_MP5025C_Colay_2
PWRGD_P12V_NIC4_R [116,182,235]PWRGD_P12V_NIC5_R [116,185,235]HP_NIC4_EN[182,235,238,249]HP_NIC5_EN[185,235,238,249]PWRGD_P12V_NIC6_R [116,188,235]PWRGD_P12V_NIC7_R [116,191,235]HP_NIC6_EN[188,235,238,249]HP_NIC7_EN[191,235,238,249]
P12V_AUXP3V3_AUXP12V_AUXP12V_NIC4_RP3V3_AUXP12V_NIC5_RP12V_AUXP12V_AUXP3V3_AUXP3V3_AUXP12V_AUXP3V3_AUXP12V_AUXP12V_NIC6_RP3V3_AUXP12V_NIC7_RP12V_AUXP3V3_AUXP12V_AUXP3V3_AUXSizeDoc NumberRevDate: SheetofReviewerDesignerDepartmentProject
Page TitleCCBU 11243 257Tuesday, August 29, 2023<project_name><Designer> GRANDTETON_SWB_20230829243 P12V_NICx_MP5025C_Colay_2<Reviewer>SizeDoc NumberRevDate: SheetofReviewerDesignerDepartmentProject
Page TitleCCBU 11243 257Tuesday, August 29, 2023<project_name><Designer> GRANDTETON_SWB_20230829243 P12V_NICx_MP5025C_Colay_2<Reviewer>SizeDoc NumberRevDate: SheetofReviewerDesignerDepartmentProject
Page TitleCCBU 11243 257Tuesday, August 29, 2023<project_name><Designer> GRANDTETON_SWB_20230829243 P12V_NICx_MP5025C_Colay_2<Reviewer>PC8211UFX6S25VC0402-0201<Part Number>PR70441001%R0402-0201<Part Number>
NI
PC8330.22UFX7R16VC0402-0201<Part Number>PR706020K1%R0402-0201<Part Number>PD5SMBJ14A<Part Number>AC PC817560PFX7R50VC0402-0201<Part Number>PC832 2.2UFX7R 16VC0603_H40<Part Number>
PR702720K1%R0402-0201<Part Number>PD15B340A-13-F<Part Number>ACPC80210UFX6S25VC0805_H61<Part Number>PC8130.22UFX7R16VC0402-0201<Part Number>PR703420K1%R0402-0201<Part Number>PD99B340A-13-F<Part Number>ACPR7030 49.91%R0603<Part Number>PC8030.1UFX7R25VC0402-0201<Part Number>
PC8360.22UFX7R16VC0402-0201<Part Number>
C843 0.01UFX7R 25VC0402-0201<Part Number>NI R955 05% R0402-0201<Part Number>PR7023 49.91%R0603<Part Number>
PR706114.7K1%R0402-0201<Part Number>PR7045 71.5K1%R0402-0201<Part Number>NI
PU105RS31312R<Part Number>VOUT_2020VIN_21_2221_22VOUT_1919VOUT_1818VOUT_1717VOUT_1616VOUT_1515VOUT_1414AVIN12VOUT_1313OV11PG10FLTB9IMON8VIN_2323VIN_2424VIN_2525VIN_2626EN1LOADEN2ENTM3TIMER4ISET5SS6GND7
PD95B340A-13-F<Part Number>ACPC80410UFX6S25VC0805_H61<Part Number>
C982 0.01UFX7R 25VC0402-0201<Part Number>NIPC8200.1UFX7R25VC0402-0201<Part Number>PC834560PFX7R50VC0402-0201<Part Number>R5969 05%1/16WR0402-0201PR7036 10K1%R0402-0201<Part Number>R5968 05%1/16WR0402-0201PR7059 10K1%R0402-0201<Part Number>PR703810K1%R0402-0201<Part Number>PC80010UFX6S25VC0805_H61<Part Number>
PC8310.022UFX7R25VC0402-0201<Part Number>
PR70251001%R0402-0201<Part Number>
NI
PR706210K1%R0402-0201<Part Number>
PR7026 71.5K1%R0402-0201<Part Number>NI
PR705120K1%R0402-0201<Part Number>PR7054 49.91%R0603<Part Number>R960 100K1% R0402-0201<Part Number>NIPC82210UFX6S25VC0805_H61<Part Number>PC8270.1UFX7R25VC0402-0201<Part Number>PR705710K1%R0402-0201<Part Number>
PC8150.22UFX7R16VC0402-0201<Part Number>PD94B340A-13-F<Part Number>AC R95310K1%R0402-0201<Part Number>R95910K1%R0402-0201<Part Number>
PC80510UFX6S25VC0805_H61<Part Number>
PR7047 49.91%R0603<Part Number>PR7029 10K1%R0402-0201<Part Number>PD97SMBJ14A<Part Number>ACPC8181UFX6S25VC0402-0201<Part Number>R958 05% R0402-0201<Part Number>PC32310UFX6S25VC0805_H61<Part Number>
PC8350.022UFX7R25VC0402-0201<Part Number>PD17SMBJ14A<Part Number>ACPR7053 10K1%R0402-0201<Part Number>C981 0.01UFX7R 25VC0402-0201<Part Number>NI PR7031 120K1%R0402-0201<Part Number>PC7981UFX6S25VC0402-0201<Part Number>PR703714.7K1%R0402-0201<Part Number>PC830 2.2UFX7R 16VC0603_H40<Part Number>PC34710UFX6S25VC0805_H61<Part Number>PR705614.7K1%R0402-0201<Part Number>
PR7028 10K1%R0402-0201<Part Number>PC82310UFX6S25VC0805_H61<Part Number>R95710K1%R0402-0201<Part Number>
PC80110UFX6S25VC0805_H61<Part Number>
PC82410UFX6S25VC0805_H61<Part Number>PC837560PFX7R50VC0402-0201<Part Number>
PC812 2.2UFX7R 16VC0603_H40<Part Number>PC8160.022UFX7R25VC0402-0201<Part Number>PR703214.7K1%R0402-0201<Part Number>R952 05% R0402-0201<Part Number>
PR7055 120K1%R0402-0201<Part Number>
PC8070.1UFX7R25VC0402-0201<Part Number>
PR70491001%R0402-0201<Part Number>
NI
PR70201001%R0402-0201<Part Number>
NI
PR7048 120K1%R0402-0201<Part Number>R961 05% R0402-0201<Part Number>
PD93SMBJ14A<Part Number>AC PU104RS31312R<Part Number>VOUT_2020VIN_21_2221_22VOUT_1919VOUT_1818VOUT_1717VOUT_1616VOUT_1515VOUT_1414AVIN12VOUT_1313OV11PG10FLTB9IMON8VIN_2323VIN_2424VIN_2525VIN_2626EN1LOADEN2ENTM3TIMER4ISET5SS6GND7R5966 05%1/16WR0402-0201PU103RS31312R<Part Number>VOUT_2020VIN_21_2221_22VOUT_1919VOUT_1818VOUT_1717VOUT_1616VOUT_1515VOUT_1414AVIN12VOUT_1313OV11PG10FLTB9IMON8VIN_2323VIN_2424VIN_2525VIN_2626EN1LOADEN2ENTM3TIMER4ISET5SS6GND7R95110K1%R0402-0201<Part Number>
R962 100K1% R0402-0201<Part Number>NIC844 0.01UFX7R 25VC0402-0201<Part Number>NIPC33510UFX6S25VC0805_H61<Part Number>PU106RS31312R<Part Number>VOUT_2020VIN_21_2221_22VOUT_1919VOUT_1818VOUT_1717VOUT_1616VOUT_1515VOUT_1414AVIN12VOUT_1313OV11PG10FLTB9IMON8VIN_2323VIN_2424VIN_2525VIN_2626EN1LOADEN2ENTM3TIMER4ISET5SS6GND7
PC7991UFX6S25VC0402-0201<Part Number>PC814560PFX7R50VC0402-0201<Part Number>PR7052 10K1%R0402-0201<Part Number>PR7050 71.5K1%R0402-0201<Part Number>NI
PR7024 120K1%R0402-0201<Part Number>PC810 2.2UFX7R 16VC0603_H40<Part Number>R5967 05%1/16WR0402-0201PR7035 10K1%R0402-0201<Part Number>R956 100K1% R0402-0201<Part Number>NIPR7021 71.5K1%R0402-0201<Part Number>NI
R954 100K1% R0402-0201<Part Number>NI
PC82610UFX6S25VC0805_H61<Part Number>PC8110.022UFX7R25VC0402-0201<Part Number>PR7058 10K1%R0402-0201<Part Number>
PR703310K1%R0402-0201<Part Number>PWRGD_P12V_NIC4_COPWRGD_P12V_NIC5_COP12V_NIC4_CO_ENP12V_NIC4_CO_AVIN_PDP12V_NIC5_CO_ENP12V_NIC4_CO_TIMERP12V_NIC4_CO_OV_FBP12V_NIC4_CO_ISETP12V_NIC4_CO_SSP12V_NIC4_CO_FLTBP12V_NIC5_CO_AVIN_PDP12V_NIC5_CO_TIMERP12V_NIC4_CO_IMON_VRP12V_NIC5_CO_OV_FBP12V_NIC5_CO_ISETP12V_NIC5_CO_SSP12V_NIC5_CO_FLTBP12V_NIC5_CO_IMON_VRPWRGD_P12V_NIC6_COPWRGD_P12V_NIC7_COP12V_NIC6_CO_ENP12V_NIC6_CO_AVIN_PDP12V_NIC6_CO_TIMERP12V_NIC7_CO_ENP12V_NIC6_CO_OV_FBP12V_NIC6_CO_ISETP12V_NIC6_CO_SSP12V_NIC6_CO_FLTBP12V_NIC7_CO_AVIN_PDP12V_NIC6_CO_IMON_VRP12V_NIC7_CO_TIMERP12V_NIC7_CO_OV_FBP12V_NIC7_CO_ISETP12V_NIC7_CO_SSP12V_NIC7_CO_FLTBP12V_NIC7_CO_IMON_VRP12V_NIC4_CO_ISET_RP12V_NIC5_CO_ISET_RP12V_NIC6_CO_ISET_RP12V_NIC7_CO_ISET_R



5
5
4
4
3
3
2
2
1
1
D D
C C
B B
A A
P12V_SSD E-fuseIout_max=2.083ACurrent limit=2.58ASoft-Start time=2.77msEnable Vth > 2V (High)
Design specification
Vclamp13.46V OCP2.58A
t_SS2.77ms
Vclamp13.46V
t_SS2.77ms
OCP2.58A
t_SS2.77ms
Vclamp13.46V OCP2.58A Vclamp13.46V OCP2.58A
t_SS2.77ms
P12V_SSDx_MP5016_Colay_1
SSD0_PWR_EN_R[115,117,236]PWRGD_P12V_SSD0_R [115,236]SSD1_PWR_EN_R[115,117,236]PWRGD_P12V_SSD1_R [115,236]SSD2_PWR_EN_R[115,117,236]PWRGD_P12V_SSD2_R [115,236]SSD3_PWR_EN_R[115,117,236]PWRGD_P12V_SSD3_R [115,236]
P12V_AUXP12V_SSD0_RP3V3_AUXP5V_AUXP12V_SSD0_RP12V_AUXP12V_SSD1_RP3V3_AUXP5V_AUXP12V_SSD1_RP12V_AUXP12V_SSD2_RP3V3_AUXP5V_AUXP12V_SSD2_RP12V_AUXP12V_SSD3_RP3V3_AUXP5V_AUXP12V_SSD3_RSizeDoc NumberRevDate: SheetofReviewerDesignerDepartmentProject
Page TitleCCBU 11244 257Tuesday, August 29, 2023<project_name><Designer> GRANDTETON_SWB_20230829244 P12V_SSDx_MP5016_Colay_1<Reviewer>SizeDoc NumberRevDate: SheetofReviewerDesignerDepartmentProject
Page TitleCCBU 11244 257Tuesday, August 29, 2023<project_name><Designer> GRANDTETON_SWB_20230829244 P12V_SSDx_MP5016_Colay_1<Reviewer>SizeDoc NumberRevDate: SheetofReviewerDesignerDepartmentProject
Page TitleCCBU 11244 257Tuesday, August 29, 2023<project_name><Designer> GRANDTETON_SWB_20230829244 P12V_SSDx_MP5016_Colay_1<Reviewer>PR69128251%R0402-0201<Part Number>PC654100PFX7R50VC0402-0201<Part Number>Q130ABSS138BKS<Part Number>S11G12D16
PC6460.01UFX7RC0402-020150V<Part Number>Q128BBSS138BKS<Part Number>D23G25S24PC36910UFX6S25VC0805_H61<Part Number>PC64139PF<Part Number>C0402-020150VNPO
R585264.9K1%R0402-0201<Part Number>
PC642100PFX7R50VC0402-0201<Part Number>PU78MP5016GQH-L-Z<Part Number>EN9MODE5ILIMIT4GND3VCC1_2DV_DT10GATE8SOURCE6_7PC64310UFX6S25VC0805_H61<Part Number>R583710K1%R0402-0201<Part Number>
PR691310K1%R0402-0201<Part Number>R584710K1%R0402-0201<Part Number>PC6481UF25VC0402-0201<Part Number>X6SR5834 0R0402-02015%1/16WPD87B340A-13-F<Part Number>AC
Q129ABSS138BKS<Part Number>S11G12D16 PU77MP5016GQH-L-Z<Part Number>EN9MODE5ILIMIT4GND3VCC1_2DV_DT10GATE8SOURCE6_7R5849 0R0402-02015%1/16W
PC640100PFX7R50VC0402-0201<Part Number>R584264.9K1%R0402-0201<Part Number>PD89SMBJ14A<Part Number>ACPR69108251%R0402-0201<Part Number>PC65510UFX6S25VC0805_H61<Part Number>
PD86B340A-13-F<Part Number>AC
R5848 0R0402-02015%1/16WR584364.9K1%R0402-0201<Part Number>PC6391UF25VC0402-0201<Part Number>X6S
R585364.9K1%R0402-0201<Part Number>PD91B340A-13-F<Part Number>ACPR690710K1%R0402-0201<Part Number>R584610K1%R0402-0201<Part Number>R585010K1%R0402-0201<Part Number>
R5835 0R0402-02015%1/16W
PC38110UFX6S25VC0805_H61<Part Number>
PU75MP5016GQH-L-Z<Part Number>EN9MODE5ILIMIT4GND3VCC1_2DV_DT10GATE8SOURCE6_7PD85SMBJ14A<Part Number>AC R585110K1%R0402-0201<Part Number>PC6381UF25VC0402-0201<Part Number>X6SPC6570.01UFX7RC0402-020150V<Part Number>R5844 0R0402-02015%1/16WQ127BBSS138BKS<Part Number>D23G25S24PR69058251%R0402-0201<Part Number>PC65339PF<Part Number>C0402-020150VNPOR584110K1%R0402-0201<Part Number>PU76MP5016GQH-L-Z<Part Number>EN9MODE5ILIMIT4GND3VCC1_2DV_DT10GATE8SOURCE6_7
PC65139PF<Part Number>C0402-020150VNPOPR690810K1%R0402-0201<Part Number>PC6470.01UFX7RC0402-020150V<Part Number>R5845 0R0402-02015%1/16WQ128ABSS138BKS<Part Number>S11G12D16PR6909280K<Part Number>R0402-02011%
PR69068251%R0402-0201<Part Number>PR6911280K<Part Number>R0402-02011%
PR6903280K<Part Number>R0402-02011%PC652100PFX7R50VC0402-0201<Part Number>
PC64439PF<Part Number>C0402-020150VNPOR5839 0R0402-02015%1/16W
Q129BBSS138BKS<Part Number>D23G25S24PC6560.01UFX7RC0402-020150V<Part Number>Q127ABSS138BKS<Part Number>S11G12D16PD84SMBJ14A<Part Number>AC
Q130BBSS138BKS<Part Number>D23G25S24PR691410K1%R0402-0201<Part Number>
PR6904280K<Part Number>R0402-02011%PD88SMBJ14A<Part Number>ACR5838 0R0402-02015%1/16WPD90B340A-13-F<Part Number>ACR584010K1%R0402-0201<Part Number>R583610K1%R0402-0201<Part Number>PC6491UF25VC0402-0201<Part Number>X6SP12V_SSD0_CO_ENP12V_SSD0_CO_MODEP12V_SSD0_CO_GATEP12V_SSD0_CO_ILIMITP12V_SSD0_CO_DV_DTPWRGD_P12V_SSD0_DPWRGD_P12V_SSD0_RP12V_SSD0_PG_G2P12V_SSD0_PG_G1P12V_SSD1_CO_ENP12V_SSD1_CO_MODEP12V_SSD1_CO_GATEP12V_SSD1_CO_ILIMITP12V_SSD1_CO_DV_DTPWRGD_P12V_SSD1_DPWRGD_P12V_SSD1_RP12V_SSD1_PG_G2P12V_SSD1_PG_G1P12V_SSD2_CO_ENP12V_SSD2_CO_MODEP12V_SSD2_CO_GATEP12V_SSD2_CO_ILIMITP12V_SSD2_CO_DV_DTPWRGD_P12V_SSD2_DPWRGD_P12V_SSD2_RP12V_SSD2_PG_G2P12V_SSD2_PG_G1P12V_SSD3_CO_ENP12V_SSD3_CO_MODEP12V_SSD3_CO_GATEP12V_SSD3_CO_ILIMITP12V_SSD3_CO_DV_DTPWRGD_P12V_SSD3_DPWRGD_P12V_SSD3_RP12V_SSD3_PG_G2P12V_SSD3_PG_G1



5
5
4
4
3
3
2
2
1
1
D D
C C
B B
A A
P12V_SSD E-fuseIout_max=2.083ACurrent limit=2.58ASoft-Start time=2.77msEnable Vth > 2V (High)
Design specification
Vclamp13.46V
Vclamp13.46V OCP2.58A
t_SS2.77ms
t_SS2.77ms
Vclamp13.46V OCP2.58A
t_SS2.77ms
OCP2.58A
Vclamp13.46V OCP2.58A
t_SS2.77ms
P12V_SSDx_MP5016_Colay_2
SSD4_PWR_EN_R[115,117,236]SSD5_PWR_EN_R[115,117,236]PWRGD_P12V_SSD4_R [115,236]PWRGD_P12V_SSD5_R [115,236]SSD6_PWR_EN_R[115,117,236]SSD7_PWR_EN_R[115,117,236]PWRGD_P12V_SSD6_R [115,236]PWRGD_P12V_SSD7_R [115,236]
P12V_AUXP12V_AUXP12V_SSD4_RP12V_SSD5_RP3V3_AUXP3V3_AUXP5V_AUXP5V_AUXP12V_SSD4_RP12V_SSD5_RP12V_AUXP12V_AUXP12V_SSD6_RP12V_SSD7_RP3V3_AUXP3V3_AUXP5V_AUXP5V_AUXP12V_SSD6_RP12V_SSD7_RSizeDoc NumberRevDate: SheetofReviewerDesignerDepartmentProject
Page TitleCCBU 11245 257Tuesday, August 29, 2023<project_name><Designer> GRANDTETON_SWB_20230829245 P12V_SSDx_MP5016_Colay_2<Reviewer>SizeDoc NumberRevDate: SheetofReviewerDesignerDepartmentProject
Page TitleCCBU 11245 257Tuesday, August 29, 2023<project_name><Designer> GRANDTETON_SWB_20230829245 P12V_SSDx_MP5016_Colay_2<Reviewer>SizeDoc NumberRevDate: SheetofReviewerDesignerDepartmentProject
Page TitleCCBU 11245 257Tuesday, August 29, 2023<project_name><Designer> GRANDTETON_SWB_20230829245 P12V_SSDx_MP5016_Colay_2<Reviewer>
PC84110UFX6S25VC0805_H61<Part Number>PC8500.01UFX7RC0402-020150V<Part Number>
PD102B340A-13-F<Part Number>ACPC8491UF25VC0402-0201<Part Number>X6SPU110MP5016GQH-L-Z<Part Number>EN9MODE5ILIMIT4GND3VCC1_2DV_DT10GATE8SOURCE6_7PR7065280K<Part Number>R0402-02011%Q201ABSS138BKS<Part Number>S11G12D16PD105SMBJ14A<Part Number>AC R5975 0R0402-02015%1/16WR597964.9K1%R0402-0201<Part Number>PC8460.01UFX7RC0402-020150V<Part Number>PD35B340A-13-F<Part Number>AC
PC8391UF25VC0402-0201<Part Number>X6S
PC853100PFX7R50VC0402-0201<Part Number>PR70718251%R0402-0201<Part Number>R597310K1%R0402-0201<Part Number>
R598710K1%R0402-0201<Part Number>
R597864.9K1%R0402-0201<Part Number>PC8570.01UFX7RC0402-020150V<Part Number>PR7070280K<Part Number>R0402-02011%R598610K1%R0402-0201<Part Number>PC39510UFX6S25VC0805_H61<Part Number>R597610K1%R0402-0201<Part Number>PD106B340A-13-F<Part Number>ACQ201BBSS138BKS<Part Number>D23G25S24R5980 0R0402-02015%1/16W
PU108MP5016GQH-L-Z<Part Number>EN9MODE5ILIMIT4GND3VCC1_2DV_DT10GATE8SOURCE6_7R597210K1%R0402-0201<Part Number>R5971 0R0402-02015%1/16WPD101SMBJ14A<Part Number>AC
R5985 0R0402-02015%1/16W
PR70648251%R0402-0201<Part Number>
Q203BBSS138BKS<Part Number>D23G25S24
PR7063280K<Part Number>R0402-02011%PU109MP5016GQH-L-Z<Part Number>EN9MODE5ILIMIT4GND3VCC1_2DV_DT10GATE8SOURCE6_7R5974 0R0402-02015%1/16WPU107MP5016GQH-L-Z<Part Number>EN9MODE5ILIMIT4GND3VCC1_2DV_DT10GATE8SOURCE6_7Q200BBSS138BKS<Part Number>D23G25S24
PR707310K1%R0402-0201<Part Number>
Q200ABSS138BKS<Part Number>S11G12D16PC84539PF<Part Number>C0402-020150VNPO
PC85539PF<Part Number>C0402-020150VNPOPR70728251%R0402-0201<Part Number>PR707410K1%R0402-0201<Part Number>
PR70668251%R0402-0201<Part Number>
Q202BBSS138BKS<Part Number>D23G25S24 R5981 0R0402-02015%1/16WPC840100PFX7R50VC0402-0201<Part Number>PC85410UFX6S25VC0805_H61<Part Number>Q203ABSS138BKS<Part Number>S11G12D16
PC84239PF<Part Number>C0402-020150VNPO
R598210K1%R0402-0201<Part Number>PC85239PF<Part Number>C0402-020150VNPOPR706710K1%R0402-0201<Part Number>PD103B340A-13-F<Part Number>ACPD100SMBJ14A<Part Number>AC
PC8481UF25VC0402-0201<Part Number>X6S
PC851100PFX7R50VC0402-0201<Part Number>
PC8470.01UFX7RC0402-020150V<Part Number>
R598310K1%R0402-0201<Part Number>PR706810K1%R0402-0201<Part Number>PC84410UFX6S25VC0805_H61<Part Number>
R5984 0R0402-02015%1/16WR598864.9K1%R0402-0201<Part Number>
PC843100PFX7R50VC0402-0201<Part Number>
R598964.9K1%R0402-0201<Part Number>PC8381UF25VC0402-0201<Part Number>X6SPD104SMBJ14A<Part Number>ACPR7069280K<Part Number>R0402-02011%R597710K1%R0402-0201<Part Number>
Q202ABSS138BKS<Part Number>S11G12D16
R5970 0R0402-02015%1/16WP12V_SSD4_CO_ENP12V_SSD5_CO_ENP12V_SSD4_CO_MODEP12V_SSD4_CO_GATEP12V_SSD5_CO_MODEP12V_SSD5_CO_GATEP12V_SSD4_CO_ILIMITP12V_SSD5_CO_ILIMITP12V_SSD4_CO_DV_DTP12V_SSD5_CO_DV_DTPWRGD_P12V_SSD4_DPWRGD_P12V_SSD4_RPWRGD_P12V_SSD5_DPWRGD_P12V_SSD5_RP12V_SSD4_PG_G2P12V_SSD5_PG_G2P12V_SSD4_PG_G1P12V_SSD5_PG_G1P12V_SSD6_CO_ENP12V_SSD7_CO_ENP12V_SSD6_CO_MODEP12V_SSD6_CO_GATEP12V_SSD7_CO_MODEP12V_SSD7_CO_GATEP12V_SSD6_CO_ILIMITP12V_SSD7_CO_ILIMITP12V_SSD6_CO_DV_DTP12V_SSD7_CO_DV_DTPWRGD_P12V_SSD6_DPWRGD_P12V_SSD6_RPWRGD_P12V_SSD7_DPWRGD_P12V_SSD7_RP12V_SSD6_PG_G2P12V_SSD7_PG_G2P12V_SSD6_PG_G1P12V_SSD7_PG_G1



5
5
4
4
3
3
2
2
1
1
D D
C C
B B
A A
P12V_SSD E-fuseIout_max=2.083ACurrent limit=2.58ASoft-Start time=2.77msEnable Vth > 2V (High)
Design specification
Vclamp13.46V
Vclamp13.46V OCP2.58A
t_SS2.77ms
t_SS2.77ms
Vclamp13.46V OCP2.58A
t_SS2.77ms
OCP2.58A
Vclamp13.46V OCP2.58A
t_SS2.77ms
P12V_SSDx_MP5016_Colay_3
SSD8_PWR_EN_R[117,237]SSD9_PWR_EN_R[117,237]PWRGD_P12V_SSD8_R [117,237]PWRGD_P12V_SSD9_R [117,237]SSD10_PWR_EN_R[117,237]SSD11_PWR_EN_R[117,237]PWRGD_P12V_SSD10_R [117,237]PWRGD_P12V_SSD11_R [117,237]
P12V_AUXP12V_AUXP12V_SSD8_RP12V_SSD9_RP3V3_AUXP3V3_AUXP5V_AUXP5V_AUXP12V_SSD8_RP12V_SSD9_RP12V_AUXP12V_AUXP12V_SSD10_RP12V_SSD11_RP3V3_AUXP3V3_AUXP5V_AUXP5V_AUXP12V_SSD10_RP12V_SSD11_RSizeDoc NumberRevDate: SheetofReviewerDesignerDepartmentProject
Page TitleCCBU 11246 257Tuesday, August 29, 2023<project_name><Designer> GRANDTETON_SWB_20230829246 P12V_SSDx_MP5016_Colay_3<Reviewer>SizeDoc NumberRevDate: SheetofReviewerDesignerDepartmentProject
Page TitleCCBU 11246 257Tuesday, August 29, 2023<project_name><Designer> GRANDTETON_SWB_20230829246 P12V_SSDx_MP5016_Colay_3<Reviewer>SizeDoc NumberRevDate: SheetofReviewerDesignerDepartmentProject
Page TitleCCBU 11246 257Tuesday, August 29, 2023<project_name><Designer> GRANDTETON_SWB_20230829246 P12V_SSDx_MP5016_Colay_3<Reviewer>
PD36SMBJ14A<Part Number>AC PC863100PFX7R50VC0402-0201<Part Number>PC8770.01UFX7RC0402-020150V<Part Number>Q205BBSS138BKS<Part Number>D23G25S24PC8670.01UFX7RC0402-020150V<Part Number>PD110B340A-13-F<Part Number>ACPD112SMBJ14A<Part Number>ACPC40510UFX6S25VC0805_H61<Part Number>PD108SMBJ14A<Part Number>ACPR708510K1%R0402-0201<Part Number>PC875100PFX7R50VC0402-0201<Part Number>PU113MP5016GQH-L-Z<Part Number>EN9MODE5ILIMIT4GND3VCC1_2DV_DT10GATE8SOURCE6_7PD46B340A-13-F<Part Number>ACR600710K1%R0402-0201<Part Number>
PC86039PF<Part Number>C0402-020150VNPO
PR7083280K<Part Number>R0402-02011%
PC86410UFX6S25VC0805_H61<Part Number>PD38B340A-13-F<Part Number>ACR599964.9K1%R0402-0201<Part Number>PD109SMBJ14A<Part Number>ACR599610K1%R0402-0201<Part Number>R5995 0R0402-02015%1/16WPR7077280K<Part Number>R0402-02011%PC8660.01UFX7RC0402-020150V<Part Number>
R600310K1%R0402-0201<Part Number>PC8581UF25VC0402-0201<Part Number>X6SR599864.9K1%R0402-0201<Part Number>PR70768251%R0402-0201<Part Number>R599710K1%R0402-0201<Part Number>PD50B340A-13-F<Part Number>AC
PC8591UF25VC0402-0201<Part Number>X6SPU112MP5016GQH-L-Z<Part Number>EN9MODE5ILIMIT4GND3VCC1_2DV_DT10GATE8SOURCE6_7R5994 0R0402-02015%1/16WPC871100PFX7R50VC0402-0201<Part Number>R600610K1%R0402-0201<Part Number>R6001 0R0402-02015%1/16WR6005 0R0402-02015%1/16WQ206ABSS138BKS<Part Number>S11G12D16 Q207ABSS138BKS<Part Number>S11G12D16Q205ABSS138BKS<Part Number>S11G12D16R6004 0R0402-02015%1/16W
R5991 0R0402-02015%1/16WPC86239PF<Part Number>C0402-020150VNPOR599310K1%R0402-0201<Part Number>PC8691UF25VC0402-0201<Part Number>X6S
PC42910UFX6S25VC0805_H61<Part Number>PR70848251%R0402-0201<Part Number>
PU111MP5016GQH-L-Z<Part Number>EN9MODE5ILIMIT4GND3VCC1_2DV_DT10GATE8SOURCE6_7
PC87610UFX6S25VC0805_H61<Part Number>Q207BBSS138BKS<Part Number>D23G25S24PR708610K1%R0402-0201<Part Number>
R5990 0R0402-02015%1/16WR599210K1%R0402-0201<Part Number>Q204BBSS138BKS<Part Number>D23G25S24PC87039PF<Part Number>C0402-020150VNPOPC8681UF25VC0402-0201<Part Number>X6SPR7075280K<Part Number>R0402-02011%
PR70828251%R0402-0201<Part Number>R600964.9K1%R0402-0201<Part Number>Q206BBSS138BKS<Part Number>D23G25S24PR707910K1%R0402-0201<Part Number>R6000 0R0402-02015%1/16WPR70788251%R0402-0201<Part Number>Q204ABSS138BKS<Part Number>S11G12D16PC8730.01UFX7RC0402-020150V<Part Number>
PC865100PFX7R50VC0402-0201<Part Number>PR7081280K<Part Number>R0402-02011%PR708010K1%R0402-0201<Part Number>PC87439PF<Part Number>C0402-020150VNPOPU114MP5016GQH-L-Z<Part Number>EN9MODE5ILIMIT4GND3VCC1_2DV_DT10GATE8SOURCE6_7R600210K1%R0402-0201<Part Number>R600864.9K1%R0402-0201<Part Number>
P12V_SSD8_CO_ENP12V_SSD9_CO_ENP12V_SSD8_CO_MODEP12V_SSD8_CO_GATEP12V_SSD9_CO_MODEP12V_SSD9_CO_GATEP12V_SSD8_CO_ILIMITP12V_SSD9_CO_ILIMITP12V_SSD8_CO_DV_DTP12V_SSD9_CO_DV_DTPWRGD_P12V_SSD8_DPWRGD_P12V_SSD8_RPWRGD_P12V_SSD9_DPWRGD_P12V_SSD9_RP12V_SSD8_PG_G2P12V_SSD9_PG_G2P12V_SSD8_PG_G1P12V_SSD9_PG_G1P12V_SSD10_CO_ENP12V_SSD11_CO_ENP12V_SSD10_CO_MODEP12V_SSD10_CO_GATEP12V_SSD11_CO_MODEP12V_SSD11_CO_GATEP12V_SSD10_CO_ILIMITP12V_SSD11_CO_ILIMITP12V_SSD10_CO_DV_DTP12V_SSD11_CO_DV_DTPWRGD_P12V_SSD10_DPWRGD_P12V_SSD10_RPWRGD_P12V_SSD11_DPWRGD_P12V_SSD11_RP12V_SSD10_PG_G2P12V_SSD11_PG_G2P12V_SSD10_PG_G1P12V_SSD11_PG_G1



5
5
4
4
3
3
2
2
1
1
D D
C C
B B
A A
P12V_SSD E-fuseIout_max=2.083ACurrent limit=2.58ASoft-Start time=2.77msEnable Vth > 2V (High)
Design specification
Vclamp13.46V
Vclamp13.46V OCP2.58A
t_SS2.77ms
t_SS2.77ms
Vclamp13.46V OCP2.58A
t_SS2.77ms
OCP2.58A
Vclamp13.46V OCP2.58A
t_SS2.77ms
P12V_SSDx_MP5016_Colay_4
SSD12_PWR_EN_R[117,237]SSD13_PWR_EN_R[117,237]PWRGD_P12V_SSD12_R [117,237]PWRGD_P12V_SSD13_R [117,237]SSD14_PWR_EN_R[117,237]SSD15_PWR_EN_R[117,237]PWRGD_P12V_SSD14_R [117,237]PWRGD_P12V_SSD15_R [117,237]
P12V_AUXP12V_AUXP12V_SSD12_RP12V_SSD13_RP3V3_AUXP3V3_AUXP5V_AUXP5V_AUXP12V_SSD12_RP12V_SSD13_RP12V_AUXP12V_AUXP12V_SSD14_RP12V_SSD15_RP3V3_AUXP3V3_AUXP5V_AUXP5V_AUXP12V_SSD14_RP12V_SSD15_RSizeDoc NumberRevDate: SheetofReviewerDesignerDepartmentProject
Page TitleCCBU 11247 257Tuesday, August 29, 2023<project_name><Designer> GRANDTETON_SWB_20230829247 P12V_SSDx_MP5016_Colay_4<Reviewer>SizeDoc NumberRevDate: SheetofReviewerDesignerDepartmentProject
Page TitleCCBU 11247 257Tuesday, August 29, 2023<project_name><Designer> GRANDTETON_SWB_20230829247 P12V_SSDx_MP5016_Colay_4<Reviewer>SizeDoc NumberRevDate: SheetofReviewerDesignerDepartmentProject
Page TitleCCBU 11247 257Tuesday, August 29, 2023<project_name><Designer> GRANDTETON_SWB_20230829247 P12V_SSDx_MP5016_Colay_4<Reviewer>PD37SMBJ14A<Part Number>AC R602310K1%R0402-0201<Part Number>
R6011 0R0402-02015%1/16WPR709110K1%R0402-0201<Part Number>R601310K1%R0402-0201<Part Number>PC8781UF25VC0402-0201<Part Number>X6SPD120SMBJ14A<Part Number>ACPC896100PFX7R50VC0402-0201<Part Number>PC8970.01UFX7RC0402-020150V<Part Number>R601864.9K1%R0402-0201<Part Number>R602610K1%R0402-0201<Part Number>
R601610K1%R0402-0201<Part Number>PC44310UFX6S25VC0805_H61<Part Number>Q209BBSS138BKS<Part Number>D23G25S24PD118B340A-13-F<Part Number>AC
Q210BBSS138BKS<Part Number>D23G25S24
PC88039PF<Part Number>C0402-020150VNPOR6014 0R0402-02015%1/16WPC8950.01UFX7RC0402-020150V<Part Number>
PR7087280K<Part Number>R0402-02011%
PR7093280K<Part Number>R0402-02011%
PC882100PFX7R50VC0402-0201<Part Number>Q208ABSS138BKS<Part Number>S11G12D16 PD117SMBJ14A<Part Number>ACPR70888251%R0402-0201<Part Number>PU117MP5016GQH-L-Z<Part Number>EN9MODE5ILIMIT4GND3VCC1_2DV_DT10GATE8SOURCE6_7R602864.9K1%R0402-0201<Part Number>PR70948251%R0402-0201<Part Number>
PD116SMBJ14A<Part Number>AC PR70908251%R0402-0201<Part Number>PR7095280K<Part Number>R0402-02011%
PC8891UF25VC0402-0201<Part Number>X6S
PU118MP5016GQH-L-Z<Part Number>EN9MODE5ILIMIT4GND3VCC1_2DV_DT10GATE8SOURCE6_7
PU115MP5016GQH-L-Z<Part Number>EN9MODE5ILIMIT4GND3VCC1_2DV_DT10GATE8SOURCE6_7PU116MP5016GQH-L-Z<Part Number>EN9MODE5ILIMIT4GND3VCC1_2DV_DT10GATE8SOURCE6_7
Q210ABSS138BKS<Part Number>S11G12D16
PC8840.01UFX7RC0402-020150V<Part Number>PC88310UFX6S25VC0805_H61<Part Number>
R602710K1%R0402-0201<Part Number>
R601964.9K1%R0402-0201<Part Number>R6010 0R0402-02015%1/16WR601210K1%R0402-0201<Part Number>PC8791UF25VC0402-0201<Part Number>X6SPD47B340A-13-F<Part Number>ACPC43110UFX6S25VC0805_H61<Part Number>Q209ABSS138BKS<Part Number>S11G12D16PR70968251%R0402-0201<Part Number>PC89339PF<Part Number>C0402-020150VNPO
PC881100PFX7R50VC0402-0201<Part Number>
R602210K1%R0402-0201<Part Number>PR709710K1%R0402-0201<Part Number>
PC88539PF<Part Number>C0402-020150VNPO
R602964.9K1%R0402-0201<Part Number>
PR7089280K<Part Number>R0402-02011%PC8881UF25VC0402-0201<Part Number>X6SR601710K1%R0402-0201<Part Number>PC89039PF<Part Number>C0402-020150VNPOPD51B340A-13-F<Part Number>ACPR709210K1%R0402-0201<Part Number>R6025 0R0402-02015%1/16WQ211ABSS138BKS<Part Number>S11G12D16
PC88610UFX6S25VC0805_H61<Part Number>PC8870.01UFX7RC0402-020150V<Part Number>R6015 0R0402-02015%1/16WQ208BBSS138BKS<Part Number>D23G25S24 R6021 0R0402-02015%1/16WQ211BBSS138BKS<Part Number>D23G25S24R6020 0R0402-02015%1/16WPR709810K1%R0402-0201<Part Number>
PD119B340A-13-F<Part Number>AC
PC891100PFX7R50VC0402-0201<Part Number>R6024 0R0402-02015%1/16W
P12V_SSD12_CO_ENP12V_SSD13_CO_ENP12V_SSD12_CO_MODEP12V_SSD12_CO_GATEP12V_SSD13_CO_MODEP12V_SSD13_CO_GATEP12V_SSD12_CO_ILIMITP12V_SSD13_CO_ILIMITP12V_SSD12_CO_DV_DTP12V_SSD13_CO_DV_DTPWRGD_P12V_SSD12_DPWRGD_P12V_SSD12_RPWRGD_P12V_SSD13_DPWRGD_P12V_SSD13_RP12V_SSD12_PG_G2P12V_SSD13_PG_G2P12V_SSD12_PG_G1P12V_SSD13_PG_G1P12V_SSD14_CO_ENP12V_SSD15_CO_ENP12V_SSD14_CO_MODEP12V_SSD14_CO_GATEP12V_SSD15_CO_MODEP12V_SSD15_CO_GATEP12V_SSD14_CO_ILIMITP12V_SSD15_CO_ILIMITP12V_SSD14_CO_DV_DTP12V_SSD15_CO_DV_DTPWRGD_P12V_SSD14_DPWRGD_P12V_SSD14_RPWRGD_P12V_SSD15_DPWRGD_P12V_SSD15_RP12V_SSD14_PG_G2P12V_SSD15_PG_G2P12V_SSD14_PG_G1P12V_SSD15_PG_G1



5
5
4
4
3
3
2
2
1
1
D D
C C
B B
A A
Design specification
P3V3_NIC E-fuseIout_max=1.1ACurrent limit=1.59ASoft-Start time=3.33msEnable Vth > 2V (High)
OCP1.59AVclamp3.66V
t_SS3.26ms t_SS3.26ms
OCP1.59AVclamp3.66V
t_SS3.26ms
OCP1.59A OCP1.59AVclamp3.66V
t_SS3.26ms
Vclamp3.66V
P3V3_NIC_MP5016_Colay_1
HP_NIC0_EN[170,235,238,242]PWRGD_P3V3_NIC0_R [116,238]HP_NIC1_EN[173,235,238,242]PWRGD_P3V3_NIC1_R [116,238]HP_NIC2_EN[176,235,238,242]HP_NIC3_EN[179,235,238,242]PWRGD_P3V3_NIC2_R [116,238]PWRGD_P3V3_NIC3_R [116,238]
P3V3_AUXP3V3_NIC0P5V_AUXP3V3_NIC0P3V3_AUXP3V3_AUXP3V3_NIC1P3V3_AUXP5V_AUXP3V3_NIC1P3V3_AUXP3V3_AUXP3V3_NIC2P3V3_NIC3P3V3_AUXP3V3_AUXP5V_AUXP5V_AUXP3V3_NIC2P3V3_NIC3SizeDoc NumberRevDate: SheetofReviewerDesignerDepartmentProject
Page TitleCCBU 11248 257Tuesday, August 29, 2023<project_name><Designer> GRANDTETON_SWB_20230829248 P3V3_NIC_MP5016_Colay_1<Reviewer>SizeDoc NumberRevDate: SheetofReviewerDesignerDepartmentProject
Page TitleCCBU 11248 257Tuesday, August 29, 2023<project_name><Designer> GRANDTETON_SWB_20230829248 P3V3_NIC_MP5016_Colay_1<Reviewer>SizeDoc NumberRevDate: SheetofReviewerDesignerDepartmentProject
Page TitleCCBU 11248 257Tuesday, August 29, 2023<project_name><Designer> GRANDTETON_SWB_20230829248 P3V3_NIC_MP5016_Colay_1<Reviewer>Q215ABSS138BKS<Part Number>S11G12D16PC79110UFX6S25VC0805_H61<Part Number>PC79439PF<Part Number>C0402-020150VNPOQ215BBSS138BKS<Part Number>D23G25S24PC7891UF25VC0402-0201<Part Number>X6SPC6650.047UFX7RC0402-020125V<Part Number>R5854 0R0402-02015%1/16WQ212BBSS138BKS<Part Number>D23G25S24 PR691771.5K<Part Number>R0402-02011%PC7881UF25VC0402-0201<Part Number>X6SR596410K1%R0402-0201<Part Number>
R586310K1%R0402-0201<Part Number>PC790100PFX7R50VC0402-0201<Part Number>R585610K1%R0402-0201<Part Number>PC7970.047UFX7RC0402-020125V<Part Number>
PU80MP5016GQH-L-ZEN9MODE5ILIMIT4GND3VCC1_2DV_DT10GATE8SOURCE6_7PU79MP5016GQH-L-ZEN9MODE5ILIMIT4GND3VCC1_2DV_DT10GATE8SOURCE6_7
PC79539PF<Part Number>C0402-020150VNPOR5954 0R0402-02015%1/16WR5858 0R0402-02015%1/16W
Q214BBSS138BKS<Part Number>D23G25S24
PC66439PF<Part Number>C0402-020150VNPOPC66310UFX6S25VC0805_H61<Part Number>R5855 0R0402-02015%1/16WPC6581UF25VC0402-0201<Part Number>X6SPR691571.5K<Part Number>R0402-02011%
R5959 0R0402-02015%1/16WR586510K1%R0402-0201<Part Number>R586410K1%R0402-0201<Part Number>R5859 0R0402-02015%1/16WR586010K1%R0402-0201<Part Number>PC6670.047UFX7RC0402-020125V<Part Number>
R595610K1%R0402-0201<Part Number>PU101MP5016GQH-L-ZEN9MODE5ILIMIT4GND3VCC1_2DV_DT10GATE8SOURCE6_7PC662100PFX7R50VC0402-0201<Part Number>PR69181.33K1%R0402-0201<Part Number>Q212ABSS138BKS<Part Number>S11G12D16 PC6591UF25VC0402-0201<Part Number>X6S
PR70141.33K1%R0402-0201<Part Number>PR70131.33K1%R0402-0201<Part Number>
PC66639PF<Part Number>C0402-020150VNPO
R596510K1%R0402-0201<Part Number>Q214ABSS138BKS<Part Number>S11G12D16 R595710K1%R0402-0201<Part Number>Q213ABSS138BKS<Part Number>S11G12D16R5958 0R0402-02015%1/16W
R586110K1%R0402-0201<Part Number>PC7960.047UFX7RC0402-020125V<Part Number>
PC660100PFX7R50VC0402-0201<Part Number>PR69161.33K1%R0402-0201<Part Number>PC79310UFX6S25VC0805_H61<Part Number>PU102MP5016GQH-L-ZEN9MODE5ILIMIT4GND3VCC1_2DV_DT10GATE8SOURCE6_7R586210K1%R0402-0201<Part Number>Q213BBSS138BKS<Part Number>D23G25S24
R596310K1%R0402-0201<Part Number>
PC66110UFX6S25VC0805_H61<Part Number>
R596010K1%R0402-0201<Part Number>R596110K1%R0402-0201<Part Number>PC792100PFX7R50VC0402-0201<Part Number>PR701271.5K<Part Number>R0402-02011%R5955 0R0402-02015%1/16WR585710K1%R0402-0201<Part Number>PR701171.5K<Part Number>R0402-02011%R596210K1%R0402-0201<Part Number>
P3V3_NIC0_CO_ENP3V3_NIC0_CO_MODEP3V3_NIC0_CO_GATEP3V3_NIC0_CO_ILIMITP3V3_NIC0_CO_DV_DTP3V3_NIC0_PG_G2P3V3_NIC0_PG_G1PWRGD_P3V3_NIC0_DPWRGD_P3V3_NIC0_RP3V3_NIC1_CO_ENP3V3_NIC1_CO_MODEP3V3_NIC1_CO_GATEP3V3_NIC1_CO_ILIMITP3V3_NIC1_CO_DV_DTPWRGD_P3V3_NIC1_DPWRGD_P3V3_NIC1_RP3V3_NIC1_PG_G2P3V3_NIC1_PG_G1P3V3_NIC2_CO_ENP3V3_NIC3_CO_ENP3V3_NIC2_CO_MODEP3V3_NIC2_CO_GATEP3V3_NIC3_CO_MODEP3V3_NIC3_CO_GATEP3V3_NIC2_CO_ILIMITP3V3_NIC3_CO_ILIMITP3V3_NIC2_CO_DV_DTP3V3_NIC3_CO_DV_DTPWRGD_P3V3_NIC2_DPWRGD_P3V3_NIC2_RPWRGD_P3V3_NIC3_DPWRGD_P3V3_NIC3_RP3V3_NIC2_PG_G2P3V3_NIC3_PG_G2P3V3_NIC2_PG_G1P3V3_NIC3_PG_G1



5
5
4
4
3
3
2
2
1
1
D D
C C
B B
A A
OCP1.59A
OCP1.59A
Vclamp3.66V OCP1.59A
P3V3_NIC E-fuseIout_max=1.1ACurrent limit=1.59ASoft-Start time=3.33msEnable Vth > 2V (High)
Vclamp3.66V
t_SS3.26ms
Design specification
Vclamp3.66V
t_SS3.26ms
Vclamp3.66V
t_SS3.26ms
OCP1.59A
t_SS3.26ms
P3V3_NIC_MP5016_Colay_2
HP_NIC4_EN[182,235,238,243]HP_NIC5_EN[185,235,238,243]PWRGD_P3V3_NIC4_R [116,238]PWRGD_P3V3_NIC5_R [116,238]HP_NIC6_EN[188,235,238,243]HP_NIC7_EN[191,235,238,243]PWRGD_P3V3_NIC6_R [116,238]PWRGD_P3V3_NIC7_R [116,238]
P3V3_AUXP3V3_AUXP3V3_NIC4P3V3_NIC5P3V3_AUXP3V3_AUXP5V_AUXP5V_AUXP3V3_NIC4P3V3_NIC5P3V3_AUXP3V3_AUXP3V3_NIC6P3V3_NIC7P3V3_AUXP3V3_AUXP5V_AUXP5V_AUXP3V3_NIC6P3V3_NIC7SizeDoc NumberRevDate: SheetofReviewerDesignerDepartmentProject
Page TitleCCBU 11249 257Tuesday, August 29, 2023<project_name><Designer> GRANDTETON_SWB_20230829249 P3V3_NIC_MP5016_Colay_2<Reviewer>SizeDoc NumberRevDate: SheetofReviewerDesignerDepartmentProject
Page TitleCCBU 11249 257Tuesday, August 29, 2023<project_name><Designer> GRANDTETON_SWB_20230829249 P3V3_NIC_MP5016_Colay_2<Reviewer>SizeDoc NumberRevDate: SheetofReviewerDesignerDepartmentProject
Page TitleCCBU 11249 257Tuesday, August 29, 2023<project_name><Designer> GRANDTETON_SWB_20230829249 P3V3_NIC_MP5016_Colay_2<Reviewer>R604510K1%R0402-0201<Part Number>PR71041.33K1%R0402-0201<Part Number>
PU120MP5016GQH-L-ZEN9MODE5ILIMIT4GND3VCC1_2DV_DT10GATE8SOURCE6_7PC90310UFX6S25VC0805_H61<Part Number>
Q219BBSS138BKS<Part Number>D23G25S24
PR71021.33K1%R0402-0201<Part Number>R603310K1%R0402-0201<Part Number>
R605210K1%R0402-0201<Part Number>PC91639PF<Part Number>C0402-020150VNPOR604010K1%R0402-0201<Part Number>R6034 0R0402-02015%1/16WPC9170.047UFX7RC0402-020125V<Part Number>
PR710171.5K<Part Number>R0402-02011%Q217BBSS138BKS<Part Number>D23G25S24R604110K1%R0402-0201<Part Number>PC8991UF25VC0402-0201<Part Number>X6SPC9050.047UFX7RC0402-020125V<Part Number>PC91110UFX6S25VC0805_H61<Part Number>PC910100PFX7R50VC0402-0201<Part Number>
PC90110UFX6S25VC0805_H61<Part Number>
Q218BBSS138BKS<Part Number>D23G25S24
PC900100PFX7R50VC0402-0201<Part Number>PU121MP5016GQH-L-ZEN9MODE5ILIMIT4GND3VCC1_2DV_DT10GATE8SOURCE6_7R6043 0R0402-02015%1/16W
R6030 0R0402-02015%1/16WPR709971.5K<Part Number>R0402-02011%R6042 0R0402-02015%1/16WR604410K1%R0402-0201<Part Number>
PC902100PFX7R50VC0402-0201<Part Number>
Q218ABSS138BKS<Part Number>S11G12D16
R603810K1%R0402-0201<Part Number>R6035 0R0402-02015%1/16WPU119MP5016GQH-L-ZEN9MODE5ILIMIT4GND3VCC1_2DV_DT10GATE8SOURCE6_7R603910K1%R0402-0201<Part Number>PC9081UF25VC0402-0201<Part Number>X6SPC91439PF<Part Number>C0402-020150VNPOQ216BBSS138BKS<Part Number>D23G25S24PR71001.33K1%R0402-0201<Part Number>PC8981UF25VC0402-0201<Part Number>X6SQ216ABSS138BKS<Part Number>S11G12D16 PU122MP5016GQH-L-ZEN9MODE5ILIMIT4GND3VCC1_2DV_DT10GATE8SOURCE6_7PR71061.33K1%R0402-0201<Part Number>Q219ABSS138BKS<Part Number>S11G12D16Q217ABSS138BKS<Part Number>S11G12D16PC912100PFX7R50VC0402-0201<Part Number>PC91310UFX6S25VC0805_H61<Part Number>R604910K1%R0402-0201<Part Number>R6047 0R0402-02015%1/16WPR710571.5K<Part Number>R0402-02011%R603210K1%R0402-0201<Part Number>R603610K1%R0402-0201<Part Number>
R605010K1%R0402-0201<Part Number>PC9150.047UFX7RC0402-020125V<Part Number>PR710371.5K<Part Number>R0402-02011%
PC90639PF<Part Number>C0402-020150VNPOPC9070.047UFX7RC0402-020125V<Part Number>
R605310K1%R0402-0201<Part Number>R6046 0R0402-02015%1/16WR604810K1%R0402-0201<Part Number>
R6031 0R0402-02015%1/16W
R605110K1%R0402-0201<Part Number>
R603710K1%R0402-0201<Part Number>PC9091UF25VC0402-0201<Part Number>X6SPC90439PF<Part Number>C0402-020150VNPOP3V3_NIC4_CO_ENP3V3_NIC5_CO_ENP3V3_NIC4_CO_MODEP3V3_NIC4_CO_GATEP3V3_NIC5_CO_MODEP3V3_NIC5_CO_GATEP3V3_NIC4_CO_ILIMITP3V3_NIC5_CO_ILIMITP3V3_NIC4_CO_DV_DTP3V3_NIC5_CO_DV_DTPWRGD_P3V3_NIC4_DPWRGD_P3V3_NIC4_RPWRGD_P3V3_NIC5_DPWRGD_P3V3_NIC5_RP3V3_NIC4_PG_G2P3V3_NIC5_PG_G2P3V3_NIC4_PG_G1P3V3_NIC5_PG_G1P3V3_NIC6_CO_ENP3V3_NIC7_CO_ENP3V3_NIC6_CO_MODEP3V3_NIC6_CO_GATEP3V3_NIC7_CO_MODEP3V3_NIC7_CO_GATEP3V3_NIC6_CO_ILIMITP3V3_NIC7_CO_ILIMITP3V3_NIC6_CO_DV_DTP3V3_NIC7_CO_DV_DTPWRGD_P3V3_NIC6_DPWRGD_P3V3_NIC6_RPWRGD_P3V3_NIC7_DPWRGD_P3V3_NIC7_RP3V3_NIC6_PG_G2P3V3_NIC7_PG_G2P3V3_NIC6_PG_G1P3V3_NIC7_PG_G1



5
5
4
4
3
3
2
2
1
1
D D
C C
B B
A A
OCP0.85A
t_SS3.26ms
Design specification
P3V3_SSD E-fuseIout_max=0.025ACurrent limit=0.85ASoft-Start time=3.33msEnable Vth > 2V (High)
Vclamp3.66V
t_SS3.26ms
Vclamp3.66V OCP0.85A
t_SS3.26ms
OCP0.85AVclamp3.66V Vclamp3.66V
t_SS3.26ms
OCP0.85A
P3V3_SSD_MP5016_Colay_1
SSD0_AUX_P3V3_EN_R[202,239]PWRGD_P3V3_SSD0_R [101,115,239]SSD1_AUX_P3V3_EN_R[202,239]PWRGD_P3V3_SSD1_R [101,115,239]SSD2_AUX_P3V3_EN_R[202,239]PWRGD_P3V3_SSD2_R [101,115,239]SSD3_AUX_P3V3_EN_R[202,239]PWRGD_P3V3_SSD3_R [101,115,239]
P3V3_AUXP3V3_SSD0P3V3_AUXP5V_AUXP3V3_SSD0P3V3_AUXP3V3_SSD1P3V3_AUXP5V_AUXP3V3_SSD1P3V3_AUXP3V3_SSD2P3V3_AUXP5V_AUXP3V3_SSD2P3V3_AUXP3V3_SSD3P3V3_AUXP5V_AUXP3V3_SSD3SizeDoc NumberRevDate: SheetofReviewerDesignerDepartmentProject
Page TitleCCBU 11250 257Tuesday, August 29, 2023<project_name><Designer> GRANDTETON_SWB_20230829240 P3V3_SSD_MP5016_Colay_1<Reviewer>SizeDoc NumberRevDate: SheetofReviewerDesignerDepartmentProject
Page TitleCCBU 11250 257Tuesday, August 29, 2023<project_name><Designer> GRANDTETON_SWB_20230829240 P3V3_SSD_MP5016_Colay_1<Reviewer>SizeDoc NumberRevDate: SheetofReviewerDesignerDepartmentProject
Page TitleCCBU 11250 257Tuesday, August 29, 2023<project_name><Designer> GRANDTETON_SWB_20230829240 P3V3_SSD_MP5016_Colay_1<Reviewer>R588910K1%R0402-0201<Part Number>PC680100PFX7R50VC0402-0201<Part Number>
PC6691UF25VC0402-0201<Part Number>X6SPR692171.5K<Part Number>R0402-02011%PC682100PFX7R50VC0402-0201<Part Number>R588410K1%R0402-0201<Part Number>PU84MP5016GQH-L-ZEN9MODE5ILIMIT4GND3VCC1_2DV_DT10GATE8SOURCE6_7PC68439PF<Part Number>C0402-020150VNPOQ133ABSS138BKS<Part Number>S11G12D16R5866 0R0402-02015%1/16W
Q136BBSS138BKS<Part Number>D23G25S24R5879 0R0402-02015%1/16WR587210K1%R0402-0201<Part Number>PC68639PF<Part Number>C0402-020150VNPOPC68110UFX6S25VC0805_H61<Part Number>PC68310UFX6S25VC0805_H61<Part Number>R5870 0R0402-02015%1/16WR586910K1%R0402-0201<Part Number>PR69222.49K1%R0402-0201<Part Number>
R588710K1%R0402-0201<Part Number>
R587310K1%R0402-0201<Part Number>Q133BBSS138BKS<Part Number>D23G25S24PC6781UF25VC0402-0201<Part Number>X6SPR692571.5K<Part Number>R0402-02011%R5882 0R0402-02015%1/16WQ135BBSS138BKS<Part Number>D23G25S24R5878 0R0402-02015%1/16WR588810K1%R0402-0201<Part Number>
PR691971.5K<Part Number>R0402-02011%
R588510K1%R0402-0201<Part Number>Q134BBSS138BKS<Part Number>D23G25S24PC670100PFX7R50VC0402-0201<Part Number>PC6770.047UFX7RC0402-020125V<Part Number>PR69262.49K1%R0402-0201<Part Number>
PC67439PF<Part Number>C0402-020150VNPOR587610K1%R0402-0201<Part Number>Q135ABSS138BKS<Part Number>S11G12D16
R5871 0R0402-02015%1/16WPC6750.047UFX7RC0402-020125V<Part Number>PU83MP5016GQH-L-ZEN9MODE5ILIMIT4GND3VCC1_2DV_DT10GATE8SOURCE6_7
PC6681UF25VC0402-0201<Part Number>X6SR587510K1%R0402-0201<Part Number>PC6850.047UFX7RC0402-020125V<Part Number>R587710K1%R0402-0201<Part Number>Q134ABSS138BKS<Part Number>S11G12D16R588610K1%R0402-0201<Part Number>PR69242.49K1%R0402-0201<Part Number>
PR69202.49K1%R0402-0201<Part Number>
R588110K1%R0402-0201<Part Number>R587410K1%R0402-0201<Part Number>PC6791UF25VC0402-0201<Part Number>X6SPC67110UFX6S25VC0805_H61<Part Number>PC67310UFX6S25VC0805_H61<Part Number>
Q136ABSS138BKS<Part Number>S11G12D16PC6870.047UFX7RC0402-020125V<Part Number>
PU82MP5016GQH-L-ZEN9MODE5ILIMIT4GND3VCC1_2DV_DT10GATE8SOURCE6_7PU81MP5016GQH-L-ZEN9MODE5ILIMIT4GND3VCC1_2DV_DT10GATE8SOURCE6_7PC67639PF<Part Number>C0402-020150VNPOR5867 0R0402-02015%1/16W
R588010K1%R0402-0201<Part Number>
R586810K1%R0402-0201<Part Number>
R5883 0R0402-02015%1/16WPR692371.5K<Part Number>R0402-02011%
PC672100PFX7R50VC0402-0201<Part Number>P3V3_SSD0_CO_ENP3V3_SSD0_CO_MODEP3V3_SSD0_CO_GATEP3V3_SSD0_CO_ILIMITP3V3_SSD0_CO_DV_DTPWRGD_P3V3_SSD0_DPWRGD_P3V3_SSD0_RP3V3_SSD0_PG_G2P3V3_SSD0_PG_G1P3V3_SSD1_CO_ENP3V3_SSD1_CO_MODEP3V3_SSD1_CO_GATEP3V3_SSD1_CO_ILIMITP3V3_SSD1_CO_DV_DTPWRGD_P3V3_SSD1_DPWRGD_P3V3_SSD1_RP3V3_SSD1_PG_G2P3V3_SSD1_PG_G1P3V3_SSD2_CO_ENP3V3_SSD2_CO_MODEP3V3_SSD2_CO_GATEP3V3_SSD2_CO_ILIMITP3V3_SSD2_CO_DV_DTPWRGD_P3V3_SSD2_DPWRGD_P3V3_SSD2_RP3V3_SSD2_PG_G2P3V3_SSD2_PG_G1P3V3_SSD3_CO_ENP3V3_SSD3_CO_MODEP3V3_SSD3_CO_GATEP3V3_SSD3_CO_ILIMITP3V3_SSD3_CO_DV_DTPWRGD_P3V3_SSD3_DPWRGD_P3V3_SSD3_RP3V3_SSD3_PG_G2P3V3_SSD3_PG_G1



5
5
4
4
3
3
2
2
1
1
D D
C C
B B
A A
OCP0.85AVclamp3.66V
t_SS3.26ms
Vclamp3.66V
t_SS3.26ms
t_SS3.26ms
Vclamp3.66V
Design specification
OCP0.85A
P3V3_SSD E-fuseIout_max=0.025ACurrent limit=0.85ASoft-Start time=3.33msEnable Vth > 2V (High)
OCP0.85A
t_SS3.26ms
OCP0.85AVclamp3.66V
P3V3_SSD_MP5016_Colay_2
SSD4_AUX_P3V3_EN_R[202,239]SSD5_AUX_P3V3_EN_R[202,239]PWRGD_P3V3_SSD4_R [101,115,239]PWRGD_P3V3_SSD5_R [101,115,239]SSD6_AUX_P3V3_EN_R[202,239]SSD7_AUX_P3V3_EN_R[202,239]PWRGD_P3V3_SSD6_R [101,115,239]PWRGD_P3V3_SSD7_R [101,115,239]
P3V3_AUXP3V3_AUXP3V3_SSD4P3V3_SSD5P3V3_AUXP3V3_AUXP5V_AUXP5V_AUXP3V3_SSD4P3V3_SSD5P3V3_AUXP3V3_AUXP3V3_SSD6P3V3_SSD7P3V3_AUXP3V3_AUXP5V_AUXP5V_AUXP3V3_SSD6P3V3_SSD7SizeDoc NumberRevDate: SheetofReviewerDesignerDepartmentProject
Page TitleCCBU 11251 257Tuesday, August 29, 2023<project_name><Designer> GRANDTETON_SWB_20230829251 P3V3_SSD_MP5016_Colay_2<Reviewer>SizeDoc NumberRevDate: SheetofReviewerDesignerDepartmentProject
Page TitleCCBU 11251 257Tuesday, August 29, 2023<project_name><Designer> GRANDTETON_SWB_20230829251 P3V3_SSD_MP5016_Colay_2<Reviewer>SizeDoc NumberRevDate: SheetofReviewerDesignerDepartmentProject
Page TitleCCBU 11251 257Tuesday, August 29, 2023<project_name><Designer> GRANDTETON_SWB_20230829251 P3V3_SSD_MP5016_Colay_2<Reviewer>PC93639PF<Part Number>C0402-020150VNPOQ223ABSS138BKS<Part Number>S11G12D16
Q220BBSS138BKS<Part Number>D23G25S24PR711171.5K<Part Number>R0402-02011%R606810K1%R0402-0201<Part Number>
PC92639PF<Part Number>C0402-020150VNPOQ221BBSS138BKS<Part Number>D23G25S24PR710971.5K<Part Number>R0402-02011%PC932100PFX7R50VC0402-0201<Part Number>
PC9270.047UFX7RC0402-020125V<Part Number>PR711371.5K<Part Number>R0402-02011%R6058 0R0402-02015%1/16W
Q222ABSS138BKS<Part Number>S11G12D16
PU124MP5016GQH-L-ZEN9MODE5ILIMIT4GND3VCC1_2DV_DT10GATE8SOURCE6_7PC9191UF25VC0402-0201<Part Number>X6SPC9281UF25VC0402-0201<Part Number>X6SPU125MP5016GQH-L-ZEN9MODE5ILIMIT4GND3VCC1_2DV_DT10GATE8SOURCE6_7PR710771.5K<Part Number>R0402-02011% PC922100PFX7R50VC0402-0201<Part Number>
R607410K1%R0402-0201<Part Number>
R6055 0R0402-02015%1/16W
Q223BBSS138BKS<Part Number>D23G25S24
R606110K1%R0402-0201<Part Number>
R607510K1%R0402-0201<Part Number>
PC9250.047UFX7RC0402-020125V<Part Number>PC92439PF<Part Number>C0402-020150VNPO
R607210K1%R0402-0201<Part Number>R606910K1%R0402-0201<Part Number>R6067 0R0402-02015%1/16WQ222BBSS138BKS<Part Number>D23G25S24 PU126MP5016GQH-L-ZEN9MODE5ILIMIT4GND3VCC1_2DV_DT10GATE8SOURCE6_7PR71122.49K1%R0402-0201<Part Number>Q221ABSS138BKS<Part Number>S11G12D16R605610K1%R0402-0201<Part Number>PR71142.49K1%R0402-0201<Part Number>PC930100PFX7R50VC0402-0201<Part Number>R607710K1%R0402-0201<Part Number>R607310K1%R0402-0201<Part Number>
PU123MP5016GQH-L-ZEN9MODE5ILIMIT4GND3VCC1_2DV_DT10GATE8SOURCE6_7PR71102.49K1%R0402-0201<Part Number>
R6071 0R0402-02015%1/16W
PC92110UFX6S25VC0805_H61<Part Number>PC9370.047UFX7RC0402-020125V<Part Number>R606310K1%R0402-0201<Part Number>R6070 0R0402-02015%1/16WR606410K1%R0402-0201<Part Number>R607610K1%R0402-0201<Part Number>
R606010K1%R0402-0201<Part Number>PC9291UF25VC0402-0201<Part Number>X6SR605710K1%R0402-0201<Part Number>PC92310UFX6S25VC0805_H61<Part Number>PR71082.49K1%R0402-0201<Part Number>R6059 0R0402-02015%1/16WPC920100PFX7R50VC0402-0201<Part Number>R606210K1%R0402-0201<Part Number>PC9350.047UFX7RC0402-020125V<Part Number>
PC9181UF25VC0402-0201<Part Number>X6SR606510K1%R0402-0201<Part Number>R6066 0R0402-02015%1/16WPC93439PF<Part Number>C0402-020150VNPOQ220ABSS138BKS<Part Number>S11G12D16PC93110UFX6S25VC0805_H61<Part Number>
R6054 0R0402-02015%1/16W
PC93310UFX6S25VC0805_H61<Part Number>
P3V3_SSD4_CO_ENP3V3_SSD5_CO_ENP3V3_SSD4_CO_MODEP3V3_SSD4_CO_GATEP3V3_SSD5_CO_MODEP3V3_SSD5_CO_GATEP3V3_SSD4_CO_ILIMITP3V3_SSD5_CO_ILIMITP3V3_SSD4_CO_DV_DTP3V3_SSD5_CO_DV_DTPWRGD_P3V3_SSD4_DPWRGD_P3V3_SSD4_RPWRGD_P3V3_SSD5_DPWRGD_P3V3_SSD5_RP3V3_SSD4_PG_G2P3V3_SSD5_PG_G2P3V3_SSD4_PG_G1P3V3_SSD5_PG_G1P3V3_SSD6_CO_ENP3V3_SSD7_CO_ENP3V3_SSD6_CO_MODEP3V3_SSD6_CO_GATEP3V3_SSD7_CO_MODEP3V3_SSD7_CO_GATEP3V3_SSD6_CO_ILIMITP3V3_SSD7_CO_ILIMITP3V3_SSD6_CO_DV_DTP3V3_SSD7_CO_DV_DTPWRGD_P3V3_SSD6_DPWRGD_P3V3_SSD6_RPWRGD_P3V3_SSD7_DPWRGD_P3V3_SSD7_RP3V3_SSD6_PG_G2P3V3_SSD7_PG_G2P3V3_SSD6_PG_G1P3V3_SSD7_PG_G1



5
5
4
4
3
3
2
2
1
1
D D
C C
B B
A A
OCP0.85AVclamp3.66V
t_SS3.26ms
Vclamp3.66V
t_SS3.26ms
t_SS3.26ms
Vclamp3.66V
Design specification
OCP0.85A
P3V3_SSD E-fuseIout_max=0.025ACurrent limit=0.85ASoft-Start time=3.33msEnable Vth > 2V (High)
OCP0.85A
t_SS3.26ms
OCP0.85AVclamp3.66V
P3V3_SSD_MP5016_Colay_3
SSD8_AUX_P3V3_EN_R[203,240]SSD9_AUX_P3V3_EN_R[203,240]PWRGD_P3V3_SSD8_R [102,117,240]PWRGD_P3V3_SSD9_R [102,117,240]SSD10_AUX_P3V3_EN_R[203,240]SSD11_AUX_P3V3_EN_R[203,240]PWRGD_P3V3_SSD10_R [102,117,240]PWRGD_P3V3_SSD11_R [102,117,240]
P3V3_AUXP3V3_AUXP3V3_SSD8P3V3_SSD9P3V3_AUXP3V3_AUXP5V_AUXP5V_AUXP3V3_SSD8P3V3_SSD9P3V3_AUXP3V3_AUXP3V3_SSD10P3V3_SSD11P3V3_AUXP3V3_AUXP5V_AUXP5V_AUXP3V3_SSD10P3V3_SSD11SizeDoc NumberRevDate: SheetofReviewerDesignerDepartmentProject
Page TitleCCBU 11252 257Tuesday, August 29, 2023<project_name><Designer> GRANDTETON_SWB_20230829252 P3V3_SSD_MP5016_Colay_3<Reviewer>SizeDoc NumberRevDate: SheetofReviewerDesignerDepartmentProject
Page TitleCCBU 11252 257Tuesday, August 29, 2023<project_name><Designer> GRANDTETON_SWB_20230829252 P3V3_SSD_MP5016_Colay_3<Reviewer>SizeDoc NumberRevDate: SheetofReviewerDesignerDepartmentProject
Page TitleCCBU 11252 257Tuesday, August 29, 2023<project_name><Designer> GRANDTETON_SWB_20230829252 P3V3_SSD_MP5016_Colay_3<Reviewer>
PC94639PF<Part Number>C0402-020150VNPOPR711571.5K<Part Number>R0402-02011%PR71222.49K1%R0402-0201<Part Number>R609810K1%R0402-0201<Part Number>PC9570.047UFX7RC0402-020125V<Part Number>R608610K1%R0402-0201<Part Number>Q224BBSS138BKS<Part Number>D23G25S24R6078 0R0402-02015%1/16WQ224ABSS138BKS<Part Number>S11G12D16 R6091 0R0402-02015%1/16WQ225BBSS138BKS<Part Number>D23G25S24R6083 0R0402-02015%1/16WPC94110UFX6S25VC0805_H61<Part Number>PC9550.047UFX7RC0402-020125V<Part Number>
PC94439PF<Part Number>C0402-020150VNPOPC9381UF25VC0402-0201<Part Number>X6S
R609710K1%R0402-0201<Part Number>R608710K1%R0402-0201<Part Number>
R610110K1%R0402-0201<Part Number>R609310K1%R0402-0201<Part Number>
R608010K1%R0402-0201<Part Number>PC940100PFX7R50VC0402-0201<Part Number>R6082 0R0402-02015%1/16W
Q227ABSS138BKS<Part Number>S11G12D16
PC9450.047UFX7RC0402-020125V<Part Number>R608810K1%R0402-0201<Part Number>R6095 0R0402-02015%1/16WPC95639PF<Part Number>C0402-020150VNPOPU129MP5016GQH-L-ZEN9MODE5ILIMIT4GND3VCC1_2DV_DT10GATE8SOURCE6_7PR711971.5K<Part Number>R0402-02011%
PU127MP5016GQH-L-ZEN9MODE5ILIMIT4GND3VCC1_2DV_DT10GATE8SOURCE6_7
Q226BBSS138BKS<Part Number>D23G25S24
PC9581UF25VC0402-0201<Part Number>X6SR6079 0R0402-02015%1/16WPU130MP5016GQH-L-ZEN9MODE5ILIMIT4GND3VCC1_2DV_DT10GATE8SOURCE6_7PC94310UFX6S25VC0805_H61<Part Number>PC9591UF25VC0402-0201<Part Number>X6SPC9391UF25VC0402-0201<Part Number>X6SR608910K1%R0402-0201<Part Number>R6094 0R0402-02015%1/16W
PU128MP5016GQH-L-ZEN9MODE5ILIMIT4GND3VCC1_2DV_DT10GATE8SOURCE6_7
R609210K1%R0402-0201<Part Number>PC95439PF<Part Number>C0402-020150VNPOR6090 0R0402-02015%1/16WPC950100PFX7R50VC0402-0201<Part Number>
PR711771.5K<Part Number>R0402-02011%PR71202.49K1%R0402-0201<Part Number>PR712171.5K<Part Number>R0402-02011%R609910K1%R0402-0201<Part Number>Q226ABSS138BKS<Part Number>S11G12D16 PC95310UFX6S25VC0805_H61<Part Number>
PC942100PFX7R50VC0402-0201<Part Number>R608410K1%R0402-0201<Part Number>PC95110UFX6S25VC0805_H61<Part Number>R610010K1%R0402-0201<Part Number>R609610K1%R0402-0201<Part Number>
PR71182.49K1%R0402-0201<Part Number>
Q227BBSS138BKS<Part Number>D23G25S24Q225ABSS138BKS<Part Number>S11G12D16R608110K1%R0402-0201<Part Number>R608510K1%R0402-0201<Part Number>PC9470.047UFX7RC0402-020125V<Part Number>PC952100PFX7R50VC0402-0201<Part Number>
PR71162.49K1%R0402-0201<Part Number>P3V3_SSD8_CO_ENP3V3_SSD9_CO_ENP3V3_SSD8_CO_MODEP3V3_SSD8_CO_GATEP3V3_SSD9_CO_MODEP3V3_SSD9_CO_GATEP3V3_SSD8_CO_ILIMITP3V3_SSD9_CO_ILIMITP3V3_SSD8_CO_DV_DTP3V3_SSD9_CO_DV_DTPWRGD_P3V3_SSD8_DPWRGD_P3V3_SSD8_RPWRGD_P3V3_SSD9_DPWRGD_P3V3_SSD9_RP3V3_SSD8_PG_G2P3V3_SSD9_PG_G2P3V3_SSD8_PG_G1P3V3_SSD9_PG_G1P3V3_SSD10_CO_ENP3V3_SSD11_CO_ENP3V3_SSD10_CO_MODEP3V3_SSD10_CO_GATEP3V3_SSD11_CO_MODEP3V3_SSD11_CO_GATEP3V3_SSD10_CO_ILIMITP3V3_SSD11_CO_ILIMITP3V3_SSD10_CO_DV_DTP3V3_SSD11_CO_DV_DTPWRGD_P3V3_SSD10_DPWRGD_P3V3_SSD10_RPWRGD_P3V3_SSD11_DPWRGD_P3V3_SSD11_RP3V3_SSD10_PG_G2P3V3_SSD11_PG_G2P3V3_SSD10_PG_G1P3V3_SSD11_PG_G1



5
5
4
4
3
3
2
2
1
1
D D
C C
B B
A A
OCP0.85AVclamp3.66V
t_SS3.26ms
Vclamp3.66V
t_SS3.26ms
t_SS3.26ms
Vclamp3.66V
Design specification
OCP0.85A
P3V3_SSD E-fuseIout_max=0.025ACurrent limit=0.85ASoft-Start time=3.33msEnable Vth > 2V (High)
OCP0.85A
t_SS3.26ms
OCP0.85AVclamp3.66V
P3V3_SSD_MP5016_Colay_4
SSD12_AUX_P3V3_EN_R[203,240]SSD13_AUX_P3V3_EN_R[203,240]PWRGD_P3V3_SSD12_R [102,117,240]PWRGD_P3V3_SSD13_R [102,117,240]SSD14_AUX_P3V3_EN_R[203,240]SSD15_AUX_P3V3_EN_R[203,240]PWRGD_P3V3_SSD14_R [102,117,240]PWRGD_P3V3_SSD15_R [102,117,240]
P3V3_AUXP3V3_AUXP3V3_SSD12P3V3_SSD13P3V3_AUXP3V3_AUXP5V_AUXP5V_AUXP3V3_SSD12P3V3_SSD13P3V3_AUXP3V3_AUXP3V3_SSD14P3V3_SSD15P3V3_AUXP3V3_AUXP5V_AUXP5V_AUXP3V3_SSD14P3V3_SSD15SizeDoc NumberRevDate: SheetofReviewerDesignerDepartmentProject
Page TitleCCBU 11253 257Tuesday, August 29, 2023<project_name><Designer> GRANDTETON_SWB_20230829253 P3V3_SSD_MP5016_Colay_4<Reviewer>SizeDoc NumberRevDate: SheetofReviewerDesignerDepartmentProject
Page TitleCCBU 11253 257Tuesday, August 29, 2023<project_name><Designer> GRANDTETON_SWB_20230829253 P3V3_SSD_MP5016_Colay_4<Reviewer>SizeDoc NumberRevDate: SheetofReviewerDesignerDepartmentProject
Page TitleCCBU 11253 257Tuesday, August 29, 2023<project_name><Designer> GRANDTETON_SWB_20230829253 P3V3_SSD_MP5016_Colay_4<Reviewer>R612010K1%R0402-0201<Part Number>R611110K1%R0402-0201<Part Number>Q229BBSS138BKS<Part Number>D23G25S24R6107 0R0402-02015%1/16WPC9491UF25VC0402-0201<Part Number>X6S
R6119 0R0402-02015%1/16W
R610410K1%R0402-0201<Part Number>PR712771.5K<Part Number>R0402-02011%
PR712371.5K<Part Number>R0402-02011%PC96439PF<Part Number>C0402-020150VNPOPC97039PF<Part Number>C0402-020150VNPOPR712871.5K<Part Number>R0402-02011%
PC96210UFX6S25VC0805_H61<Part Number>PC961100PFX7R50VC0402-0201<Part Number>PU133MP5016GQH-L-ZEN9MODE5ILIMIT4GND3VCC1_2DV_DT10GATE8SOURCE6_7R6102 0R0402-02015%1/16WPU134MP5016GQH-L-ZEN9MODE5ILIMIT4GND3VCC1_2DV_DT10GATE8SOURCE6_7PC97439PF<Part Number>C0402-020150VNPOR612510K1%R0402-0201<Part Number>Q231ABSS138BKS<Part Number>S11G12D16Q228ABSS138BKS<Part Number>S11G12D16 PC97210UFX6S25VC0805_H61<Part Number>R610810K1%R0402-0201<Part Number>Q228BBSS138BKS<Part Number>D23G25S24PC9681UF25VC0402-0201<Part Number>X6SPC965100PFX7R50VC0402-0201<Part Number>R6115 0R0402-02015%1/16WPR712571.5K<Part Number>R0402-02011%R6106 0R0402-02015%1/16WPC975100PFX7R50VC0402-0201<Part Number>R6118 0R0402-02015%1/16W
PC9670.047UFX7RC0402-020125V<Part Number>R611010K1%R0402-0201<Part Number>PC971100PFX7R50VC0402-0201<Part Number>
PC96039PF<Part Number>C0402-020150VNPOPU131MP5016GQH-L-ZEN9MODE5ILIMIT4GND3VCC1_2DV_DT10GATE8SOURCE6_7R6103 0R0402-02015%1/16W
Q231BBSS138BKS<Part Number>D23G25S24
PC96610UFX6S25VC0805_H61<Part Number>PU132MP5016GQH-L-ZEN9MODE5ILIMIT4GND3VCC1_2DV_DT10GATE8SOURCE6_7PC9691UF25VC0402-0201<Part Number>X6SR610510K1%R0402-0201<Part Number>PR71242.49K1%R0402-0201<Part Number>Q229ABSS138BKS<Part Number>S11G12D16PR71292.49K1%R0402-0201<Part Number>R612110K1%R0402-0201<Part Number>Q230BBSS138BKS<Part Number>D23G25S24 PC97610UFX6S25VC0805_H61<Part Number>PC9730.047UFX7RC0402-020125V<Part Number>R611610K1%R0402-0201<Part Number>R6114 0R0402-02015%1/16WPC9630.047UFX7RC0402-020125V<Part Number>PR71302.49K1%R0402-0201<Part Number>R611310K1%R0402-0201<Part Number>Q230ABSS138BKS<Part Number>S11G12D16
PC9481UF25VC0402-0201<Part Number>X6S
R612210K1%R0402-0201<Part Number>R612310K1%R0402-0201<Part Number>PC9770.047UFX7RC0402-020125V<Part Number>R611710K1%R0402-0201<Part Number>R611210K1%R0402-0201<Part Number>R612410K1%R0402-0201<Part Number>
R610910K1%R0402-0201<Part Number>PR71262.49K1%R0402-0201<Part Number>P3V3_SSD12_CO_ENP3V3_SSD13_CO_ENP3V3_SSD12_CO_MODEP3V3_SSD12_CO_GATEP3V3_SSD13_CO_MODEP3V3_SSD13_CO_GATEP3V3_SSD12_CO_ILIMITP3V3_SSD13_CO_ILIMITP3V3_SSD12_CO_DV_DTP3V3_SSD13_CO_DV_DTPWRGD_P3V3_SSD12_DPWRGD_P3V3_SSD12_RPWRGD_P3V3_SSD13_DPWRGD_P3V3_SSD13_RP3V3_SSD12_PG_G2P3V3_SSD13_PG_G2P3V3_SSD12_PG_G1P3V3_SSD13_PG_G1P3V3_SSD14_CO_ENP3V3_SSD15_CO_ENP3V3_SSD14_CO_MODEP3V3_SSD14_CO_GATEP3V3_SSD15_CO_MODEP3V3_SSD15_CO_GATEP3V3_SSD14_CO_ILIMITP3V3_SSD15_CO_ILIMITP3V3_SSD14_CO_DV_DTP3V3_SSD15_CO_DV_DTPWRGD_P3V3_SSD14_DPWRGD_P3V3_SSD14_RPWRGD_P3V3_SSD15_DPWRGD_P3V3_SSD15_RP3V3_SSD14_PG_G2P3V3_SSD15_PG_G2P3V3_SSD14_PG_G1P3V3_SSD15_PG_G1



5
5
4
4
3
3
2
2
1
1
D D
C C
B B
A A
TDR
TOP
IN4
BOT
IN3
IN1
IN2
TDR-SINGLE
IN4
IN3
IN1
IN2
TOP
TDR-DIFFERENTIAL(85 ohm)
IN4
IN3
IN1
IN2
TOP
BOT BOT
IN5
IN6
IN5
IN6
IN5
IN6
TOP
TDR-DIFFERENTIAL(100 ohm)
TOP
IN5
IN2
IN3
IN1
IN4
IN6
IN5
BOT
IN2
IN3
BOT
IN6
IN1
IN4
COUPON_GND1COUPON_GND1COUPON_GND1COUPON_GND1COUPON_GND1COUPON_GND1COUPON_GND1COUPON_GND1COUPON_GND1COUPON_GND1COUPON_GND1COUPON_GND1COUPON_GND1COUPON_GND1COUPON_GND1COUPON_GND1COUPON_GND1COUPON_GND1COUPON_GND1COUPON_GND1COUPON_GND1COUPON_GND1COUPON_GND1COUPON_GND1COUPON_GND1COUPON_GND1COUPON_GND1COUPON_GND1COUPON_GND1COUPON_GND1COUPON_GND1COUPON_GND1COUPON_GND1COUPON_GND1COUPON_GND1COUPON_GND1COUPON_GND1COUPON_GND1COUPON_GND1COUPON_GND1SizeDoc NumberRevDate: SheetofReviewerDesignerDepartmentProject
Page TitleCCBU D254 257Tuesday, August 29, 2023<project_name><Designer> GRANDTETON_SWB_20230829254 TDR<Reviewer>SizeDoc NumberRevDate: SheetofReviewerDesignerDepartmentProject
Page TitleCCBU D254 257Tuesday, August 29, 2023<project_name><Designer> GRANDTETON_SWB_20230829254 TDR<Reviewer>SizeDoc NumberRevDate: SheetofReviewerDesignerDepartmentProject
Page TitleCCBU D254 257Tuesday, August 29, 2023<project_name><Designer> GRANDTETON_SWB_20230829254 TDR<Reviewer>X57TP_TDR_4P_DIPNIP12P23S11S24
J46TDR_3P_C85P67_141_100M_QNIGND1IO12IO23X3TP_TDR_4P_DIPNIP12P23S11S24X78TP_TDR_4P_DIPNIP12P23S11S24X74TP_TDR_4P_DIPNIP12P23S11S24X70TP_TDR_4P_DIPNIP12P23S11S24J53TDR_3P_C85P67_141_100M_QNIGND1IO12IO23 X66TP_TDR_4P_DIPNIP12P23S11S24J51TDR_3P_C85P67_141_100M_QNIGND1IO12IO23J50TDR_3P_C85P67_141_100M_QNIGND1IO12IO23 X79TP_TDR_4P_DIPNIP12P23S11S24X75TP_TDR_4P_DIPNIP12P23S11S24X71TP_TDR_4P_DIPNIP12P23S11S24X67TP_TDR_4P_DIPNIP12P23S11S24X21TP_TDR_4P_DIPNIP12P23S11S24X2TP_TDR_4P_DIPNIP12P23S11S24
X56TP_TDR_4P_DIPNIP12P23S11S24X20TP_TDR_4P_DIPNIP12P23S11S24X64TP_TDR_4P_DIPNIP12P23S11S24J52TDR_3P_C85P67_141_100M_QNIGND1IO12IO23X14TP_TDR_4P_DIPNIP12P23S11S24J47TDR_3P_C85P67_141_100M_QNIGND1IO12IO23J48TDR_3P_C85P67_141_100M_QNIGND1IO12IO23X62TP_TDR_4P_DIPNIP12P23S11S24X80TP_TDR_4P_DIPNIP12P23S11S24X76TP_TDR_4P_DIPNIP12P23S11S24X72TP_TDR_4P_DIPNIP12P23S11S24X68TP_TDR_4P_DIPNIP12P23S11S24X9TP_TDR_4P_DIPNIP12P23S11S24J49TDR_3P_C85P67_141_100M_QNIGND1IO12IO23 X81TP_TDR_4P_DIPNIP12P23S11S24X77TP_TDR_4P_DIPNIP12P23S11S24X26TP_TDR_4P_DIPNIP12P23S11S24 X73TP_TDR_4P_DIPNIP12P23S11S24X69TP_TDR_4P_DIPNIP12P23S11S24X65TP_TDR_4P_DIPNIP12P23S11S24X8TP_TDR_4P_DIPNIP12P23S11S24X63TP_TDR_4P_DIPNIP12P23S11S24X15TP_TDR_4P_DIPNIP12P23S11S24X27TP_TDR_4P_DIPNIP12P23S11S24TDR_SE_50_OHM_TOPTDR_SE_50_OHM_IN1TDR_SE_50_OHM_IN2TDR_SE_50_OHM_IN3TDR_SE_50_OHM_IN4TDR_SE_50_OHM_BOTTDR_DIFF_85_TOP_DIPTDR_DIFF_85_TOP_DINTDR_DIFF_85_IN1_DIPTDR_DIFF_85_IN1_DINTDR_DIFF_85_IN2_DIPTDR_DIFF_85_IN2_DINTDR_DIFF_85_IN3_DIPTDR_DIFF_85_IN3_DINTDR_DIFF_85_IN4_DIPTDR_DIFF_85_IN4_DINTDR_DIFF_85_BOT_DIPTDR_DIFF_85_BOT_DINTDR_SE_50_OHM_IN5TDR_SE_50_OHM_IN6TDR_DIFF_85_IN5_DIPTDR_DIFF_85_IN5_DINTDR_DIFF_85_IN6_DIPTDR_DIFF_85_IN6_DIN
TDR_DIFF_100_TOP_DIPTDR_DIFF_100_TOP_DINTDR_DIFF_100_IN1_DIPTDR_DIFF_100_IN1_DINTDR_DIFF_100_IN2_DIPTDR_DIFF_100_IN2_DINTDR_DIFF_100_IN3_DIPTDR_DIFF_100_IN3_DINTDR_DIFF_100_IN4_DIPTDR_DIFF_100_IN4_DINTDR_DIFF_100_IN5_DIPTDR_DIFF_100_IN5_DINTDR_DIFF_100_IN6_DIPTDR_DIFF_100_IN6_DINTDR_DIFF_100_BOT_DIPTDR_DIFF_100_BOT_DIN



5
5
4
4
3
3
2
2
1
1
D D
C C
B B
A A
DELTA_L
PVT_CHANGECOUPON_GND2COUPON_GND2COUPON_GND2COUPON_GND2COUPON_GND2COUPON_GND2COUPON_GND2COUPON_GND2COUPON_GND2COUPON_GND2COUPON_GND2COUPON_GND2COUPON_GND2COUPON_GND2COUPON_GND2COUPON_GND2COUPON_GND2COUPON_GND2COUPON_GND2COUPON_GND2COUPON_GND2COUPON_GND2COUPON_GND2COUPON_GND2COUPON_GND2COUPON_GND2COUPON_GND2COUPON_GND2COUPON_GND2COUPON_GND2COUPON_GND2COUPON_GND2SizeDoc NumberRevDate: SheetofReviewerDesignerDepartmentProject
Page TitleCCBU D255 257Tuesday, August 29, 2023<project_name><Designer> GRANDTETON_SWB_20230829255 DELTA_L<Reviewer>SizeDoc NumberRevDate: SheetofReviewerDesignerDepartmentProject
Page TitleCCBU D255 257Tuesday, August 29, 2023<project_name><Designer> GRANDTETON_SWB_20230829255 DELTA_L<Reviewer>SizeDoc NumberRevDate: SheetofReviewerDesignerDepartmentProject
Page TitleCCBU D255 257Tuesday, August 29, 2023<project_name><Designer> GRANDTETON_SWB_20230829255 DELTA_L<Reviewer>
DE04F_1DELTA-L 4.0NI2_N23_G31_P1DE12T_2DELTA-L 4.0NI2_N23_G31_P1DE05F_2DELTA-L 4.0NI2_N23_G31_P1DE06F_3DELTA-L 4.0NI2_N23_G31_P1DE15T_1DELTA-L 4.0NI2_N23_G31_P1DE02F_2DELTA-L 4.0NI2_N23_G31_P1DE06F_4DELTA-L 4.0NI2_N23_G31_P1DE15T_2DELTA-L 4.0NI2_N23_G31_P1DE02F_1DELTA-L 4.0NI2_N23_G31_P1 DE16T_3DELTA-L 4.0NI2_N23_G31_P1DE13T_1DELTA-L 4.0NI2_N23_G31_P1DE06F_1DELTA-L 4.0NI2_N23_G31_P1DE16T_4DELTA-L 4.0NI2_N23_G31_P1DE13T_2DELTA-L 4.0NI2_N23_G31_P1DE06F_2DELTA-L 4.0NI2_N23_G31_P1 DE16T_1DELTA-L 4.0NI2_N23_G31_P1DE11T_2DELTA-L 4.0NI2_N23_G31_P1DE03F_2DELTA-L 4.0NI2_N23_G31_P1DE16T_2DELTA-L 4.0NI2_N23_G31_P1DE11T_1DELTA-L 4.0NI2_N23_G31_P1DE03F_1DELTA-L 4.0NI2_N23_G31_P1 DE14T_1DELTA-L 4.0NI2_N23_G31_P1DE05F_3DELTA-L 4.0NI2_N23_G31_P1DE01F_2DELTA-L 4.0NI2_N23_G31_P1DE14T_2DELTA-L 4.0NI2_N23_G31_P1DE05F_4DELTA-L 4.0NI2_N23_G31_P1DE01F_1DELTA-L 4.0NI2_N23_G31_P1DE15T_3DELTA-L 4.0NI2_N23_G31_P1DE04F_2DELTA-L 4.0NI2_N23_G31_P1DE12T_1DELTA-L 4.0NI2_N23_G31_P1DE05F_1DELTA-L 4.0NI2_N23_G31_P1DE15T_4DELTA-L 4.0NI2_N23_G31_P185_5INCH_TOP_DP85_5INCH_TOP_DN85_5INCH_BOTTOM_DP85_5INCH_BOTTOM_DN85_5INCH_IN1_DP85_5INCH_IN1_DN85_5INCH_IN2_DP85_5INCH_IN2_DN85_5INCH_IN3_DP85_5INCH_IN3_DN85_5INCH_IN4_DP85_5INCH_IN4_DN85_5INCH_IN5_DP85_5INCH_IN5_DN85_5INCH_IN6_DP85_5INCH_IN6_DN85_10INCH_TOP_DP85_10INCH_TOP_DN85_10INCH_BOTTOM_DP85_10INCH_BOTTOM_DN85_10INCH_IN1_DP85_10INCH_IN1_DN85_10INCH_IN2_DP85_10INCH_IN2_DN85_10INCH_IN3_DP85_10INCH_IN3_DN85_10INCH_IN4_DP85_10INCH_IN4_DN85_10INCH_IN5_DP85_10INCH_IN5_DN85_10INCH_IN6_DP85_10INCH_IN6_DN



5
5
4
4
3
3
2
2
1
1
D D
C C
B B
A A
SCREW HOLE
DETAIL  A *23
DETAIL B *1
DETAIL C *4
TOOLING HOLE *4
DETAIL E *32
DETAIL D *16 DETAIL G*10
DVT_CHANGE
SizeDoc NumberRevDate: SheetofReviewerDesignerDepartmentProject
Page TitleCCBU D256 257Tuesday, August 29, 2023<project_name><Designer> GRANDTETON_SWB_20230829256 SCREW_HOLE<Reviewer>SizeDoc NumberRevDate: SheetofReviewerDesignerDepartmentProject
Page TitleCCBU D256 257Tuesday, August 29, 2023<project_name><Designer> GRANDTETON_SWB_20230829256 SCREW_HOLE<Reviewer>SizeDoc NumberRevDate: SheetofReviewerDesignerDepartmentProject
Page TitleCCBU D256 257Tuesday, August 29, 2023<project_name><Designer> GRANDTETON_SWB_20230829256 SCREW_HOLE<Reviewer>
H63HOLE_C10D5-6B10_NPBNIH106HOLE_R4-2X5D2B4_IX0-1T_NPM_RBNI
H54HOLE_C10D5-6B10_NPBNI
H136C6-5D3-2NI
H64HOLE_C10D5-6B10_NPBNI H86GNDHOLE_8PINNIH94GNDHOLE_8PINNI
H48HOLE_C10D5-6B10_NPBNI
H113HOLE_R4-2X5D2B4_IX0-1T_NPM_RBNIH143HOLE_C8D4-2B8_NPMNIH137C6-5D3-2NIH126HOLE_R4-2X5D2B4_IX0-1T_NPM_RBNI
H55HOLE_C10D5-6B10_NPBNIH110HOLE_R4-2X5D2B4_IX0-1T_NPM_RBNI H98GNDHOLE_8PINNI
H67HOLE_C10D5-6B10_NPBNIH49HOLE_C10D5-6B10_NPBNI
H130HOLE_R4-2X5D2B4_IX0-1T_NPM_RBNIH102HOLE_R4-2X5D2B4_IX0-1T_NPM_RBNI H138C6-5D3-2NI
H56HOLE_C10D5-6B10_NPBNIH107HOLE_R4-2X5D2B4_IX0-1T_NPM_RBNIH132C6-5D3-2NIH68HOLE_C10D5-6B10_NPBNI H133C6-5D3-2NIH104HOLE_R4-2X5D2B4_IX0-1T_NPM_RBNI
H50HOLE_C10D5-6B10_NPBNI
H139C6-5D3-2NIH112HOLE_R4-2X5D2B4_IX0-1T_NPM_RBNIH120HOLE_R4-2X5D2B4_IX0-1T_NPM_RBNI
H58HOLE_C10D5-6B10_NPBNI
H122HOLE_R4-2X5D2B4_IX0-1T_NPM_RBNIH99GNDHOLE_8PINNI
H69HOLE_C10D5-6B10_NPBNI H87GNDHOLE_8PINNIH79GND_C10D3-4B10NIH51HOLE_C10D5-6B10_NPBNI
H97GNDHOLE_8PINNIH128HOLE_R4-2X5D2B4_IX0-1T_NPM_RBNIH131HOLE_R4-2X5D2B4_IX0-1T_NPM_RBNI
H59HOLE_C10D5-6B10_NPBNI H142HOLE_TOOLINGD125N_T2-0NI
H103HOLE_R4-2X5D2B4_IX0-1T_NPM_RBNIH80GND_C10D3-4B10NIH75HOLE_C5D3-1NNIH70HOLE_C10D5-6B10_NPBNIH52HOLE_C10D5-6B10_NPBNI
H114HOLE_R4-2X5D2B4_IX0-1T_NPM_RBNI
H60HOLE_C10D5-6B10_NPBNIH115HOLE_R4-2X5D2B4_IX0-1T_NPM_RBNIH124HOLE_R4-2X5D2B4_IX0-1T_NPM_RBNIH117HOLE_R4-2X5D2B4_IX0-1T_NPM_RBNI
H71HOLE_C10D5-6B10_NPBNIH53HOLE_C10D5-6B10_NPBNI
H89GNDHOLE_8PINNI
H61HOLE_C10D5-6B10_NPBNI
H119HOLE_R4-2X5D2B4_IX0-1T_NPM_RBNI H134C6-5D3-2NIH84GNDHOLE_8PINNIH109HOLE_R4-2X5D2B4_IX0-1T_NPM_RBNI
H47HOLE_C10D5-6B10_NPBNI
H116HOLE_R4-2X5D2B4_IX0-1T_NPM_RBNI H90GNDHOLE_8PINNIH105HOLE_R4-2X5D2B4_IX0-1T_NPM_RBNI
H62HOLE_C10D5-6B10_NPBNIH81GND_C10D3-4B10NIH135C6-5D3-2NIH95GNDHOLE_8PINNI
H44HOLE_TOOLINGD125N_T2-0NIH46HOLE_C10D5-6B10_NPBNIH42HOLE_TOOLINGD125N_T2-0NI
H100HOLE_R4-2X5D2B4_IX0-1T_NPM_RBNI H78GND_C10D3-4B10NI
H140C6-5D3-2NIH129HOLE_R4-2X5D2B4_IX0-1T_NPM_RBNIH121HOLE_R4-2X5D2B4_IX0-1T_NPM_RBNIH93GNDHOLE_8PINNIH108HOLE_R4-2X5D2B4_IX0-1T_NPM_RBNI H141C6-5D3-2NIH92GNDHOLE_8PINNIH96GNDHOLE_8PINNIH91GNDHOLE_8PINNI
H43HOLE_TOOLINGD125N_T2-0NI
H123HOLE_R4-2X5D2B4_IX0-1T_NPM_RBNIH127HOLE_R4-2X5D2B4_IX0-1T_NPM_RBNIH88GNDHOLE_8PINNIH118HOLE_R4-2X5D2B4_IX0-1T_NPM_RBNIH125HOLE_R4-2X5D2B4_IX0-1T_NPM_RBNIH111HOLE_R4-2X5D2B4_IX0-1T_NPM_RBNIH101HOLE_R4-2X5D2B4_IX0-1T_NPM_RBNI H85GNDHOLE_8PINNI



5
5
4
4
3
3
2
2
1
1
D D
C C
B B
A A
DUMMY SYMBOL
CBS_SYMBOL
MECHANIC_SYMBOL
BIOS-BMCLABELPB-E1 SN LABEL
PICKUP_SYMBOL
QCT_LOGO
HEATSINK
PCB_VENDER_LOGO
QUANTA_LOGO
PICKUP_SYMBOL
BIOS_FLASH
BATTERY_SYMBOL
WEEE
FBPN+VPN BMC_FLASH
STAGE REWORK LABEL BACKPLANE
PVT_CHANGE
SizeDoc NumberRevDate: SheetofReviewerDesignerDepartmentProject
Page TitleCCBU D257 257Tuesday, August 29, 2023<project_name><Designer> GRANDTETON_SWB_20230829257 DUMMY_SYMBOL<Reviewer>SizeDoc NumberRevDate: SheetofReviewerDesignerDepartmentProject
Page TitleCCBU D257 257Tuesday, August 29, 2023<project_name><Designer> GRANDTETON_SWB_20230829257 DUMMY_SYMBOL<Reviewer>SizeDoc NumberRevDate: SheetofReviewerDesignerDepartmentProject
Page TitleCCBU D257 257Tuesday, August 29, 2023<project_name><Designer> GRANDTETON_SWB_20230829257 DUMMY_SYMBOL<Reviewer>
SCREW_1<Part Number>1ME_PART SymbolME9SNLABEL_27X6SCREW_4<Part Number>1DUMMY_SYMBOLPEX0_HSFBF0T002010SCREW_5<Part Number>1SCREW_2<Part Number>1DUMMY_SYMBOLPEX3_HSFBF0T002010SCREW_6<Part Number>1ME_PART SymbolME6PCB_VENDOR_LOGO_15X8NIHANDLE_0<Part Number>1DUMMY_SYMBOLPEX1_HSFBF0T002010SCREW_3<Part Number>1SCREW_7<Part Number>1DUMMY_SYMBOLVR_HS0FBF0T009010ME_PART SymbolME7MACLABEL_17X12DUMMY_SYMBOLPEX2_HSFBF0T002010J61CONN1_10165288-101LFSCR_H1HANDLE_1<Part Number>1DUMMY_SYMBOLVR_HS1FBF0T009010ME_PART SymbolME8REWORKLABEL_39-5X6-5
ME_PART SymbolME10SNLABEL_15X5<Part Number>HS_BP0<Part Number>1ME_PART SymbolME2WEEENI J62CONN1_10165288-101LFSCR_H1ME_PART SymbolME3PB-E1_SMALLNIHS_BP1<Part Number>1 J63CONN1_10165288-101LFSCR_H1HS_BP2<Part Number>1 J64CONN1_10165288-101LFSCR_H1HS_BP3<Part Number>1 SCREW_0<Part Number>1ME_PART SymbolME1QUANTA_LOGO_7X26NI